G04 ================== begin FILE IDENTIFICATION RECORD ==================*
G04 Layout Name:  9127_F0T_Expander_BD_F_v02_0110_1240.brd*
G04 Film Name:    in1*
G04 File Format:  Gerber RS274X*
G04 File Origin:  Cadence Allegro 17.2-S081*
G04 Origin Date:  Wed Jan 11 16:06:14 2023*
G04 *
G04 Layer:  VIA CLASS/IN1*
G04 Layer:  PIN/IN1*
G04 Layer:  ETCH/IN1*
G04 Layer:  PIN/SPECIAL_DRILL*
G04 Layer:  DRAWING FORMAT/TITLE_BLOCK_A*
G04 Layer:  DRAWING FORMAT/TITLE_BLOCK*
G04 Layer:  MANUFACTURING/PHOTOPLOT_OUTLINE*
G04 Layer:  DRAWING FORMAT/TITLE_DATA_IN1*
G04 *
G04 Offset:    (0.00 0.00)*
G04 Mirror:    No*
G04 Mode:      Positive*
G04 Rotation:  0*
G04 FullContactRelief:  No*
G04 UndefLineWidth:     6.00*
G04 ================== end FILE IDENTIFICATION RECORD ====================*
%FSLAX25Y25*MOIN*%
%IR0*IPPOS*OFA0.00000B0.00000*MIA0B0*SFA1.00000B1.00000*%
%ADD17O,.137X.062*%
%ADD10C,.02*%
%ADD21C,.03*%
%ADD12O,.137X.064*%
%ADD16C,.016*%
%ADD19C,.018*%
%ADD14C,.0315*%
%ADD20C,.064*%
%ADD24C,.048*%
%ADD15C,.0282*%
%ADD25C,.085*%
%ADD23C,.07051*%
%ADD22C,.0193*%
%ADD18C,.03568*%
%ADD26O,.044X.071*%
%ADD27O,.044X.087*%
%ADD11C,.256*%
%ADD13C,.394*%
%ADD28C,.01*%
%ADD29C,.015*%
%ADD30C,.006*%
%ADD31C,.0061*%
%ADD32C,.0035*%
%ADD33C,.008*%
%ADD34C,.0045*%
%ADD35C,.0055*%
%ADD36C,.0065*%
%ADD48C,.03004*%
%ADD55C,.03006*%
%ADD50C,.02404*%
%ADD58C,.02604*%
%ADD51C,.02804*%
%ADD40C,.08404*%
%ADD53C,.03824*%
%ADD57C,.02934*%
%ADD41C,.07606*%
%ADD42C,.08408*%
%ADD49C,.03198*%
%ADD46C,.07608*%
%ADD43C,.08409*%
%ADD37O,.1621X.2251*%
%ADD38O,.03604X.07004*%
%ADD52O,.03006X.06406*%
%ADD59C,.16206*%
%ADD39O,.03606X.07006*%
%ADD45C,.17406*%
%ADD44C,.16506*%
%ADD47C,.16804*%
%ADD56C,.37406*%
%ADD54C,.21786*%
G75*
%LPD*%
G75*
G36*
G01X2000Y1212277D02*
X3998D01*
Y970425D01*
G03X5133Y967685I3877J1D01*
G01X15480Y957338D01*
G02X18958Y948943I-8394J-8396D01*
G01Y344836D01*
G02X15480Y336442I-11871J1D01*
G01X5132Y326094D01*
G03X3998Y323355I2742J-2739D01*
G01Y7874D01*
G03X7874Y3998I3876J0D01*
G01X23484D01*
G03X27360Y7874I0J3876D01*
G01Y46654D01*
G02X35295Y54588I7935J-1D01*
G01X64100D01*
X64454Y54234D01*
Y52945D01*
X64100Y52591D01*
X35295D01*
G03X29358Y46654I0J-5937D01*
G01Y7874D01*
G02X23484Y2000I-5874J0D01*
G01X7874D01*
G02X2000Y7874I0J5874D01*
G01Y323354D01*
G02X3720Y327506I5873J-1D01*
G01X14068Y337855D01*
G03X16961Y344836I-6980J6983D01*
G01Y948943D01*
G03X14068Y955925I-9875J-1D01*
G01X3720Y966273D01*
G02X2000Y970426I4154J4153D01*
G01Y1212277D01*
G37*
G36*
G01X1081725Y1645992D02*
X1833071D01*
G02X1838945Y1640118I0J-5874D01*
G01Y970426D01*
G02X1837225Y966273I-5874J0D01*
G01X1826876Y955925D01*
G03X1823984Y948944I6982J-6982D01*
G01Y344836D01*
G03X1826876Y337855I9873J0D01*
G01X1837225Y327506D01*
G02X1838945Y323354I-4153J-4153D01*
G01Y7874D01*
G02X1833071Y2000I-5874J0D01*
G01X1756949D01*
G02X1751075Y7874I0J5874D01*
G01Y46654D01*
G03X1749600Y50571I-5938J0D01*
G01Y50666D01*
X1749606Y50672D01*
X1751979D01*
G02X1753072Y46654I-6841J-4019D01*
G01Y7874D01*
G03X1756947Y3998I3876J0D01*
G01X1833071D01*
G03X1836948Y7874I0J3877D01*
G01Y323354D01*
G03X1835813Y326094I-3876J0D01*
G01X1825464Y336443D01*
G02X1821987Y344836I8393J8394D01*
G01X1821986D01*
Y948944D01*
X1821987D01*
G02X1825464Y957337I11871J-1D01*
G01X1835813Y967685D01*
G03X1836948Y970426I-2742J2741D01*
G01Y1640118D01*
G03X1833073Y1643994I-3876J0D01*
G01X1633526D01*
Y1644873D01*
X1578560D01*
Y1644608D01*
X1578346D01*
X1577732Y1643994D01*
X1285912D01*
Y1644677D01*
X1232543D01*
Y1644165D01*
X1232372Y1643994D01*
X1081724D01*
G03X1078854Y1642722I1J-3877D01*
G02X1070058Y1638822I-8797J7971D01*
G01X800966D01*
G02X792169Y1642722I0J11872D01*
G03X789299Y1643994I-2871J-2603D01*
G01X609628D01*
X609011Y1644611D01*
X555245D01*
X554628Y1643994D01*
X262776D01*
Y1644377D01*
X208818D01*
Y1643994D01*
X7874D01*
G03X3998Y1640118I0J-3876D01*
G01Y970425D01*
G03X5133Y967685I3877J1D01*
G01X15480Y957338D01*
G02X18958Y948943I-8394J-8396D01*
G01Y344836D01*
G02X15480Y336442I-11871J1D01*
G01X5132Y326094D01*
G03X3998Y323355I2742J-2739D01*
G01Y7874D01*
G03X7874Y3998I3876J0D01*
G01X23484D01*
G03X27360Y7874I0J3876D01*
G01Y46654D01*
G02X35295Y54588I7935J-1D01*
G01X64100D01*
X64454Y54234D01*
Y52945D01*
X64100Y52591D01*
X35295D01*
G03X29358Y46654I0J-5937D01*
G01Y7874D01*
G02X23484Y2000I-5874J0D01*
G01X7874D01*
G02X2000Y7874I0J5874D01*
G01Y323354D01*
G02X3720Y327506I5873J-1D01*
G01X14068Y337855D01*
G03X16961Y344836I-6980J6983D01*
G01Y948943D01*
G03X14068Y955925I-9875J-1D01*
G01X3720Y966273D01*
G02X2000Y970426I4154J4153D01*
G01Y1640118D01*
G02X7874Y1645992I5874J0D01*
G01X789298D01*
G02X793649Y1644063I-1J-5873D01*
G03X800966Y1640819I7317J6631D01*
G01X1070058D01*
G03X1077374Y1644063I-1J9873D01*
G02X1081725Y1645992I4352J-3945D01*
G37*
G36*
G01X1702190Y336835D02*
G02X1702015Y336701I-321J238D01*
G01X1702013D01*
G02X1701825Y336677I-143J374D01*
G02X1701809Y336680I29J198D01*
G02X1701778Y336687I72J393D01*
G02X1701700Y336735I63J190D01*
G01X1692290Y346145D01*
G02X1692305Y346254I198J28D01*
G01X1692360Y346360D01*
G02X1692532Y346458I172J-102D01*
G01X1692534D01*
X1692547Y346457D01*
G03X1692669Y346453I112J1559D01*
G01X1692676D01*
G03X1691114Y348015I0J1562D01*
G03X1691285Y347307I1562J3D01*
G01X1691290Y347297D01*
G02X1691299Y347273I-183J-82D01*
G01Y347271D01*
G02X1691307Y347199I-191J-58D01*
G01Y347198D01*
X1691306Y347188D01*
G02X1691302Y347164I-199J21D01*
G01X1691296Y347144D01*
G02X1691276Y347103I-189J67D01*
G01X1691222Y347028D01*
X1691209Y347010D01*
X1691207Y347007D01*
X1691204Y347003D01*
X1691176Y346963D01*
X1691110Y346869D01*
X1691097Y346851D01*
Y346850D01*
X1691078Y346833D01*
G02X1691040Y346806I-134J148D01*
G01X1690944Y346819D01*
G03X1690814Y346833I-312J-2285D01*
G03X1690640Y346840I-180J-2300D01*
G01X1689008D01*
G02X1688917Y346862I0J200D01*
G02X1688867Y346898I90J178D01*
G01X1688785Y346980D01*
G02X1688727Y347121I142J141D01*
G01Y347143D01*
G02X1688740Y347213I200J-1D01*
G01X1688750Y347232D01*
G03X1688926Y347937I-1326J705D01*
G03X1687424Y349439I-1502J0D01*
G01X1687422D01*
G03X1686757Y349283I1J-1501D01*
G03X1686709Y349258I670J-1345D01*
G01X1686679Y349242D01*
G02X1686677Y349241I-90J177D01*
G01X1686670Y349237D01*
G02X1686551Y349215I-94J176D01*
G01X1686550D01*
X1681528Y354237D01*
G03X1679898Y354912I-1630J-1631D01*
G01X1676036D01*
G02X1675922Y354947I-1J200D01*
G02X1675906Y354960I118J162D01*
G01X1675526Y355340D01*
X1675355Y355512D01*
G03X1673723Y356188I-1632J-1632D01*
G03X1671668Y354929I0J-2307D01*
G01Y354928D01*
X1671637Y354868D01*
X1671630Y354855D01*
X1671618Y354846D01*
X1671494Y354813D01*
X1671492D01*
X1671431Y354797D01*
G02X1671343Y354795I-48J194D01*
G01X1671300Y354803D01*
X1671263Y354830D01*
G03X1670323Y355135I-940J-1296D01*
G03X1668787Y353985I0J-1601D01*
G01X1668775Y353948D01*
X1668646Y353819D01*
G02X1668558Y353811I-62J190D01*
G01X1668327Y354042D01*
X1668302Y354084D01*
X1668295Y354107D01*
G03X1667036Y355153I-1435J-446D01*
G01X1666979Y355159D01*
G03X1666860Y355164I-123J-1498D01*
G03X1665498Y354299I0J-1505D01*
G01X1665490Y354282D01*
G02X1665435Y354221I-173J101D01*
G01X1665414Y354206D01*
X1665390Y354197D01*
G02X1665343Y354185I-73J186D01*
G01X1665211Y354169D01*
X1665209D01*
X1665137Y354160D01*
G02X1665111Y354158I-28J198D01*
G01X1664970D01*
G02X1664928Y354162I-2J200D01*
G02X1664885Y354177I44J195D01*
G01X1664846Y354196D01*
X1664817Y354232D01*
G03X1663651Y354786I-1166J-949D01*
G01X1663649D01*
G03X1663579Y354784I8J-1503D01*
G01X1663525Y354780D01*
G03X1662158Y353459I125J-1497D01*
G01X1662154Y353421D01*
G03X1662147Y353284I1496J-145D01*
G01Y353282D01*
G03X1663204Y351848I1503J1D01*
G01X1663205D01*
G02X1663287Y351798I-60J-191D01*
G01X1668672Y346413D01*
G02X1668728Y346300I-142J-141D01*
G02X1668333Y345844I-396J-56D01*
G01X1667202D01*
G02X1667134Y345856I0J200D01*
G01X1667101Y345868D01*
X1667074Y345890D01*
X1667063Y345899D01*
X1659408Y353554D01*
X1659398Y353569D01*
G03X1659135Y353883I-1893J-1318D01*
G01X1642562Y370456D01*
G02X1642526Y370506I142J140D01*
G02X1642504Y370597I178J91D01*
G01Y374690D01*
G03X1641852Y376297I-2306J0D01*
G01X1641742Y376411D01*
G02Y376465I198J27D01*
G01X1643246Y377968D01*
G03X1643922Y379599I-1631J1632D01*
G01Y379656D01*
X1643921Y379679D01*
G03X1641615Y381906I-2305J-79D01*
G03X1639984Y381231I-1J-2306D01*
G01X1639436Y380683D01*
G02X1639341Y380691I-31J198D01*
G01X1639304Y380704D01*
X1639249Y380733D01*
X1639237Y380742D01*
G03X1638375Y381038I-896J-1206D01*
G01X1638373D01*
X1638340Y381039D01*
G03X1636905Y379982I0J-1503D01*
G01Y379981D01*
G02X1636855Y379899I-191J60D01*
G01X1627155Y370199D01*
G03X1626772Y369275I923J-924D01*
G01Y352797D01*
G02X1626743Y352766I-160J120D01*
G01X1626723Y352749D01*
X1626617Y352657D01*
G02X1626615Y352656I-88J173D01*
G01X1626505Y352561D01*
G02X1626386Y352521I-120J160D01*
G01X1626359D01*
X1626346Y352523D01*
G03X1626149Y352535I-190J-1491D01*
G01X1626146D01*
G03X1624645Y351033I1J-1502D01*
G01Y351030D01*
G03X1624817Y350331I1504J-1D01*
G02X1624840Y350238I-177J-93D01*
G01Y263456D01*
G03X1625223Y262532I1306J0D01*
G01X1629799Y257956D01*
G03X1630721Y257574I923J924D01*
G01X1633228D01*
X1633239Y257568D01*
G03X1634703I732J1313D01*
G01X1634714Y257574D01*
X1646255D01*
G02X1646297Y257570I2J-200D01*
G02X1646396Y257516I-42J-196D01*
G01X1652494Y251417D01*
G03X1653418Y251034I924J923D01*
G01X1653738D01*
G02X1653874Y250980I-1J-200D01*
G01X1653947Y250908D01*
G03X1654411Y250613I895J896D01*
G01X1654416D01*
X1654481Y250588D01*
X1654489Y250585D01*
X1654503Y250581D01*
G03X1654527Y250576I53J194D01*
G01X1654530D01*
X1654548Y250573D01*
X1654553Y250572D01*
X1654556Y250571D01*
X1654558D01*
G03X1654706Y250545I293J1232D01*
G01X1654707D01*
X1654717Y250544D01*
G03X1654843Y250538I123J1260D01*
G01X1663256D01*
G02X1663282Y250536I-2J-200D01*
G01X1663284D01*
G02X1663419Y250455I-27J-198D01*
G02X1663441Y250414I-164J-114D01*
G01X1663487Y250303D01*
Y250301D01*
X1663512Y250240D01*
Y250239D01*
G03X1663529Y250206I186J75D01*
G01X1663534Y250198D01*
G02X1663557Y250135I-174J-99D01*
G01X1663558Y250129D01*
X1663574Y250027D01*
G02X1663561Y249915I-197J-34D01*
G01X1663532Y249848D01*
X1663505Y249821D01*
G03X1663072Y248800I1069J-1056D01*
G01Y248742D01*
G03X1664518Y247264I1502J23D01*
G01X1664519D01*
G03X1664574Y247263I55J1501D01*
G01X1664576D01*
G03X1665510Y247590I-1J1501D01*
G01X1665536Y247610D01*
X1665580Y247625D01*
G02X1665633Y247633I56J-192D01*
G01X1665719D01*
G03X1665802Y247651I0J200D01*
G01X1665856Y247676D01*
G02X1665934Y247695I85J-181D01*
G02X1665968Y247693I5J-200D01*
G02X1666072Y247645I-28J-198D01*
G01X1666073Y247644D01*
G03X1666415Y247415I999J1123D01*
G03X1666473Y247388I663J1348D01*
G01X1666491Y247380D01*
G03X1667069Y247263I581J1385D01*
G01X1667095D01*
G03X1667555Y247342I-21J1502D01*
G03X1668008Y247589I-482J1423D01*
G01X1668009Y247590D01*
X1668021Y247600D01*
G02X1668127Y247633I110J-167D01*
G01X1668219D01*
G03X1668302Y247651I0J200D01*
G01X1668356Y247676D01*
G02X1668434Y247695I85J-181D01*
G02X1668468Y247693I5J-200D01*
G02X1668572Y247645I-28J-198D01*
G01X1668573Y247644D01*
G03X1669572Y247263I1000J1122D01*
G01X1669574D01*
G03X1671076Y248765I0J1502D01*
G03X1670643Y249820I-1502J0D01*
G01X1670642Y249821D01*
X1670617Y249847D01*
X1670593Y249900D01*
X1670585Y249918D01*
G02X1670580Y249933I187J71D01*
G01X1670566Y250002D01*
G02X1670575Y250088I199J23D01*
G01X1670661Y250301D01*
Y250303D01*
X1670706Y250413D01*
G02X1670840Y250531I185J-75D01*
G01X1670872Y250540D01*
X1670905Y250538D01*
X1675444D01*
G03X1675552Y250570I0J200D01*
G01X1675586Y250592D01*
X1675710Y250613D01*
G02X1675765I28J-198D01*
G01X1675992Y250386D01*
G02X1676032Y250267I-160J-120D01*
G01Y228906D01*
G02X1676031Y228886I-200J0D01*
G02X1675976Y228767I-199J20D01*
G01X1674514Y227306D01*
G03X1674132Y226384I924J-923D01*
G01Y222748D01*
G02X1674041Y222680I-160J120D01*
G01X1673870Y222617D01*
X1673688Y222550D01*
G02X1673658Y222542I-66J189D01*
G02X1673567Y222545I-39J196D01*
G01X1673538Y222553D01*
X1673486Y222586D01*
X1673466Y222610D01*
G03X1672317Y223144I-1149J-969D01*
G03X1670815Y221642I0J-1502D01*
G03X1672141Y220150I1502J0D01*
G01X1672199Y220144D01*
G03X1672317Y220139I123J1498D01*
G03X1673457Y220663I-1J1503D01*
G01X1673462Y220669D01*
X1673479Y220686D01*
G02X1673604Y220744I142J-141D01*
G02X1673689Y220732I15J-199D01*
G01X1673731Y220717D01*
X1674040Y220604D01*
G02X1674082Y220583I-68J-188D01*
G02X1674132Y220536I-110J-167D01*
G01Y216980D01*
G03X1674514Y216058I1306J1D01*
G01X1682089Y208483D01*
X1682114Y208441D01*
X1682121Y208418D01*
G03X1683556Y207362I1435J447D01*
G03X1685058Y208864I0J1502D01*
G01X1685059D01*
G03X1684002Y210299I-1503J0D01*
G01X1684001D01*
G02X1683919Y210349I60J191D01*
G01X1681595Y212673D01*
X1676802Y217465D01*
G02X1676749Y217561I142J141D01*
G02X1676744Y217606I195J44D01*
G01Y222896D01*
G02X1676793Y222942I159J-121D01*
G01X1677047Y223112D01*
X1677056Y223118D01*
G02X1677154Y223146I102J-172D01*
G01X1677256D01*
X1677290Y223133D01*
G03X1677824Y223034I536J1403D01*
G01X1677826D01*
G03X1679280Y224160I0J1502D01*
G01X1679287Y224187D01*
X1679300Y224209D01*
G02X1679330Y224248I172J-101D01*
G01X1679964Y224882D01*
G03X1680334Y225775I-897J895D01*
G01Y227085D01*
G02X1680439Y227260I200J-1D01*
G01X1680451Y227266D01*
G03X1681259Y228184I-626J1365D01*
G01Y228186D01*
G02X1681308Y228266I190J-62D01*
G01X1683562Y230520D01*
G03X1683944Y231442I-924J923D01*
G01Y246878D01*
G02X1684007Y246933I160J-120D01*
G01X1684303Y247098D01*
G02X1684335Y247112I96J-176D01*
G02X1684452Y247116I65J-189D01*
G01X1684455Y247115D01*
X1684488Y247106D01*
X1684489Y247105D01*
X1684515Y247098D01*
X1684538Y247084D01*
G03X1685312Y246869I774J1287D01*
G01X1685348D01*
G03X1686815Y248371I-35J1502D01*
G03X1685313Y249873I-1502J0D01*
G01X1685312D01*
G03X1684538Y249658I0J-1502D01*
G01X1684529Y249652D01*
X1684515Y249644D01*
X1684450Y249625D01*
G02X1684312Y249641I-47J194D01*
G01X1684261Y249669D01*
X1684007Y249809D01*
G02X1683944Y249864I97J175D01*
G01Y278884D01*
G02X1683963Y278906I160J-119D01*
G01X1686046Y280989D01*
G02X1686147Y281042I140J-143D01*
G01X1686149D01*
G02X1686186Y281046I40J-196D01*
G01X1696928D01*
G02X1696960Y281043I-3J-200D01*
G01X1696962D01*
G02X1697068Y280989I-34J-197D01*
G01X1710870Y267187D01*
G02X1710923Y267086I-143J-140D01*
G01Y267084D01*
G02X1710927Y267047I-196J-40D01*
G01Y263494D01*
Y263492D01*
G03X1710934Y263438I200J-1D01*
G01X1710942Y263412D01*
Y248568D01*
X1710940Y248563D01*
X1710901Y248534D01*
X1710900D01*
X1710714Y248394D01*
X1710641Y248339D01*
G02X1710635Y248335I-114J165D01*
G01X1710613Y248323D01*
G02X1710512Y248303I-88J180D01*
G01X1710483Y248307D01*
X1710465Y248312D01*
G03X1710030Y248376I-434J-1438D01*
G01X1710028D01*
G03X1708526Y246874I0J-1502D01*
G03X1710026Y245372I1502J0D01*
G01X1710034D01*
G03X1710599Y245485I-7J1502D01*
G01X1710617Y245492D01*
X1710656Y245500D01*
G02X1710778Y245487I41J-196D01*
G01X1710779Y245486D01*
X1710796Y245478D01*
G02X1710870Y245406I-98J-175D01*
G02X1710881Y245382I-176J-95D01*
G01X1710926Y245277D01*
G02X1710941Y245219I-184J-79D01*
G02X1710942Y245199I-199J-20D01*
G01Y245040D01*
X1710931Y245019D01*
G03X1710825Y244777I1317J-721D01*
G03X1710746Y244307I1423J-481D01*
G01Y244280D01*
G03X1712235Y242795I1502J17D01*
G01X1712271D01*
G03X1712954Y242967I-15J1503D01*
G02X1713047Y242990I93J-177D01*
G01X1713628D01*
G02X1713666Y242986I-2J-200D01*
G02X1713768Y242933I-37J-196D01*
G01X1715687Y241014D01*
G02X1715740Y240912I-143J-139D01*
G02X1715744Y240874I-196J-40D01*
G01Y231707D01*
G02X1715646Y231535I-200J0D01*
G01X1715478Y231435D01*
G02X1715331Y231412I-102J172D01*
G01X1715270Y231426D01*
X1715246Y231439D01*
G03X1714535Y231619I-713J-1322D01*
G01X1714531D01*
G03Y228615I0J-1502D01*
G01X1714535D01*
G03X1715247Y228795I-1J1503D01*
G01X1715271Y228808D01*
X1715337Y228823D01*
G02X1715462Y228806I37J-196D01*
G01X1715645Y228698D01*
G02X1715744Y228526I-101J-173D01*
G01Y216176D01*
G02X1715639Y216001I-200J1D01*
G01X1715619Y215993D01*
G02X1715503Y215981I-78J184D01*
G01X1715477Y215986D01*
X1715425Y216014D01*
X1702412Y229027D01*
X1702387Y229069D01*
X1702380Y229092D01*
G03X1700945Y230148I-1435J-447D01*
G03X1699443Y228646I0J-1502D01*
G01X1699442D01*
G03X1700499Y227211I1503J0D01*
G01X1700500D01*
G02X1700582Y227161I-60J-191D01*
G01X1714277Y213466D01*
G02X1714330Y213364I-143J-139D01*
G02X1714334Y213326I-196J-40D01*
G01Y181702D01*
G02X1714275Y181560I-200J0D01*
G01X1691450Y158734D01*
G02X1691374Y158687I-141J142D01*
G02X1691309Y158676I-65J189D01*
G01X1680185D01*
X1680168Y158685D01*
G03X1679442Y158872I-726J-1317D01*
G01X1679440D01*
G03Y155868I0J-1502D01*
G01X1679441D01*
G03X1680172Y156058I-1J1504D01*
G01X1680183Y156064D01*
X1690291D01*
G02X1690471Y155951I0J-200D01*
G01X1690476Y155939D01*
G02X1690487Y155821I-185J-77D01*
G01X1690482Y155795D01*
X1690455Y155745D01*
X1677322Y142612D01*
G02X1677272Y142576I-140J142D01*
G02X1677181Y142554I-91J178D01*
G01X1673378D01*
G02X1673340Y142592I121J159D01*
G01X1673217Y142763D01*
X1673152Y142854D01*
G02X1673119Y142960I167J110D01*
G01Y143039D01*
X1673128Y143069D01*
G03X1673197Y143518I-1433J450D01*
G03X1671695Y145020I-1502J0D01*
G03X1670193Y143529I0J-1502D01*
G01Y143515D01*
G03X1670262Y143066I1502J1D01*
G01X1670265Y143056D01*
X1670271Y143037D01*
X1670277Y142986D01*
G02X1670246Y142864I-199J-14D01*
G01X1670171Y142759D01*
X1670049Y142590D01*
G02X1670012Y142554I-157J124D01*
G01X1668003D01*
G02X1667910Y142577I0J200D01*
G03X1667211Y142749I-698J-1332D01*
G01X1667208D01*
G03Y139745I0J-1502D01*
G01X1667212D01*
G03X1667910Y139917I0J1504D01*
G02X1668003Y139940I93J-177D01*
G01X1676164D01*
G02X1676339Y139835I-1J-200D01*
G01X1676347Y139815D01*
G02X1676359Y139699I-184J-78D01*
G01X1676354Y139673D01*
X1676326Y139621D01*
X1667180Y130475D01*
G03X1666798Y129553I924J-923D01*
G01Y116957D01*
G03X1667180Y116035I1306J1D01*
G01X1669638Y113578D01*
G02X1669694Y113466I-142J-141D01*
G02X1669696Y113437I-198J-28D01*
G01Y112827D01*
X1669687Y112810D01*
G03X1669576Y112555I1316J-724D01*
G03X1669564Y112517I1426J-471D01*
G01X1669553Y112482D01*
X1669290Y112219D01*
X1668753Y111681D01*
G02X1668632Y111627I-137J145D01*
G02X1668615Y111626I-20J199D01*
G01X1657185D01*
G03X1656263Y111244I1J-1306D01*
G01X1653995Y108975D01*
G02X1653879Y108919I-140J143D01*
G02X1653855Y108918I-20J199D01*
G01X1649748D01*
G03X1648826Y108536I1J-1306D01*
G01X1644986Y104696D01*
G02X1644825Y104756I56J396D01*
G02X1644642Y105091I217J336D01*
G01Y107649D01*
G03X1641038I-1802J0D01*
G01Y105267D01*
X1641037Y104249D01*
G03X1642250Y102545I1803J0D01*
G01X1642268Y102539D01*
G02X1642378Y102408I-84J-182D01*
G01X1642382Y102394D01*
X1642410Y102269D01*
Y102267D01*
X1642413Y102254D01*
G02X1642359Y102069I-195J-43D01*
G01X1640218Y99927D01*
G02X1640079Y99868I-142J141D01*
G01X1633878D01*
X1633865D01*
G02X1633738Y99925I13J200D01*
G01X1633447Y100217D01*
X1633322Y100342D01*
X1633297Y100384D01*
X1633290Y100407D01*
G03X1631855Y101463I-1435J-447D01*
G03X1630353Y99961I0J-1502D01*
G01X1630352D01*
G03X1631409Y98526I1503J0D01*
G01X1631410D01*
G02X1631492Y98476I-60J-191D01*
G01X1631659Y98309D01*
G02Y98252I-198J-29D01*
G01X1630274Y96867D01*
G03X1629631Y95624I1631J-1631D01*
G01X1629615Y95527D01*
G02X1629537Y95480I-140J143D01*
G01X1629505Y95470D01*
X1629342Y95419D01*
X1629192Y95372D01*
G02X1629110Y95367I-53J193D01*
G01X1628317Y96160D01*
G03X1627395Y96542I-923J-924D01*
G01X1622717D01*
X1622700Y96551D01*
G03X1621974Y96738I-726J-1317D01*
G01X1621972D01*
G03Y93734I0J-1502D01*
G01X1621973D01*
G03X1622704Y93924I-1J1504D01*
G01X1622715Y93930D01*
X1626769D01*
X1626782D01*
G02X1626909Y93873I-13J-200D01*
G01X1627224Y93557D01*
X1627378Y93403D01*
G02X1627379Y93349I-198J-31D01*
G02X1627371Y93314I-198J27D01*
G01X1627334Y93203D01*
Y93201D01*
X1627250Y92928D01*
X1627221Y92902D01*
X1627124Y92885D01*
G03X1625379Y91437I410J-2270D01*
G01X1625346Y91351D01*
G02X1625277Y91322I-111J166D01*
G01X1625083Y91281D01*
X1625081D01*
X1624940Y91251D01*
G02X1624884Y91252I-24J199D01*
G01X1623854Y92282D01*
G03X1622222Y92958I-1632J-1632D01*
G03X1619914Y90650I0J-2308D01*
G03X1620590Y89018I2308J0D01*
G01X1622530Y87078D01*
G03X1624162Y86402I1632J1632D01*
G03X1624246Y86404I-13J2308D01*
G01X1639006D01*
X1639008D01*
G02X1639133Y86359I-1J-200D01*
G02X1639167Y86323I-127J-154D01*
G01X1639299Y86145D01*
G02X1639335Y86062I-160J-119D01*
G01X1639344Y86016D01*
X1639330Y85969D01*
G03X1639267Y85539I1439J-430D01*
G03X1639673Y84512I1502J0D01*
G01X1639701Y84482D01*
X1639714Y84448D01*
G02X1639717Y84441I-182J-82D01*
G02X1639727Y84377I-190J-63D01*
G01Y84101D01*
G02X1639717Y84037I-200J-1D01*
G02X1639714Y84030I-185J75D01*
G01X1639701Y83996D01*
X1639673Y83966D01*
G03Y81912I1096J-1027D01*
G01X1639701Y81882D01*
X1639714Y81848D01*
G02X1639717Y81841I-182J-82D01*
G02X1639727Y81777I-190J-63D01*
G01Y81501D01*
G02X1639717Y81437I-200J-1D01*
G02X1639714Y81430I-185J75D01*
G01X1639701Y81396D01*
X1639673Y81366D01*
G03Y79312I1096J-1027D01*
G01X1639701Y79282D01*
X1639714Y79248D01*
G02X1639717Y79241I-182J-82D01*
G02X1639727Y79177I-190J-63D01*
G01Y78901D01*
G02X1639717Y78837I-200J-1D01*
G02X1639714Y78830I-185J75D01*
G01X1639701Y78796D01*
X1639673Y78766D01*
G03Y76712I1096J-1027D01*
G01X1639701Y76682D01*
X1639714Y76648D01*
G02X1639717Y76641I-182J-82D01*
G02X1639727Y76577I-190J-63D01*
G01Y76301D01*
G02X1639717Y76237I-200J-1D01*
G02X1639714Y76230I-185J75D01*
G01X1639701Y76196D01*
X1639673Y76166D01*
G03X1639267Y75139I1096J-1027D01*
G03X1642271I1502J0D01*
G03X1641865Y76166I-1502J0D01*
G01X1641837Y76196D01*
X1641824Y76230D01*
G02X1641821Y76237I182J82D01*
G02X1641811Y76301I190J63D01*
G01Y76577D01*
G02X1641821Y76641I200J1D01*
G02X1641824Y76648I185J-75D01*
G01X1641837Y76682D01*
X1641865Y76712D01*
G03Y78766I-1096J1027D01*
G01X1641837Y78796D01*
X1641824Y78830D01*
G02X1641821Y78837I182J82D01*
G02X1641811Y78901I190J63D01*
G01Y79177D01*
G02X1641821Y79241I200J1D01*
G02X1641824Y79248I185J-75D01*
G01X1641837Y79282D01*
X1641865Y79312D01*
G03Y81366I-1096J1027D01*
G01X1641837Y81396D01*
X1641824Y81430D01*
G02X1641821Y81437I182J82D01*
G02X1641811Y81501I190J63D01*
G01Y81777D01*
G02X1641821Y81841I200J1D01*
G02X1641824Y81848I185J-75D01*
G01X1641837Y81882D01*
X1641865Y81912D01*
G03Y83966I-1096J1027D01*
G01X1641837Y83996D01*
X1641824Y84030D01*
G02X1641821Y84037I182J82D01*
G02X1641811Y84101I190J63D01*
G01Y84377D01*
G02X1641821Y84441I200J1D01*
G02X1641824Y84448I185J-75D01*
G01X1641837Y84482D01*
X1641865Y84512D01*
G03X1642271Y85539I-1096J1027D01*
G03X1642208Y85969I-1502J0D01*
G01Y85970D01*
G02X1642203Y86063I192J57D01*
G01X1642211Y86108D01*
X1642372Y86324D01*
G02X1642394Y86348I158J-122D01*
G02X1642530Y86404I139J-144D01*
G01X1659656D01*
G02X1659770Y86369I1J-200D01*
G02X1659786Y86356I-118J-162D01*
G01X1661137Y85005D01*
G02X1661139Y84976I-198J-28D01*
G01Y84913D01*
X1661127Y84867D01*
X1661110Y84834D01*
G03X1660940Y84143I1332J-694D01*
G01Y84110D01*
G03X1662442Y82638I1502J30D01*
G01X1662458D01*
G03X1662493Y82639I-25J1502D01*
G01X1662516D01*
G02X1662636Y82599I0J-200D01*
G01X1662648Y82590D01*
X1662862Y82384D01*
G02X1662884Y82359I-139J-144D01*
G01Y78752D01*
X1662883Y76587D01*
G03X1663673Y74849I2307J0D01*
G01X1663716Y74812D01*
X1663724Y74795D01*
G02X1663742Y74717I-182J-83D01*
G01X1663748Y74497D01*
Y74494D01*
X1663750Y74437D01*
X1663559Y74246D01*
G03X1662884Y72615I1631J-1630D01*
G01X1662883Y72567D01*
G03X1665190Y70308I2307J49D01*
G01X1665226D01*
G03X1666083Y70488I-37J2307D01*
G03X1666822Y70984I-892J2127D01*
G01X1669060Y73222D01*
G03X1669736Y74853I-1631J1632D01*
G01Y84548D01*
G02X1669806Y84606I159J-121D01*
G01X1670089Y84726D01*
X1670091D01*
X1670160Y84754D01*
G02X1670266Y84767I76J-185D01*
G01X1672586Y82447D01*
G02X1672588Y82400I-197J-32D01*
G01X1672533Y82055D01*
G02X1672499Y81980I-196J43D01*
G01X1672479Y81953D01*
X1672457Y81942D01*
G03X1671599Y80581I650J-1361D01*
G03X1674617I1509J0D01*
G01Y80584D01*
G03X1674534Y81076I-1509J-2D01*
G01X1674521Y81114D01*
X1674520Y81121D01*
G02X1674552Y81247I200J16D01*
G01X1674557Y81254D01*
X1674744Y81516D01*
G02X1674747Y81520I162J-118D01*
G01X1680933D01*
G03X1682563Y82195I0J2306D01*
G01X1684783Y84415D01*
G03X1685458Y86045I-1631J1630D01*
G01Y86046D01*
G03X1683152Y88352I-2306J0D01*
G01X1683151D01*
G03X1681521Y87677I0J-2306D01*
G01X1681243Y87398D01*
G02X1681202Y87396I-30J198D01*
G01X1681082Y87497D01*
G03X1679598Y88038I-1484J-1765D01*
G01X1678977D01*
G02X1678941Y88073I120J160D01*
G01X1678868Y88164D01*
X1678738Y88325D01*
G02X1678728Y88341I165J114D01*
G02X1678710Y88388I176J94D01*
G01X1678697Y88438D01*
X1678699Y88445D01*
X1678707Y88485D01*
G03X1678740Y88791I-1469J313D01*
G03Y88793I-1502J1D01*
G01Y88816D01*
G03X1677414Y90293I-1502J-15D01*
G01X1677358Y90299D01*
G03X1677238Y90304I-123J-1498D01*
G03X1676228Y89914I0J-1503D01*
G01X1676226Y89912D01*
G02X1676126Y89864I-133J149D01*
G01X1676098Y89860D01*
X1676070Y89863D01*
G02X1676014Y89879I26J198D01*
G01X1675946Y89909D01*
X1675675Y90029D01*
G02X1675600Y90090I85J181D01*
G01Y102105D01*
G02X1675684Y102170I160J-120D01*
G01X1675716Y102180D01*
G03X1676456Y102672I-425J1441D01*
G03X1676725Y103173I-1165J948D01*
G02X1676727Y103177I178J-86D01*
G01X1676728Y103181D01*
G02X1676776Y103258I189J-65D01*
G01X1680479Y106961D01*
G03X1680862Y107885I-923J924D01*
G01Y118847D01*
G03X1680479Y119771I-1306J0D01*
G01X1676708Y123541D01*
G02X1676653Y123648I142J141D01*
G02X1676650Y123682I197J35D01*
G01Y125927D01*
G02X1676690Y126047I200J0D01*
G01X1699331Y148689D01*
G02X1699404Y148685I26J-198D01*
G01X1699523Y148649D01*
X1699525D01*
X1699712Y148591D01*
G02X1699745Y148575I-70J-187D01*
G02X1699786Y148543I-102J-173D01*
G01X1699824Y148500D01*
X1699826Y148498D01*
X1699858Y148463D01*
G02X1699883Y148425I-154J-128D01*
G01X1699896Y148400D01*
X1699900Y148384D01*
X1699902Y148374D01*
G03X1701365Y147215I1463J344D01*
G03X1702867Y148717I0J1502D01*
G03X1701708Y150180I-1503J0D01*
G01X1701707D01*
X1701679Y150187D01*
X1701638Y150208D01*
X1701611Y150232D01*
X1701610Y150233D01*
X1701584Y150256D01*
X1701582Y150258D01*
X1701539Y150296D01*
G02X1701507Y150337I141J143D01*
G02X1701491Y150370I171J103D01*
G01X1701433Y150557D01*
Y150559D01*
X1701397Y150678D01*
G02X1701393Y150751I194J47D01*
G01X1705641Y154999D01*
G02X1705742Y155044I129J-153D01*
G02X1706080Y154932I56J-396D01*
G02X1706082Y154930I-140J-142D01*
G02X1706122Y154882I-286J-279D01*
G02X1706158Y154768I-164J-114D01*
G01Y144532D01*
X1706147Y144487D01*
X1706136Y144466D01*
G03X1706115Y144425I1327J-706D01*
G01X1706097Y144386D01*
G03X1706030Y144209I1370J-620D01*
G01Y144206D01*
G02X1705981Y144126I-190J62D01*
G01X1700113Y138258D01*
G03X1699730Y137334I923J-924D01*
G01Y127601D01*
G02X1699713Y127581I-161J119D01*
G01X1699506Y127411D01*
X1699462Y127375D01*
G02X1699413Y127345I-128J154D01*
G01X1699330Y127363D01*
G03X1698851Y127414I-482J-2256D01*
G03X1696544Y125107I0J-2307D01*
G01Y121166D01*
G02X1696500Y121123I-160J120D01*
G01X1696363Y121039D01*
X1696215Y120948D01*
G02X1696174Y120929I-104J171D01*
G01X1696165Y120926D01*
G02X1696020Y120940I-55J192D01*
G01X1696019D01*
X1695977Y120961D01*
G03X1695318Y121112I-660J-1367D01*
G01X1695317D01*
G03X1693799Y119594I0J-1518D01*
G03X1694375Y118404I1517J0D01*
G02X1694431Y118335I-124J-157D01*
G01X1694449Y118298D01*
X1694450Y118296D01*
G02X1694471Y118207I-179J-89D01*
G01Y117983D01*
G02X1694453Y117900I-200J0D01*
G01X1694440Y117873D01*
Y117871D01*
X1694413Y117817D01*
G02X1694380Y117772I-176J95D01*
G01X1694361Y117753D01*
X1694354Y117747D01*
G03X1693815Y116594I964J-1153D01*
G03X1695317Y115092I1502J0D01*
G03X1696394Y115547I0J1502D01*
G01X1696421Y115575D01*
X1696561Y115637D01*
X1696610Y115635D01*
X1696701Y115630D01*
G02X1696795Y115602I-8J-200D01*
G01X1696815Y115590D01*
X1696849Y115556D01*
X1696863Y115532D01*
G03X1697220Y115071I1988J1170D01*
G01X1702401Y109891D01*
X1706830Y105461D01*
G02X1706843Y105445I-149J-134D01*
G02X1706878Y105331I-165J-113D01*
G01Y95111D01*
G03X1711490I2306J0D01*
G01Y105214D01*
G02X1711530Y105254I160J-120D01*
G01X1712579D01*
G02X1712636Y105246I1J-200D01*
G01X1712715Y105222D01*
X1712736Y105210D01*
X1712738Y105208D01*
G03X1712768Y105190I827J1345D01*
G01X1712790Y105178D01*
X1712838Y105131D01*
X1712846Y105123D01*
X1712850Y105118D01*
G02X1712900Y104970I-149J-133D01*
G01X1712897Y104931D01*
X1712878Y104894D01*
X1712861Y104869D01*
G02X1712825Y104828I-167J110D01*
G01X1712765Y104776D01*
X1712741Y104764D01*
G03X1711892Y103411I654J-1353D01*
G03X1714896I1502J0D01*
G03X1714317Y104596I-1502J0D01*
G01X1714299Y104610D01*
X1714262Y104655D01*
G02X1714230Y104709I154J128D01*
G02X1714216Y104792I186J74D01*
G01X1714222Y104921D01*
Y104923D01*
X1714226Y105011D01*
G02X1714278Y105135I200J-11D01*
G01X1714281Y105139D01*
X1714327Y105185D01*
X1714350Y105198D01*
G03X1715131Y106561I-799J1363D01*
G03X1713553Y108139I-1578J0D01*
G03X1712702Y107890I0J-1579D01*
G01X1712666Y107868D01*
X1712119D01*
X1712100Y107888D01*
G03X1712093Y107894I-134J-149D01*
G01X1712088Y107898D01*
X1702351Y117635D01*
G02X1702344Y117644I154J127D01*
G01Y136710D01*
G02X1702348Y136748I200J-2D01*
G02X1702401Y136850I196J-37D01*
G01X1707846Y142295D01*
X1707888Y142320D01*
X1707911Y142327D01*
G03X1708919Y143385I-446J1434D01*
G01X1708926Y143412D01*
X1708942Y143439D01*
G02X1708972Y143478I172J-101D01*
G01X1728005Y162510D01*
G03X1728376Y163406I-896J896D01*
G01Y174937D01*
G02X1728391Y175013I200J0D01*
G01X1728406Y175049D01*
X1728415Y175058D01*
G03X1728817Y176002I-907J944D01*
G03X1728816Y176048I-1308J-5D01*
G01Y271248D01*
G03X1728817Y271294I-1307J51D01*
G03X1728415Y272238I-1309J0D01*
G01X1728406Y272247D01*
X1728391Y272283D01*
G02X1728376Y272359I185J76D01*
G01Y274837D01*
G03X1728005Y275733I-1267J0D01*
G01X1700868Y302870D01*
G03X1700404Y303165I-895J-896D01*
G01X1700399D01*
X1700333Y303190D01*
G03X1700307Y303197I-65J-189D01*
G01X1700306D01*
X1700296Y303199D01*
X1700285Y303202D01*
G03X1699972Y303240I-308J-1228D01*
G01X1699913D01*
G02X1699713Y303440I0J200D01*
G01Y303473D01*
X1699723Y303503D01*
G03X1699794Y303959I-1431J456D01*
G01Y303962D01*
G03X1698292Y305464I-1502J0D01*
G03X1696790Y303964I0J-1502D01*
G01Y303959D01*
G03X1696809Y303718I1502J-3D01*
G01X1696810Y303713D01*
X1696813Y303684D01*
G02X1696805Y303616I-200J-11D01*
G01X1696793Y303577D01*
X1696766Y303545D01*
X1696734Y303507D01*
Y303505D01*
X1696570Y303311D01*
G02X1696417Y303240I-153J129D01*
G01X1693853D01*
G02X1693831Y303241I-2J200D01*
G02X1693775Y303256I23J199D01*
G01X1693743Y303270D01*
X1693716Y303296D01*
G03X1693704Y303306I-134J-149D01*
G01X1693695Y303313D01*
X1687029Y309979D01*
G02X1686971Y310125I142J141D01*
G01X1686978Y310254D01*
X1686988Y310430D01*
G02X1687005Y310499I200J-13D01*
G01X1687010Y310509D01*
X1687020Y310528D01*
X1687031Y310548D01*
X1687062Y310574D01*
G03X1687617Y311739I-946J1166D01*
G01Y311768D01*
G03X1687047Y312918I-1502J-28D01*
G01X1687037Y312926D01*
X1687022Y312941D01*
G02X1686976Y313013I142J141D01*
G01X1686961Y313052D01*
X1686964Y313096D01*
X1686987Y313438D01*
G02X1687012Y313513I199J-25D01*
G01X1687028Y313535D01*
G02X1687029Y313537I176J-87D01*
G01X1687075Y313579D01*
G02X1687078Y313581I112J-165D01*
G03X1687089Y313588I-801J1271D01*
G01X1687096Y313591D01*
G03X1687841Y314890I-760J1299D01*
G03X1686339Y316392I-1502J0D01*
G01X1686336D01*
G03X1685987Y316350I4J-1502D01*
G01X1685978Y316348D01*
X1685936Y316338D01*
X1685883Y316347D01*
G02X1685811Y316380I46J195D01*
G01X1685697Y316452D01*
X1685695D01*
X1685579Y316525D01*
G02X1685521Y316581I107J169D01*
G01X1685498Y316614D01*
X1685491Y316646D01*
X1685489Y316655D01*
Y316656D01*
G03X1685439Y316830I-1239J-262D01*
G03X1685438Y316832I-178J-88D01*
G03X1685418Y316882I-1186J-445D01*
G03X1685157Y317277I-1169J-489D01*
G03X1685155Y317279I-142J-140D01*
G01X1685154Y317280D01*
G03X1685147Y317287I-899J-892D01*
G01X1682942Y319492D01*
G03X1682478Y319787I-895J-896D01*
G01X1682473D01*
X1682407Y319812D01*
G03X1682381Y319819I-65J-189D01*
G01X1682380D01*
X1682370Y319821D01*
X1682359Y319824D01*
G03X1682046Y319862I-308J-1228D01*
G01X1677741D01*
G02X1677719Y319863I-2J200D01*
G02X1677663Y319878I23J199D01*
G01X1677631Y319892D01*
X1677604Y319918D01*
G03X1677592Y319928I-134J-149D01*
G01X1677583Y319935D01*
X1667887Y329631D01*
G02X1667851Y329681I142J140D01*
G02X1667829Y329772I178J91D01*
G01Y332492D01*
G02X1667909Y332652I200J0D01*
G01X1677666D01*
G02X1677686Y332635I-119J-160D01*
G01X1679340Y330981D01*
G03X1680941Y330318I1602J1603D01*
G01X1685977D01*
X1685995Y330315D01*
G03X1686405Y330278I411J2269D01*
G01X1686408D01*
G03X1688714Y332584I0J2306D01*
G01Y332585D01*
G03X1688039Y334215I-2306J0D01*
G01X1685665Y336589D01*
G03X1685283Y336897I-1631J-1631D01*
G02X1685405Y337265I108J168D01*
G03X1685498Y337262I89J1303D01*
G01X1687544D01*
G02X1687615Y337249I0J-200D01*
G02X1687685Y337204I-71J-187D01*
G01X1722935Y301953D01*
G03X1722939Y301949I926J922D01*
G03X1723171Y301765I923J925D01*
G01X1723191Y301753D01*
X1723779Y301165D01*
G03X1723921Y301106I142J141D01*
G01X1782818D01*
G02X1782856Y301102I-2J-200D01*
G02X1782958Y301049I-37J-196D01*
G01X1787198Y296809D01*
G02X1787251Y296707I-143J-139D01*
G02X1787255Y296669I-196J-40D01*
G01Y288564D01*
Y288562D01*
G03X1787262Y288508I200J-1D01*
G01X1787270Y288482D01*
Y264375D01*
X1787250Y264356D01*
G03X1787244Y264349I148J-133D01*
G01X1787237Y264340D01*
X1784839Y261942D01*
G02X1784789Y261906I-140J142D01*
G02X1784698Y261884I-91J178D01*
G01X1763427D01*
G03X1763003Y261813I-6J-1267D01*
G01X1763002Y261812D01*
X1762999Y261811D01*
X1762992Y261808D01*
X1762982Y261804D01*
X1762980Y261803D01*
G03X1762909Y261774I443J-1186D01*
G01X1762533Y261512D01*
G03X1762506Y261489I116J-163D01*
G01X1760741Y259723D01*
X1760726Y259714D01*
X1760720Y259710D01*
G03X1760490Y259529I688J-1111D01*
G03X1760486Y259525I922J-926D01*
G01X1758731Y257770D01*
X1758689Y257745D01*
X1758666Y257738D01*
G03X1757643Y256615I447J-1434D01*
G03X1757618Y256147I1469J-313D01*
G01X1757622Y256105D01*
X1757610Y256066D01*
G02X1757578Y256005I-190J61D01*
G01X1757396Y255800D01*
X1757366Y255766D01*
G02X1757287Y255716I-144J139D01*
G01X1757245Y255704D01*
X1755178D01*
G02X1755122Y255712I0J200D01*
G02X1755104Y255718I54J193D01*
G01X1755068Y255733D01*
X1751025Y259776D01*
G03X1750562Y260071I-896J-896D01*
G01X1750520Y260085D01*
X1750490Y260096D01*
G03X1750462Y260104I-69J-188D01*
G01X1750455Y260105D01*
X1750443Y260108D01*
X1750438Y260109D01*
G03X1750130Y260147I-308J-1229D01*
G01X1750107D01*
X1750098Y260146D01*
X1750045D01*
X1750022Y260151D01*
G03X1749722Y260186I-300J-1271D01*
G01X1737078D01*
X1737061Y260195D01*
G03X1736335Y260382I-726J-1317D01*
G01X1736333D01*
G03Y257378I0J-1502D01*
G01X1736334D01*
G03X1737065Y257568I-1J1504D01*
G01X1737076Y257574D01*
X1749097D01*
G02X1749134Y257571I2J-200D01*
G02X1749238Y257516I-37J-197D01*
G01X1753585Y253168D01*
X1753677Y253076D01*
G03X1754244Y252743I924J924D01*
G03X1754452Y252702I356J1257D01*
G01X1754455D01*
G02X1754571Y252647I-23J-199D01*
G01X1756286Y250931D01*
X1756289Y250927D01*
G03X1756859Y250584I916J877D01*
G01X1756870Y250582D01*
X1756881Y250579D01*
G03X1757203Y250536I327J1225D01*
G01X1765623D01*
G02X1765729Y250503I-4J-200D01*
G01X1765756Y250484D01*
G02X1765774Y250468I-124J-157D01*
G02X1765825Y250379I-142J-141D01*
G01X1765839Y250328D01*
X1765856Y250287D01*
X1765874Y250240D01*
G03X1765911Y250180I186J74D01*
G01X1765915Y250175D01*
G02X1765960Y250077I-152J-129D01*
G01X1765964Y250050D01*
X1765961Y250023D01*
G02X1765945Y249967I-198J26D01*
G01X1765911Y249891D01*
Y249889D01*
X1765893Y249848D01*
X1765867Y249821D01*
G03X1765866Y249820I1062J-1063D01*
G03X1765864Y249818I140J-142D01*
G03X1765434Y248773I1072J-1052D01*
G01Y248741D01*
G03X1766880Y247264I1502J24D01*
G01X1766881D01*
G03X1766936Y247263I55J1501D01*
G01X1766938D01*
G03X1767872Y247590I-1J1501D01*
G01X1767898Y247610D01*
X1767942Y247625D01*
G02X1767995Y247633I56J-192D01*
G01X1768081D01*
G03X1768164Y247651I0J200D01*
G01X1768218Y247676D01*
G02X1768296Y247695I85J-181D01*
G02X1768330Y247693I5J-200D01*
G02X1768434Y247645I-28J-198D01*
G01X1768435Y247644D01*
G03X1768777Y247415I999J1123D01*
G03X1768835Y247388I663J1348D01*
G01X1768853Y247380D01*
G03X1769431Y247263I581J1385D01*
G01X1769457D01*
G03X1769917Y247342I-21J1502D01*
G03X1770370Y247589I-482J1423D01*
G01X1770371Y247590D01*
X1770383Y247600D01*
G02X1770489Y247633I110J-167D01*
G01X1770581D01*
G03X1770664Y247651I0J200D01*
G01X1770718Y247676D01*
G02X1770796Y247695I85J-181D01*
G02X1770830Y247693I5J-200D01*
G02X1770934Y247645I-28J-198D01*
G01X1770935Y247644D01*
G03X1771934Y247263I1000J1122D01*
G01X1771936D01*
G03X1773438Y248765I0J1502D01*
G03X1773005Y249820I-1502J0D01*
G01X1773004Y249821D01*
X1772980Y249846D01*
X1772964Y249880D01*
X1772949Y249912D01*
G02X1772941Y249936I185J75D01*
G01X1772929Y249992D01*
G02X1772936Y250089I198J34D01*
G01X1773011Y250273D01*
Y250275D01*
X1773072Y250421D01*
G02X1773099Y250464I182J-84D01*
G02X1773253Y250536I154J-128D01*
G01X1777933D01*
G02X1777965Y250533I-3J-200D01*
G01X1777967D01*
G02X1778073Y250479I-34J-197D01*
G01X1778376Y250176D01*
G02X1778394Y250155I-142J-140D01*
G01Y228983D01*
G02X1778389Y228976I-165J113D01*
G01X1778380Y228965D01*
X1777067Y227652D01*
G03X1776786Y227225I896J-896D01*
G02X1776776Y227203I-187J72D01*
G01X1776759Y227172D01*
G03X1776494Y226384I1041J-789D01*
G01Y222748D01*
G02X1776403Y222680I-160J120D01*
G01X1776232Y222617D01*
X1776050Y222550D01*
G02X1776020Y222542I-66J189D01*
G02X1775929Y222545I-39J196D01*
G01X1775900Y222553D01*
X1775848Y222586D01*
X1775828Y222610D01*
G03X1774679Y223144I-1149J-969D01*
G03Y220140I0J-1502D01*
G03X1775806Y220648I0J1504D01*
G01X1775829Y220674D01*
X1775881Y220709D01*
G02X1775907Y220722I102J-172D01*
G03X1775909Y220724I-140J142D01*
G02X1776056Y220731I82J-182D01*
G01X1776059Y220730D01*
X1776403Y220604D01*
G02X1776494Y220537I-68J-188D01*
G01Y216980D01*
G03X1776876Y216058I1306J1D01*
G01X1784451Y208483D01*
X1784476Y208441D01*
X1784483Y208418D01*
G03X1785020Y207660I1434J447D01*
G03X1785894Y207362I898J1204D01*
G01X1785917Y207361D01*
X1786040Y207307D01*
X1786044Y207304D01*
X1786302Y207046D01*
G02X1786345Y206828I-142J-141D01*
G02X1786343Y206824I-180J87D01*
G01X1786234Y206578D01*
Y206576D01*
X1786203Y206509D01*
G02X1786199Y206499I-188J69D01*
G01X1786180Y206464D01*
G02X1786008Y206364I-173J100D01*
G01X1785991D01*
G03X1785918Y206366I-78J-1500D01*
G03X1787420Y204864I0J-1502D01*
G01Y204866D01*
G03X1787329Y205381I-1502J0D01*
G01X1787323Y205397D01*
X1787316Y205430D01*
G02X1787374Y205613I197J38D01*
G02X1787396Y205630I133J-149D01*
G01X1787411Y205641D01*
X1787450Y205669D01*
G02X1787658Y205679I112J-165D01*
G01X1787686Y205662D01*
X1787779Y205569D01*
G02X1787832Y205468I-143J-140D01*
G01Y205466D01*
G02X1787836Y205429I-196J-40D01*
G01Y198067D01*
G02X1787814Y197976I-200J0D01*
G02X1787778Y197926I-178J90D01*
G01X1787460Y197608D01*
G02X1787427Y197606I-29J198D01*
G01X1787138Y197613D01*
G02X1787074Y197625I4J200D01*
G02X1787060Y197631I72J187D01*
G01X1787023Y197648D01*
X1786995Y197678D01*
G03X1785887Y198167I-1109J-1012D01*
G01X1785886D01*
G03X1784384Y196665I0J-1502D01*
G03X1784987Y195462I1502J0D01*
G01X1785000Y195452D01*
X1785023Y195428D01*
X1785025Y195426D01*
X1785027Y195423D01*
G02X1785079Y195263I-146J-136D01*
G01X1785075Y195233D01*
X1785074Y195222D01*
X1784148Y194297D01*
G03X1783472Y192666I1631J-1632D01*
G01Y192607D01*
X1783473Y192583D01*
G03X1785558Y190369I2305J82D01*
G01X1785596Y190366D01*
X1785630Y190348D01*
G02X1785686Y190306I-90J-178D01*
G01X1785706Y190284D01*
G03X1785709Y190281I143J140D01*
G01X1785722Y190268D01*
G02X1785776Y190162I-143J-140D01*
G01Y190160D01*
G02X1785779Y190128I-197J-35D01*
G01Y189701D01*
G03X1785838Y189559I200J0D01*
G01X1786441Y188956D01*
G02X1786481Y188731I-142J-141D01*
G01X1786357Y188463D01*
X1786339Y188425D01*
G02X1786160Y188313I-179J88D01*
G01X1786141D01*
X1786132Y188314D01*
G03X1785999Y188320I-136J-1536D01*
G03Y185236I0J-1542D01*
G01X1786001D01*
G03X1786680Y185394I-1J1543D01*
G02X1786841Y185401I88J-179D01*
G01X1786863Y185392D01*
G02X1786869Y185388I-108J-168D01*
G01X1787085Y185251D01*
X1787121Y185228D01*
G02X1787200Y185134I-106J-170D01*
G02X1787214Y185073I-186J-75D01*
G01Y178337D01*
G02X1787170Y178212I-200J0D01*
G03X1787168Y178210I140J-142D01*
G02X1787156Y178196I-158J123D01*
G01X1787110Y178150D01*
X1787088Y178137D01*
X1787030Y178103D01*
G02X1787028Y178102I-90J178D01*
G03X1786973Y178054I102J-172D01*
G01X1786948Y178021D01*
X1786903Y177997D01*
G02X1786817Y177976I-89J179D01*
G01X1786669D01*
G02X1786621Y177982I1J200D01*
G01X1786597Y177988D01*
G03X1785886Y178167I-711J-1323D01*
G03Y175163I0J-1502D01*
G03X1786619Y175354I0J1502D01*
G01X1786620Y175355D01*
G02X1786719Y175380I97J-175D01*
G01X1786772Y175379D01*
X1786970Y175263D01*
X1787115Y175178D01*
G02X1787214Y175006I-101J-173D01*
G01Y170337D01*
G02X1787170Y170212I-200J0D01*
G03X1787168Y170210I140J-142D01*
G02X1787156Y170196I-158J123D01*
G01X1787110Y170150D01*
X1787088Y170137D01*
X1787030Y170103D01*
G02X1787028Y170102I-90J178D01*
G03X1786973Y170054I102J-172D01*
G01X1786948Y170021D01*
X1786903Y169997D01*
G02X1786817Y169976I-89J179D01*
G01X1786669D01*
G02X1786621Y169982I1J200D01*
G01X1786597Y169988D01*
G03X1785886Y170167I-711J-1323D01*
G03Y167163I0J-1502D01*
G03X1786619Y167354I0J1502D01*
G01X1786620Y167355D01*
G02X1786719Y167380I97J-175D01*
G01X1786772Y167379D01*
X1786970Y167263D01*
X1787115Y167178D01*
G02X1787214Y167006I-101J-173D01*
G01Y147778D01*
G02X1787192Y147687I-200J0D01*
G02X1787156Y147637I-178J90D01*
G01X1769542Y130023D01*
G03X1769160Y129101I924J-923D01*
G01Y116703D01*
G03X1769542Y115781I1306J1D01*
G01X1771635Y113689D01*
G02X1771675Y113473I-144J-138D01*
G02X1771491Y113350I-185J77D01*
G01X1762261D01*
G03X1761365Y112979I0J-1267D01*
G01X1760536Y112150D01*
X1760514Y112137D01*
G03X1760251Y111934I660J-1127D01*
G01X1757374Y109056D01*
G02X1757264Y109000I-141J142D01*
G02X1757233Y108998I-28J198D01*
G01X1752183D01*
G03X1751261Y108616I1J-1306D01*
G01X1748518Y105873D01*
X1747430Y104786D01*
G02X1747175Y104763I-141J142D01*
G02X1747155Y104779I240J320D01*
G01X1747153D01*
G02X1747004Y105091I251J312D01*
G01Y107649D01*
G03X1743400I-1802J0D01*
G01Y105267D01*
X1743399Y104249D01*
G03X1744612Y102545I1803J0D01*
G01X1744630Y102539D01*
G02X1744740Y102408I-84J-182D01*
G01X1744744Y102394D01*
X1744772Y102269D01*
Y102267D01*
X1744779Y102237D01*
G02X1744721Y102047I-195J-44D01*
G01X1744591Y101938D01*
G03X1744505Y101860I834J-1006D01*
G01X1742531Y99886D01*
G02X1742481Y99850I-140J142D01*
G02X1742390Y99828I-91J178D01*
G01X1736281D01*
G02X1736190Y99850I0J200D01*
G02X1736140Y99886I90J178D01*
G01X1735684Y100342D01*
X1735659Y100384D01*
X1735652Y100407D01*
G03X1734217Y101463I-1435J-447D01*
G03X1732715Y99961I0J-1502D01*
G01X1732714D01*
G03X1733771Y98526I1503J0D01*
G01X1733773D01*
X1733796Y98518D01*
X1733836Y98494D01*
X1733885Y98445D01*
X1734021Y98310D01*
G02Y98252I-198J-29D01*
G01X1732636Y96867D01*
G03X1731993Y95624I1631J-1631D01*
G01X1731977Y95527D01*
G02X1731899Y95480I-140J143D01*
G01X1731867Y95470D01*
X1731704Y95419D01*
X1731554Y95372D01*
G02X1731472Y95367I-53J193D01*
G01X1730679Y96160D01*
G03X1729757Y96542I-923J-924D01*
G01X1725079D01*
X1725062Y96551D01*
G03X1724336Y96738I-726J-1317D01*
G01X1724334D01*
G03Y93734I0J-1502D01*
G01X1724335D01*
G03X1725066Y93924I-1J1504D01*
G01X1725077Y93930D01*
X1729131D01*
X1729144D01*
G02X1729271Y93873I-13J-200D01*
G01X1729586Y93557D01*
X1729740Y93403D01*
G02X1729741Y93349I-198J-31D01*
G02X1729733Y93314I-198J27D01*
G01X1729696Y93203D01*
Y93201D01*
X1729612Y92928D01*
X1729583Y92902D01*
X1729486Y92885D01*
G03X1727741Y91437I410J-2270D01*
G01X1727708Y91351D01*
G02X1727639Y91322I-111J166D01*
G01X1727445Y91281D01*
X1727443D01*
X1727302Y91251D01*
G02X1727246Y91252I-24J199D01*
G01X1726216Y92282D01*
G03X1724584Y92958I-1632J-1632D01*
G03X1722276Y90650I0J-2308D01*
G03X1722952Y89018I2308J0D01*
G01X1724892Y87078D01*
G03X1726524Y86402I1632J1632D01*
G03X1726608Y86404I-13J2308D01*
G01X1741368D01*
X1741370D01*
G02X1741495Y86359I-1J-200D01*
G02X1741529Y86323I-127J-154D01*
G01X1741661Y86145D01*
G02X1741697Y86062I-160J-119D01*
G01X1741706Y86016D01*
X1741692Y85969D01*
G03X1741629Y85539I1439J-430D01*
G03X1742035Y84512I1502J0D01*
G01X1742063Y84482D01*
X1742076Y84448D01*
G02X1742079Y84441I-182J-82D01*
G02X1742089Y84377I-190J-63D01*
G01Y84101D01*
G02X1742079Y84037I-200J-1D01*
G02X1742076Y84030I-185J75D01*
G01X1742063Y83996D01*
X1742035Y83966D01*
G03Y81912I1096J-1027D01*
G01X1742063Y81882D01*
X1742076Y81848D01*
G02X1742079Y81841I-182J-82D01*
G02X1742089Y81777I-190J-63D01*
G01Y81501D01*
G02X1742079Y81437I-200J-1D01*
G02X1742076Y81430I-185J75D01*
G01X1742063Y81396D01*
X1742035Y81366D01*
G03Y79312I1096J-1027D01*
G01X1742063Y79282D01*
X1742076Y79248D01*
G02X1742079Y79241I-182J-82D01*
G02X1742089Y79177I-190J-63D01*
G01Y78901D01*
G02X1742079Y78837I-200J-1D01*
G02X1742076Y78830I-185J75D01*
G01X1742063Y78796D01*
X1742035Y78766D01*
G03Y76712I1096J-1027D01*
G01X1742063Y76682D01*
X1742076Y76648D01*
G02X1742079Y76641I-182J-82D01*
G02X1742089Y76577I-190J-63D01*
G01Y76301D01*
G02X1742079Y76237I-200J-1D01*
G02X1742076Y76230I-185J75D01*
G01X1742063Y76196D01*
X1742035Y76166D01*
G03X1741629Y75139I1096J-1027D01*
G03X1744633I1502J0D01*
G03X1744227Y76166I-1502J0D01*
G01X1744199Y76196D01*
X1744186Y76230D01*
G02X1744183Y76237I182J82D01*
G02X1744173Y76301I190J63D01*
G01Y76577D01*
G02X1744183Y76641I200J1D01*
G02X1744186Y76648I185J-75D01*
G01X1744199Y76682D01*
X1744227Y76712D01*
G03Y78766I-1096J1027D01*
G01X1744199Y78796D01*
X1744186Y78830D01*
G02X1744183Y78837I182J82D01*
G02X1744173Y78901I190J63D01*
G01Y79177D01*
G02X1744183Y79241I200J1D01*
G02X1744186Y79248I185J-75D01*
G01X1744199Y79282D01*
X1744227Y79312D01*
G03Y81366I-1096J1027D01*
G01X1744199Y81396D01*
X1744186Y81430D01*
G02X1744183Y81437I182J82D01*
G02X1744173Y81501I190J63D01*
G01Y81777D01*
G02X1744183Y81841I200J1D01*
G02X1744186Y81848I185J-75D01*
G01X1744199Y81882D01*
X1744227Y81912D01*
G03Y83966I-1096J1027D01*
G01X1744199Y83996D01*
X1744186Y84030D01*
G02X1744183Y84037I182J82D01*
G02X1744173Y84101I190J63D01*
G01Y84377D01*
G02X1744183Y84441I200J1D01*
G02X1744186Y84448I185J-75D01*
G01X1744199Y84482D01*
X1744227Y84512D01*
G03X1744633Y85539I-1096J1027D01*
G03X1744570Y85969I-1502J0D01*
G01Y85970D01*
G02X1744565Y86063I192J57D01*
G01X1744573Y86108D01*
X1744734Y86324D01*
G02X1744756Y86348I158J-122D01*
G02X1744892Y86404I139J-144D01*
G01X1762018D01*
G02X1762132Y86369I1J-200D01*
G02X1762148Y86356I-118J-162D01*
G01X1763499Y85005D01*
G02X1763501Y84976I-198J-28D01*
G01Y84913D01*
X1763489Y84867D01*
X1763472Y84834D01*
G03X1763302Y84143I1332J-694D01*
G01Y84110D01*
G03X1764804Y82638I1502J30D01*
G01X1764820D01*
G03X1764855Y82639I-25J1502D01*
G01X1764878D01*
G02X1764998Y82599I0J-200D01*
G01X1765010Y82590D01*
X1765224Y82384D01*
G02X1765246Y82359I-139J-144D01*
G01Y78752D01*
X1765245Y76587D01*
G03X1766035Y74849I2307J0D01*
G01X1766078Y74812D01*
X1766086Y74795D01*
G02X1766104Y74717I-182J-83D01*
G01X1766110Y74497D01*
Y74494D01*
X1766112Y74437D01*
X1765921Y74246D01*
G03X1765246Y72615I1631J-1630D01*
G01X1765245Y72567D01*
G03X1767552Y70308I2307J49D01*
G01X1767588D01*
G03X1768445Y70488I-37J2307D01*
G03X1769184Y70984I-892J2127D01*
G01X1771422Y73222D01*
G03X1772098Y74853I-1631J1632D01*
G01Y84548D01*
G02X1772168Y84606I159J-121D01*
G01X1772451Y84726D01*
X1772453D01*
X1772521Y84754D01*
G02X1772735Y84714I76J-185D01*
G01X1773952Y83497D01*
X1774896Y82554D01*
G02X1774949Y82392I-145J-137D01*
G01X1774941Y82342D01*
X1774895Y82057D01*
G02X1774861Y81980I-196J41D01*
G01X1774841Y81953D01*
X1774819Y81942D01*
G03X1773961Y80581I650J-1361D01*
G03X1776979I1509J0D01*
G01Y80584D01*
G03X1776896Y81076I-1509J-2D01*
G01X1776883Y81114D01*
X1776882Y81121D01*
G02X1776914Y81247I200J16D01*
G01X1776919Y81254D01*
X1777106Y81516D01*
G02X1777109Y81520I162J-118D01*
G01X1783262D01*
G03X1784892Y82195I0J2306D01*
G01X1786256Y83559D01*
G02X1786358Y83612I139J-143D01*
G02X1786396Y83616I40J-196D01*
G01X1786466D01*
G03Y88230I0J2307D01*
G01X1785357D01*
G03X1783726Y87554I1J-2307D01*
G01X1783585Y87412D01*
X1783549Y87411D01*
X1783524Y87431D01*
X1783428Y87511D01*
G03X1781961Y88038I-1468J-1780D01*
G01X1781339D01*
G02X1781303Y88073I120J160D01*
G01X1781230Y88164D01*
X1781100Y88325D01*
G02X1781090Y88341I165J114D01*
G02X1781072Y88388I176J94D01*
G01X1781059Y88438D01*
X1781061Y88445D01*
X1781069Y88485D01*
G03X1781102Y88791I-1469J313D01*
G03Y88793I-1502J1D01*
G01Y88816D01*
G03X1779776Y90293I-1502J-15D01*
G01X1779720Y90299D01*
G03X1779600Y90304I-123J-1498D01*
G03X1778590Y89914I0J-1503D01*
G01X1778588Y89912D01*
G02X1778488Y89864I-133J149D01*
G01X1778460Y89860D01*
X1778432Y89863D01*
G02X1778376Y89879I26J198D01*
G01X1778308Y89909D01*
X1778041Y90027D01*
G02X1777922Y90210I81J183D01*
G01Y101985D01*
G02X1777987Y102133I200J0D01*
G02X1778054Y102173I134J-149D01*
G01X1778067Y102177D01*
G03X1779087Y103173I-414J1444D01*
G02X1779089Y103177I178J-86D01*
G01X1779090Y103181D01*
G02X1779138Y103258I189J-65D01*
G01X1782824Y106944D01*
G03X1783206Y107866I-924J923D01*
G01Y118837D01*
G03X1782824Y119759I-1306J-1D01*
G01X1779070Y123512D01*
G02X1779015Y123619I142J141D01*
G02X1779012Y123653I197J35D01*
G01Y125475D01*
G02X1779023Y125540I200J0D01*
G02X1779070Y125616I189J-65D01*
G01X1801799Y148344D01*
G03X1802177Y149163I-924J923D01*
G01X1802180Y149199D01*
X1802194Y149230D01*
G02X1802234Y149287I181J-85D01*
G01X1802697Y149750D01*
G03X1802756Y149892I-141J142D01*
G01Y279175D01*
G02X1802760Y279212I200J-3D01*
G01Y279214D01*
G02X1802813Y279315I196J-39D01*
G01X1809887Y286389D01*
G03X1809946Y286531I-141J142D01*
G01Y287915D01*
X1809955Y287945D01*
G03X1810014Y288332I-1247J388D01*
G01Y300720D01*
G03X1809955Y301107I-1306J-1D01*
G01X1809946Y301137D01*
Y303937D01*
G03X1809575Y304833I-1267J0D01*
G01X1802667Y311741D01*
G03X1802525Y311800I-142J-141D01*
G01X1728457D01*
G02X1728315Y311859I0J200D01*
G01X1716943Y323231D01*
G02X1716894Y323433I141J141D01*
G01X1717000Y323771D01*
G02X1717060Y323862I191J-60D01*
G01X1717081Y323880D01*
X1717128Y323903D01*
X1717156Y323908D01*
G03X1719062Y326179I-400J2271D01*
G03X1716755Y328486I-2307J0D01*
G01X1715981D01*
G02X1715890Y328508I0J200D01*
G02X1715840Y328544I90J178D01*
G01X1715491Y328893D01*
G02X1715501Y328989I198J28D01*
G01X1715562Y329159D01*
Y329161D01*
X1715625Y329334D01*
G02X1715651Y329383I188J-68D01*
G01X1715667Y329404D01*
X1715678Y329412D01*
X1715781Y329420D01*
G03X1717897Y331719I-191J2299D01*
G01Y331748D01*
X1717895Y331792D01*
G03X1717221Y333350I-2305J-72D01*
G01X1712644Y337927D01*
G02X1712608Y337977I142J140D01*
G02X1712586Y338068I178J91D01*
G01Y341736D01*
G02X1712593Y341746I167J-110D01*
G01X1712741Y341780D01*
G03X1712979Y341848I-514J2248D01*
G03X1712987Y341850I-45J195D01*
G03X1712997Y341854I-851J2143D01*
G02X1713005Y341857I74J-185D01*
G03X1713027Y341865I-777J2171D01*
G01X1713114Y341897D01*
G02X1713159Y341876I-61J-190D01*
G01X1713283Y341790D01*
X1713285D01*
X1713447Y341675D01*
G02X1713484Y341637I-123J-157D01*
G01Y341107D01*
G03X1714160Y339476I2307J1D01*
G01X1714298Y339338D01*
G03X1715930Y338662I1632J1632D01*
G03X1718236Y340969I0J2306D01*
G03X1718109Y341726I-2306J2D01*
G01X1718098Y341758D01*
Y364210D01*
G02X1718135Y364248I160J-119D01*
G01X1718151Y364260D01*
X1718415Y364452D01*
G02X1718488Y364480I107J-169D01*
G01X1718535Y364487D01*
X1718582Y364472D01*
X1718585Y364471D01*
G03X1719284Y364360I701J2155D01*
G01X1735733D01*
G03X1737334Y365023I-1J2266D01*
G01X1738726Y366415D01*
X1738741Y366425D01*
G03X1739055Y366688I-1318J1893D01*
G01X1748351Y375984D01*
G03X1749026Y377614I-1631J1630D01*
G01Y377649D01*
G02X1749226Y377849I200J0D01*
G01X1749284D01*
X1749333Y377818D01*
G03X1750135Y377586I802J1270D01*
G03Y380590I0J1502D01*
G01X1750134D01*
G03X1749575Y380482I0J-1502D01*
G01X1749529Y380463D01*
X1749431Y380473D01*
X1749114Y380688D01*
G02X1749026Y380853I112J166D01*
G01Y381427D01*
G03X1748351Y383057I-2306J0D01*
G01X1745811Y385597D01*
G03X1744181Y386272I-1630J-1631D01*
G01X1744180D01*
G03X1741874Y383966I0J-2306D01*
G01Y383965D01*
G03X1742549Y382335I2306J0D01*
G01X1743657Y381227D01*
G02X1743715Y381072I-142J-141D01*
G01X1743692Y380728D01*
X1743651Y380653D01*
X1743616Y380626D01*
G03X1743022Y379429I909J-1197D01*
G01Y379428D01*
G03X1743536Y378297I1502J0D01*
G01X1743568Y378269D01*
X1743604Y378195D01*
X1743615Y377862D01*
G02X1743557Y377714I-200J-7D01*
G01X1743478Y377635D01*
G02X1743196I-141J142D01*
G01X1743165Y377666D01*
X1743150Y377706D01*
G03X1741746Y378675I-1404J-533D01*
G01X1741745D01*
G03X1741065Y378512I1J-1502D01*
G01X1741064D01*
G02X1740832Y378549I-91J178D01*
G01X1740577Y378804D01*
G03X1738946Y379480I-1632J-1631D01*
G01X1737786D01*
G03X1735480Y377173I0J-2306D01*
G03X1735710Y376168I2306J-1D01*
G01Y376167D01*
G02X1735699Y375975I-180J-86D01*
G01X1735520Y375688D01*
G02X1735350Y375594I-170J106D01*
G01X1731243D01*
G02X1731063Y375707I0J200D01*
G01X1730906Y376031D01*
G02X1730928Y376241I180J87D01*
G01X1730929Y376242D01*
G03X1731253Y377173I-1178J932D01*
G03X1729751Y378675I-1502J0D01*
G03X1728317Y377620I0J-1502D01*
G01Y377618D01*
G02X1728268Y377538I-190J62D01*
G01X1727193Y376463D01*
G02X1727051Y376404I-142J141D01*
G01X1723611D01*
G02X1723457Y376477I0J200D01*
G01X1723261Y376715D01*
G02X1723219Y376880I154J127D01*
G01Y376881D01*
G03X1723248Y377173I-1473J294D01*
G03X1720244I-1502J0D01*
G03X1720273Y376882I1502J3D01*
G01Y376880D01*
G02X1720231Y376715I-196J-38D01*
G01X1720035Y376477D01*
G02X1719881Y376404I-154J127D01*
G01X1719592D01*
G02X1719450Y376463I0J200D01*
G01X1697567Y398345D01*
G02X1697508Y398487I141J142D01*
G01Y423254D01*
G02X1697567Y423396I200J0D01*
G01X1712546Y438375D01*
G03X1712605Y438517I-141J142D01*
G01Y439626D01*
X1712611Y439649D01*
G03X1712646Y439954I-1272J300D01*
G01Y458394D01*
G02X1712705Y458536I200J0D01*
G01X1717869Y463699D01*
G02X1718086Y463742I141J-142D01*
G01X1718143Y463719D01*
X1718210Y463618D01*
Y458164D01*
G02X1718151Y458022I-200J0D01*
G01X1715945Y455817D01*
G02X1715865Y455768I-142J141D01*
G01X1715864D01*
G03X1714808Y454334I446J-1434D01*
G03X1716310Y452832I1502J0D01*
G03X1717744Y453887I0J1502D01*
G01Y453889D01*
G02X1717793Y453969I190J-62D01*
G01X1720440Y456616D01*
G03X1720822Y457538I-924J923D01*
G01Y463233D01*
G02X1720881Y463375I200J0D01*
G01X1730058Y472551D01*
G02X1730200Y472610I142J-141D01*
G01X1736113D01*
G03X1737037Y472993I0J1306D01*
G01X1737267Y473223D01*
G02X1737409Y473282I142J-141D01*
G01X1743598D01*
G03X1744522Y473665I0J1306D01*
G01X1756756Y485899D01*
G02X1756836Y485948I142J-141D01*
G01X1756837D01*
G03X1756872Y485959I-433J1438D01*
G02X1756902Y485967I66J-189D01*
G01X1756952Y485975D01*
G02X1757152Y485775I0J-200D01*
G01X1757129Y485696D01*
G02X1757109Y485649I-192J54D01*
G03X1756899Y484883I1292J-766D01*
G01Y484882D01*
G03X1758401Y486384I1502J0D01*
G01X1758399D01*
G03X1758236Y486375I1J-1502D01*
G01X1758185Y486369D01*
X1758091Y486408D01*
X1757847Y486712D01*
G02X1757814Y486901I156J125D01*
G03X1757893Y487381I-1423J481D01*
G01Y487382D01*
G03X1756391Y488884I-1502J0D01*
G03X1754957Y487829I0J-1502D01*
G01Y487827D01*
G02X1754908Y487747I-190J62D01*
G01X1743116Y475955D01*
G02X1742974Y475896I-142J141D01*
G01X1739312D01*
G02X1739140Y475994I0J200D01*
G01X1738965Y476290D01*
G02X1738962Y476488I172J102D01*
G03X1739148Y477211I-1316J724D01*
G01Y477213D01*
G03X1738778Y478200I-1501J0D01*
G01Y478201D01*
X1738777D01*
G02X1738729Y478331I152J130D01*
G01Y478595D01*
G02X1738777Y478725I200J0D01*
G01X1738778Y478726D01*
G03X1739148Y479713I-1131J987D01*
G03X1737646Y481215I-1502J0D01*
G03X1736394Y480542I0J-1501D01*
G02X1736263Y480456I-166J111D01*
G01X1735939Y480396D01*
X1735860Y480414D01*
X1735827Y480438D01*
G03X1734952Y480719I-875J-1222D01*
G03X1733450Y479217I0J-1502D01*
G03X1733820Y478230I1501J0D01*
G01Y478229D01*
X1733821D01*
G02X1733869Y478099I-152J-130D01*
G01Y477835D01*
G02X1733821Y477705I-200J0D01*
G01X1733820Y477704D01*
G03X1733450Y476717I1131J-987D01*
G01Y476716D01*
G03X1733723Y475853I1502J1D01*
G01X1733755Y475807D01*
X1733763Y475696D01*
X1733573Y475332D01*
G02X1733396Y475224I-178J92D01*
G01X1732756D01*
G02X1732569Y475354I0J200D01*
G01X1732416Y475762D01*
X1732446Y475883D01*
X1732493Y475924D01*
G03X1733004Y477053I-992J1129D01*
G03X1731502Y478555I-1502J0D01*
G03X1730515Y478185I0J-1501D01*
G01X1730514D01*
Y478184D01*
G02X1730384Y478136I-130J152D01*
G01X1730120D01*
G02X1729990Y478184I0J200D01*
G01X1729989Y478185D01*
G03X1729002Y478555I-987J-1131D01*
G03X1727500Y477053I0J-1502D01*
G03X1728589Y475609I1502J0D01*
G02X1728730Y475458I-55J-192D01*
G01X1728815Y475058D01*
X1728779Y474954D01*
X1728736Y474918D01*
G03X1728652Y474841I840J-1001D01*
G01X1727115Y473303D01*
G02X1726898Y473259I-142J141D01*
G01X1726500Y473423D01*
X1726432Y473522D01*
Y473583D01*
G03X1726062Y474558I-1502J-12D01*
G01Y474559D01*
X1726061D01*
G02X1726013Y474689I152J130D01*
G01Y474953D01*
G02X1726061Y475083I200J0D01*
G01X1726062Y475084D01*
G03Y477058I-1131J987D01*
G01Y477059D01*
X1726061D01*
G02X1726013Y477189I152J130D01*
G01Y477453D01*
G02X1726061Y477583I200J0D01*
G01X1726062Y477584D01*
G03Y479558I-1131J987D01*
G01Y479559D01*
X1726061D01*
G02X1726013Y479689I152J130D01*
G01Y479953D01*
G02X1726061Y480083I200J0D01*
G01X1726062Y480084D01*
G03X1726432Y481071I-1131J987D01*
G03X1724930Y482573I-1502J0D01*
G03X1724117Y482334I0J-1502D01*
G01X1724071Y482304D01*
X1723961Y482300D01*
X1723604Y482494D01*
G02X1723500Y482670I96J176D01*
G01Y506990D01*
G02X1723515Y507067I200J1D01*
G01X1724169Y508640D01*
G02X1724212Y508705I185J-76D01*
G01X1743848Y528341D01*
X1743844Y528344D01*
X1750441Y534941D01*
G02X1750583Y535000I142J-141D01*
G01X1755417D01*
G03X1755559Y535059I0J200D01*
G01X1760441Y539941D01*
G03X1760500Y540083I-141J142D01*
G01Y543917D01*
G03X1760441Y544059I-200J0D01*
G01X1760059Y544441D01*
G03X1759917Y544500I-142J-141D01*
G01X1759293D01*
X1759273Y544504D01*
G03X1758957Y544538I-318J-1468D01*
G03X1758641Y544504I2J-1502D01*
G01X1758621Y544500D01*
X1757886D01*
G02X1757742Y544560I-1J200D01*
G03X1756089Y545258I-1653J-1608D01*
G03X1754436Y544560I0J-2306D01*
G02X1754292Y544500I-143J140D01*
G01X1743529D01*
G02X1743387Y544559I0J200D01*
G01X1742505Y545441D01*
G02X1742446Y545583I141J142D01*
G01Y916423D01*
G02X1742547Y916597I200J0D01*
G03Y919203I-747J1303D01*
G02X1742446Y919377I99J174D01*
G01Y936304D01*
G02X1742505Y936446I200J0D01*
G01X1784499Y978440D01*
G02X1784761Y978459I142J-141D01*
G03X1785663Y978158I902J1201D01*
G03X1787165Y979660I0J1502D01*
G03X1787144Y979910I-1502J0D01*
G01X1787137Y979954D01*
X1787160Y980038D01*
X1787386Y980305D01*
G02X1787539Y980376I153J-129D01*
G01X1804328D01*
X1804430Y980305D01*
X1804452Y980245D01*
G03X1807274I1411J515D01*
G01X1807296Y980305D01*
X1807398Y980376D01*
X1837677D01*
G02X1837819Y980317I0J-200D01*
G01X1838752Y979384D01*
G02X1838811Y979242I-141J-142D01*
G01Y972441D01*
G02X1838752Y972299I-200J0D01*
G01X1837999Y971546D01*
G03X1837940Y971404I141J-142D01*
G01Y967703D01*
G02X1837881Y967561I-200J0D01*
G01X1824029Y953709D01*
G03X1823970Y953567I141J-142D01*
G01Y375590D01*
G02X1823911Y375448I-200J0D01*
G01X1823882Y375419D01*
Y340689D01*
G03X1823941Y340547I200J0D01*
G01X1837825Y326663D01*
G02X1837878Y326562I-143J-140D01*
G01Y326560D01*
G02X1837882Y326523I-196J-40D01*
G01Y325609D01*
G03X1837941Y325467I200J0D01*
G01X1838727Y324681D01*
G02X1838780Y324580I-143J-140D01*
G01Y324578D01*
G02X1838784Y324541I-196J-40D01*
G01Y9379D01*
G02X1838776Y9323I-200J0D01*
G02X1838770Y9305I-193J54D01*
G01X1838755Y9269D01*
X1838095Y8609D01*
G03X1838036Y8467I141J-142D01*
G01Y5557D01*
G02X1838028Y5501I-200J0D01*
G02X1838022Y5483I-193J54D01*
G01X1838007Y5447D01*
X1835158Y2598D01*
G02X1835108Y2562I-140J142D01*
G02X1835017Y2540I-91J178D01*
G01X1757743D01*
G02X1757601Y2599I0J200D01*
G01X1756168Y4032D01*
G02X1756109Y4174I141J142D01*
G01Y10730D01*
G02X1756073Y10780I142J140D01*
G02X1756051Y10871I178J91D01*
G01Y52483D01*
G03X1755992Y52625I-200J0D01*
G01X1755208Y53409D01*
G02X1755152Y53518I141J142D01*
G01Y53566D01*
G02X1755155Y53599I200J-2D01*
G01X1755177Y53733D01*
X1755208Y53917D01*
G02X1755227Y53966I194J-47D01*
G01X1755241Y53988D01*
G02X1755314Y54051I163J-115D01*
G01X1755318Y54053D01*
X1755319Y54054D01*
G03X1760056Y61614I-3664J7560D01*
G03X1751654Y70016I-8402J0D01*
G03X1743252Y61658I0J-8402D01*
G01Y61613D01*
G03X1744073Y57990I8402J0D01*
G01X1744083Y57970D01*
X1744094Y57923D01*
G02X1744075Y57782I-195J-45D01*
G01X1744071Y57774D01*
X1744048Y57738D01*
X1744045Y57735D01*
X1743974Y57622D01*
X1743882Y57475D01*
X1743873Y57468D01*
X1743840Y57440D01*
G02X1743718Y57397I-124J157D01*
G01X1710285D01*
G03X1710143Y57338I0J-200D01*
G01X1703478Y50673D01*
G03X1703419Y50531I141J-142D01*
G01Y6503D01*
G02X1703411Y6447I-200J0D01*
G02X1703405Y6429I-193J54D01*
G01X1703390Y6394D01*
X1703362Y6364D01*
G03X1703353Y6354I143J-138D01*
G01X1703338Y6336D01*
X1703324Y6325D01*
X1703297Y6299D01*
X1703263Y6285D01*
G02X1703251Y6281I-69J188D01*
G02X1703189Y6271I-62J190D01*
G01X1655942D01*
G02X1655920Y6272I-2J200D01*
G02X1655864Y6287I23J199D01*
G01X1655832Y6301D01*
X1655805Y6327D01*
G03X1655793Y6337I-134J-149D01*
G01X1655784Y6344D01*
X1652696Y9432D01*
G02X1652660Y9482I142J140D01*
G02X1652638Y9573I178J91D01*
G01Y52286D01*
G03X1652579Y52428I-200J0D01*
G01X1651960Y53047D01*
G02X1651951Y53057I144J139D01*
G01X1651947Y53063D01*
G02X1651912Y53225I160J119D01*
G01X1651936Y53332D01*
Y53334D01*
X1651975Y53504D01*
G02X1651977Y53512I195J-45D01*
G01X1651989Y53556D01*
X1652048Y53625D01*
X1652051Y53629D01*
X1652098Y53681D01*
X1652131Y53705D01*
X1652164Y53718D01*
X1652168Y53720D01*
G03X1657693Y61614I-2877J7894D01*
G03X1640889I-8402J0D01*
G03X1640891Y61414I8402J-16D01*
G03X1642170Y57153I8400J199D01*
G01X1642186Y57129D01*
X1642201Y57104D01*
X1642216Y57080D01*
X1642233Y57024D01*
G02X1642217Y56869I-191J-59D01*
G01X1642216Y56868D01*
X1642144Y56737D01*
X1642078Y56616D01*
X1642076Y56614D01*
X1642055Y56574D01*
G02X1641877Y56467I-177J93D01*
G01X1607062D01*
G03X1606920Y56408I0J-200D01*
G01X1600745Y50233D01*
G03X1600686Y50091I141J-142D01*
G01Y3669D01*
G02X1600627Y3527I-200J0D01*
G01X1599359Y2259D01*
G02X1599217Y2200I-142J141D01*
G01X1551883D01*
G02X1551741Y2259I0J200D01*
G01X1550695Y3305D01*
G02X1550636Y3447I141J142D01*
G01Y50384D01*
G03X1550577Y50526I-200J0D01*
G01X1548446Y52657D01*
G02X1548410Y52707I142J140D01*
G02X1548388Y52798I178J91D01*
G01Y53003D01*
G02X1548395Y53054I200J-1D01*
G01X1548438Y53196D01*
G02X1548458Y53242I192J-56D01*
G01X1548471Y53263D01*
X1548476Y53267D01*
X1548504Y53294D01*
G02X1548512Y53301I136J-147D01*
G01X1548561Y53343D01*
G02X1548614Y53376I131J-151D01*
G01X1548616D01*
G02X1548628Y53381I83J-182D01*
G01X1548646Y53387D01*
X1548666Y53392D01*
G03X1555331Y61613I-1738J8221D01*
G01Y61614D01*
G03X1538527I-8402J0D01*
G01Y61610D01*
G03X1539307Y58077I8402J2D01*
G01X1539310Y58071D01*
X1539320Y58043D01*
G02X1539306Y57871I-187J-71D01*
G01X1539131Y57597D01*
G02X1539108Y57570I-163J116D01*
G01X1539061Y57523D01*
G02X1539050Y57516I-113J165D01*
G01X1539048D01*
G02X1538953Y57491I-97J175D01*
G01X1505793D01*
G03X1505651Y57432I0J-200D01*
G01X1499183Y50964D01*
G03X1499124Y50822I141J-142D01*
G01Y32943D01*
G02X1499062Y32798I-200J0D01*
G01X1498822Y32569D01*
X1498781Y32555D01*
X1498744Y32541D01*
X1498701Y32543D01*
G03X1498624Y32545I-77J-1500D01*
G01X1498621D01*
G03Y29541I0J-1502D01*
G01X1498624D01*
G03X1498700Y29543I-2J1502D01*
G01X1498741Y29545D01*
X1498793Y29526D01*
G02X1498842Y29496I-79J-184D01*
G01X1499061Y29289D01*
G02X1499124Y29144I-137J-146D01*
G01Y24943D01*
G02X1499062Y24798I-200J0D01*
G01X1498822Y24569D01*
X1498781Y24555D01*
X1498744Y24541D01*
X1498701Y24543D01*
G03X1498624Y24545I-77J-1500D01*
G01X1498621D01*
G03Y21541I0J-1502D01*
G01X1498624D01*
G03X1498700Y21543I-2J1502D01*
G01X1498741Y21545D01*
X1498793Y21526D01*
G02X1498842Y21496I-79J-184D01*
G01X1499061Y21289D01*
G02X1499124Y21144I-137J-146D01*
G01Y20943D01*
G02X1499062Y20798I-200J0D01*
G01X1498822Y20569D01*
X1498781Y20555D01*
X1498744Y20541D01*
X1498701Y20543D01*
G03X1498624Y20545I-77J-1500D01*
G01X1498621D01*
G03Y17541I0J-1502D01*
G01X1498624D01*
G03X1498700Y17543I-2J1502D01*
G01X1498741Y17545D01*
X1498793Y17526D01*
G02X1498842Y17496I-79J-184D01*
G01X1499061Y17289D01*
G02X1499124Y17144I-137J-146D01*
G01Y9332D01*
G02X1499123Y9310I-200J-2D01*
G02X1499108Y9254I-199J23D01*
G01X1499094Y9222D01*
X1499068Y9195D01*
G03X1499058Y9183I147J-133D01*
G01X1499051Y9174D01*
X1495474Y5597D01*
G02X1495424Y5561I-140J142D01*
G02X1495333Y5539I-91J178D01*
G01X1448965D01*
G02X1448943Y5540I-2J200D01*
G02X1448887Y5555I23J199D01*
G01X1448855Y5569D01*
X1448828Y5595D01*
G03X1448816Y5605I-134J-149D01*
G01X1448807Y5612D01*
X1447865Y6554D01*
G02X1447829Y6604I142J140D01*
G02X1447807Y6695I178J91D01*
G01Y30474D01*
G02X1447846Y30592I200J-1D01*
G01X1447864Y30616D01*
X1447914Y30653D01*
X1447946Y30663D01*
G03X1449007Y32113I-460J1450D01*
G03X1448994Y32316I-1521J4D01*
G01Y32318D01*
G02X1449053Y32486I198J25D01*
G01X1449201Y32630D01*
G02X1449252Y32666I139J-143D01*
G02X1449283Y32678I87J-180D01*
G01X1449330Y32692D01*
X1449379Y32682D01*
G03X1449685Y32651I311J1545D01*
G03X1450917Y33243I0J1578D01*
G01X1450921Y33248D01*
X1450926Y33254D01*
G02X1451083Y33321I150J-133D01*
G01X1451118Y33319D01*
X1451120D01*
X1451317Y33308D01*
G02X1451410Y33275I-18J-199D01*
G02X1451413Y33273I-109J-167D01*
G01X1451465Y33221D01*
X1451467Y33218D01*
X1451476Y33205D01*
G03X1452717Y32550I1241J848D01*
G03Y35554I0J1502D01*
G03X1451584Y35038I0J-1502D01*
G01X1451579Y35032D01*
X1451560Y35013D01*
G02X1451411Y34955I-141J142D01*
G01X1451409D01*
X1451284Y34961D01*
X1451282D01*
X1451182Y34967D01*
X1451181D01*
G02X1451093Y34994I13J200D01*
G01X1451073Y35006D01*
X1451038Y35040D01*
X1451025Y35061D01*
G03X1449685Y35805I-1340J-835D01*
G03X1448453Y35212I0J-1576D01*
G01X1448446Y35203D01*
X1448427Y35184D01*
G02X1448218Y35138I-141J142D01*
G01X1448144Y35165D01*
X1448142D01*
X1447940Y35237D01*
G02X1447807Y35425I67J188D01*
G01Y51408D01*
G03X1447748Y51550I-200J0D01*
G01X1446486Y52812D01*
G02X1446436Y52992I145J137D01*
G01X1446502Y53236D01*
X1446527Y53329D01*
G02X1446528Y53333I195J-47D01*
G01X1446529Y53337D01*
G02X1446535Y53357I194J-47D01*
G02X1446542Y53373I187J-72D01*
G03X1446544Y53375I-134J136D01*
G02X1446658Y53475I179J-89D01*
G01X1446659D01*
X1446673Y53480D01*
X1446680Y53482D01*
X1446684Y53483D01*
G03X1447150Y53619I-2120J8130D01*
G03X1452969Y61613I-2581J7994D01*
G01Y61614D01*
G03X1436165I-8402J0D01*
G01Y61612D01*
G03X1437265Y57456I8402J0D01*
G01X1437278Y57433D01*
X1437291Y57384D01*
Y57358D01*
G02X1437268Y57265I-200J0D01*
G01X1437157Y57071D01*
Y57069D01*
X1437091Y56956D01*
G02X1437062Y56918I-173J102D01*
G02X1437018Y56884I-143J140D01*
G01X1436996Y56872D01*
X1436972Y56865D01*
G02X1436919Y56858I-52J193D01*
G01X1402717D01*
G03X1402575Y56799I0J-200D01*
G01X1395961Y50185D01*
G03X1395902Y50043I141J-142D01*
G01Y7674D01*
G02X1395901Y7652I-200J-2D01*
G02X1395886Y7596I-199J23D01*
G01X1395872Y7564D01*
X1395846Y7537D01*
G03X1395836Y7525I147J-133D01*
G01X1395829Y7516D01*
X1395374Y7061D01*
G02X1395324Y7025I-140J142D01*
G02X1395233Y7003I-91J178D01*
G01X1298230D01*
G02X1298208Y7004I-2J200D01*
G02X1298152Y7019I23J199D01*
G01X1298120Y7033D01*
X1298093Y7059D01*
G03X1298081Y7069I-134J-149D01*
G01X1298072Y7076D01*
X1297812Y7336D01*
G02X1297776Y7386I142J140D01*
G02X1297754Y7477I178J91D01*
G01Y32003D01*
G02X1297757Y32035I200J-3D01*
G02X1297805Y32131I197J-38D01*
G01X1297881Y32215D01*
G02X1297908Y32241I151J-130D01*
G02X1297929Y32255I121J-159D01*
G01X1297938Y32260D01*
G02X1298004Y32282I95J-176D01*
G03X1297970Y35259I-220J1486D01*
G01X1297940Y35275D01*
G02X1297894Y35309I95J176D01*
G01X1297825Y35384D01*
X1297813Y35398D01*
X1297784Y35426D01*
X1297767Y35469D01*
G02X1297754Y35539I187J71D01*
G01Y53263D01*
G03X1297695Y53405I-200J0D01*
G01X1297616Y53484D01*
G02X1297565Y53573I142J141D01*
G02X1297614Y53764I193J52D01*
G01X1297645Y53796D01*
X1297685Y53812D01*
G03X1302969Y61614I-3118J7802D01*
G03X1294567Y70016I-8402J0D01*
G03X1294367Y70014I-16J-8402D01*
G03X1286165Y61687I200J-8400D01*
G01X1286164Y61613D01*
Y61612D01*
G03X1287873Y56535I8403J2D01*
G01X1287881Y56524D01*
X1287903Y56484D01*
X1287917Y56444D01*
X1287923Y56405D01*
X1287918Y56362D01*
X1287914Y56349D01*
Y56348D01*
X1287911Y56338D01*
G02X1287900Y56309I-192J56D01*
G01X1287821Y56152D01*
Y56150D01*
X1287755Y56020D01*
G02X1287718Y55969I-178J90D01*
G01X1287689Y55940D01*
G02X1287622Y55896I-141J142D01*
G01X1287588Y55882D01*
X1250130D01*
G03X1249988Y55823I0J-200D01*
G01X1247178Y53013D01*
G03X1247119Y52871I141J-142D01*
G01Y6715D01*
G02X1246919Y6515I-200J0D01*
G01X1198032D01*
G02X1198010Y6516I-2J200D01*
G02X1197954Y6531I23J199D01*
G01X1197922Y6545D01*
X1197895Y6571D01*
G03X1197883Y6581I-134J-149D01*
G01X1197874Y6588D01*
X1195469Y8993D01*
G02X1195433Y9043I142J140D01*
G02X1195411Y9134I178J91D01*
G01Y43311D01*
G02X1195415Y43348I200J-3D01*
G01Y43350D01*
G02X1195468Y43451I196J-39D01*
G01X1195547Y43530D01*
G03X1195606Y43672I-141J142D01*
G01Y49945D01*
G03X1195547Y50087I-200J0D01*
G01X1193034Y52600D01*
G02X1192987Y52807I142J141D01*
G01Y52814D01*
X1193029Y52930D01*
Y52932D01*
X1193102Y53145D01*
X1193107Y53158D01*
G02X1193186Y53249I184J-80D01*
G01X1193230Y53273D01*
X1193268Y53278D01*
G03X1200607Y61614I-1065J8336D01*
G03X1192205Y70016I-8402J0D01*
G03X1183803Y61636I0J-8402D01*
G01Y61612D01*
G03X1184904Y57455I8402J1D01*
G01X1184915Y57436D01*
G02X1184931Y57357I-184J-78D01*
G01Y57303D01*
X1184770Y57026D01*
X1184734Y56964D01*
X1184733Y56963D01*
X1184725Y56945D01*
X1184687Y56902D01*
X1184663Y56887D01*
G02X1184573Y56858I-105J170D01*
G02X1184558Y56857I-21J199D01*
G01X1148274D01*
G03X1148132Y56798I0J-200D01*
G01X1143177Y51843D01*
G03X1143118Y51701I141J-142D01*
G01Y8746D01*
Y8745D01*
G02X1143103Y8670I-200J1D01*
G01X1143102Y8668D01*
Y3585D01*
G02X1143043Y3443I-200J0D01*
G01X1142359Y2759D01*
G02X1142217Y2700I-142J141D01*
G01X1096483D01*
G02X1096341Y2759I0J200D01*
G01X1095566Y3534D01*
G02X1095507Y3676I141J142D01*
G01Y47993D01*
G03X1095448Y48135I-200J0D01*
G01X1090946Y52637D01*
G02X1090897Y52840I141J142D01*
G01X1090952Y53009D01*
Y53011D01*
X1091009Y53182D01*
G02X1091070Y53271I189J-64D01*
G01X1091166Y53315D01*
X1091189Y53319D01*
X1091194Y53320D01*
G03X1098245Y61613I-1351J8293D01*
G01Y61614D01*
G03X1089843Y70016I-8402J0D01*
G03X1081441Y61655I0J-8402D01*
G01Y61606D01*
G03X1082328Y57854I8402J6D01*
G01X1082334Y57842D01*
X1082347Y57805D01*
X1082353Y57782D01*
Y57781D01*
X1082362Y57750D01*
X1082364Y57741D01*
X1082358Y57702D01*
G02X1082332Y57630I-197J31D01*
G01X1082288Y57558D01*
Y57556D01*
X1082168Y57363D01*
G02X1082145Y57335I-166J113D01*
G01X1082115Y57305D01*
G02X1082048Y57261I-141J142D01*
G01X1082014Y57247D01*
X1046419D01*
G03X1046277Y57188I0J-200D01*
G01X1040931Y51842D01*
G03X1040872Y51700I141J-142D01*
G01Y7575D01*
G02X1040871Y7553I-200J-2D01*
G02X1040856Y7497I-199J23D01*
G01X1040842Y7465D01*
X1040816Y7438D01*
G03X1040806Y7426I147J-133D01*
G01X1040799Y7417D01*
X1039565Y6183D01*
G02X1039515Y6147I-140J142D01*
G02X1039424Y6125I-91J178D01*
G01X993953D01*
G02X993914Y6129I1J200D01*
G01X993913D01*
X993854Y6141D01*
X993823Y6155D01*
X993792Y6183D01*
X993790Y6185D01*
G03X993783Y6191I-133J-148D01*
G01X993774Y6198D01*
X991369Y8603D01*
G02X991333Y8653I142J140D01*
G02X991311Y8744I178J91D01*
G01Y51115D01*
G03X991252Y51257I-200J0D01*
G01X989628Y52881D01*
G02X989618Y52892I143J140D01*
G02X989576Y53058I155J127D01*
G01X989644Y53323D01*
Y53325D01*
X989663Y53396D01*
G02X989679Y53439I194J-48D01*
G02X989785Y53533I177J-93D01*
G01X989799Y53538D01*
X989807Y53541D01*
X989813Y53543D01*
X989814D01*
G03X995882Y61614I-2334J8071D01*
G03X987480Y70016I-8402J0D01*
G01X987461D01*
G03X979059Y61614I0J-8402D01*
G01Y61610D01*
G03X980152Y57465I8403J-1D01*
G01X980167Y57438D01*
X980179Y57380D01*
G02X980159Y57254I-197J-33D01*
G01X980081Y57120D01*
X979997Y56977D01*
X979984Y56954D01*
X979979Y56946D01*
G02X979813Y56857I-166J111D01*
G01X945539D01*
G03X945397Y56798I0J-200D01*
G01X939271Y50672D01*
G03X939212Y50530I141J-142D01*
G01Y6987D01*
G02X939211Y6969I-200J2D01*
G02X939196Y6913I-199J23D01*
G01X939182Y6881D01*
X939156Y6854D01*
G03X939146Y6842I147J-133D01*
G01X939139Y6833D01*
X938441Y6135D01*
G02X938391Y6099I-140J142D01*
G02X938300Y6077I-91J178D01*
G01X913660D01*
G03X913518Y6018I0J-200D01*
G01X910542Y3042D01*
G02X910400Y2983I-142J141D01*
G01X867500D01*
G02X867358Y3042I0J200D01*
G01X864382Y6018D01*
G03X864240Y6077I-142J-141D01*
G01X842731D01*
G02X842692Y6081I1J200D01*
G01X842691D01*
X842632Y6093D01*
X842601Y6107D01*
X842570Y6135D01*
X842568Y6137D01*
G03X842561Y6143I-133J-148D01*
G01X842552Y6150D01*
X840031Y8671D01*
G02X839995Y8721I142J140D01*
G02X839973Y8812I178J91D01*
G01Y49330D01*
G03X839914Y49472I-200J0D01*
G01X836851Y52535D01*
G02X836799Y52625I141J142D01*
G01X836798Y52626D01*
G02X836791Y52683I193J53D01*
G02X836799Y52731I200J-9D01*
G01Y52732D01*
X836802Y52741D01*
G02X836810Y52762I191J-61D01*
G01X836885Y52932D01*
Y52934D01*
X836956Y53096D01*
G02X836981Y53139I184J-78D01*
G01X837018Y53176D01*
G02X837054Y53198I122J-158D01*
G01Y53199D01*
G02X837148Y53218I85J-181D01*
G03X837466Y53212I317J8396D01*
G01X837480D01*
G03Y70016I0J8402D01*
G03X829078Y61640I0J-8402D01*
G01Y61612D01*
G03X830195Y57427I8402J1D01*
G01X830196Y57425D01*
X830222Y57328D01*
G02X830200Y57235I-200J-2D01*
G01X830030Y56943D01*
G02X829911Y56840I-180J88D01*
G01X829873Y56828D01*
X796835D01*
G03X796693Y56769I0J-200D01*
G01X790372Y50448D01*
G03X790313Y50306I141J-142D01*
G01Y7689D01*
G02X790305Y7633I-200J0D01*
G02X790299Y7615I-193J54D01*
G01X790284Y7579D01*
X787785Y5080D01*
G02X787735Y5044I-140J142D01*
G02X787644Y5022I-91J178D01*
G01X740856D01*
G02X740817Y5026I1J200D01*
G01X740816D01*
X740757Y5038D01*
X740726Y5052D01*
X740695Y5080D01*
X740693Y5082D01*
G03X740686Y5088I-133J-148D01*
G01X740677Y5095D01*
X737882Y7890D01*
G02X737846Y7940I142J140D01*
G02X737824Y8031I178J91D01*
G01Y50633D01*
G03X737765Y50775I-200J0D01*
G01X735931Y52609D01*
X735923Y52621D01*
X735922Y52623D01*
X735911Y52640D01*
G02X735891Y52686I172J102D01*
G02X735888Y52788I192J57D01*
G01X735896Y52817D01*
X736011Y53148D01*
G02X736070Y53229I186J-74D01*
G01X736071D01*
X736115Y53265D01*
G03X743526Y61614I-997J8349D01*
G03X726710I-8408J0D01*
G01Y61612D01*
G03X727824Y57431I8407J1D01*
G01X727829Y57422D01*
X727836Y57410D01*
X727846Y57377D01*
X727850Y57359D01*
G02X727827Y57220I-196J-39D01*
G01X727716Y57027D01*
X727660Y56929D01*
G02X727629Y56888I-174J99D01*
G02X727512Y56831I-141J142D01*
G01X727510D01*
G02X727486Y56829I-29J198D01*
G01X694071D01*
G03X693929Y56770I0J-200D01*
G01X687386Y50227D01*
G03X687327Y50085I141J-142D01*
G01Y5579D01*
G02X687268Y5437I-200J0D01*
G01X684873Y3042D01*
G02X684731Y2983I-142J141D01*
G01X637397D01*
G02X637255Y3042I0J200D01*
G01X635482Y4815D01*
G02X635423Y4957I141J142D01*
G01Y49307D01*
G03X635364Y49449I-200J0D01*
G01X632282Y52531D01*
G02X632229Y52719I141J141D01*
G01X632236Y52747D01*
X632275Y52835D01*
Y52836D01*
X632386Y53093D01*
G02X632449Y53173I183J-80D01*
G02X632570Y53214I121J-159D01*
G01X632575D01*
G03X632756Y53212I183J8400D01*
G03Y70016I0J8402D01*
G03X624354Y61623I0J-8402D01*
G01Y61612D01*
G03X625375Y57599I8402J1D01*
G01X625376Y57598D01*
G03X625381Y57588I7513J3750D01*
G01X625384Y57583D01*
Y57582D01*
X625415Y57525D01*
X625423Y57489D01*
G02X625425Y57476I-197J-37D01*
G01Y57424D01*
X625418Y57372D01*
G02X625393Y57299I-198J27D01*
G01X625239Y57034D01*
Y57033D01*
G02X625076Y56934I-173J101D01*
G01X590496D01*
G03X590354Y56875I0J-200D01*
G01X583442Y49963D01*
G03X583383Y49821I141J-142D01*
G01Y7678D01*
G02X583382Y7660I-200J2D01*
G02X583367Y7604I-199J23D01*
G01X583353Y7572D01*
X583327Y7545D01*
G03X583317Y7533I147J-133D01*
G01X583310Y7524D01*
X581916Y6130D01*
G02X581866Y6094I-140J142D01*
G02X581775Y6072I-91J178D01*
G01X535494D01*
G02X535455Y6076I1J200D01*
G01X535454D01*
X535395Y6088D01*
X535364Y6102D01*
X535333Y6130D01*
X535331Y6132D01*
G03X535324Y6138I-133J-148D01*
G01X535315Y6145D01*
X534015Y7445D01*
G02X533979Y7495I142J140D01*
G02X533957Y7586I178J91D01*
G01Y51258D01*
G03X533898Y51400I-200J0D01*
G01X532452Y52846D01*
G02X532399Y53034I141J141D01*
G01X532407Y53066D01*
X532457Y53254D01*
Y53255D01*
X532476Y53329D01*
G02X532526Y53412I191J-59D01*
G01X532591Y53477D01*
G02X532631Y53508I142J-141D01*
G01X532653Y53521D01*
X532678Y53528D01*
G03X538796Y61614I-2285J8086D01*
G03X521992I-8402J0D01*
G03X521994Y61414I8402J-16D01*
G03X523519Y56784I8400J201D01*
G01X523526Y56774D01*
G02X523556Y56681I-170J-106D01*
G01X523559Y56627D01*
X523369Y56262D01*
X523365Y56253D01*
G02X523295Y56183I-172J102D01*
G01X523272Y56169D01*
X523247Y56162D01*
G02X523192Y56154I-56J192D01*
G01X487317D01*
G03X487175Y56095I0J-200D01*
G01X483071Y51991D01*
G03X483012Y51849I141J-142D01*
G01Y8543D01*
G02X483004Y8487I-200J0D01*
G02X482998Y8469I-193J54D01*
G01X482983Y8433D01*
X480029Y5479D01*
G02X479979Y5443I-140J142D01*
G02X479888Y5421I-91J178D01*
G01X386937D01*
G02X386898Y5425I1J200D01*
G01X386897D01*
X386838Y5437D01*
X386807Y5451D01*
X386776Y5479D01*
X386774Y5481D01*
G03X386767Y5487I-132J-147D01*
G01X386758Y5494D01*
X384157Y8095D01*
G02X384121Y8145I142J140D01*
G02X384099Y8236I178J91D01*
G01Y29062D01*
G02X384132Y29172I200J0D01*
G01X384147Y29195D01*
X384189Y29231D01*
X384218Y29244D01*
G03X384219Y31992I-605J1374D01*
G01X384218D01*
X384216Y31993D01*
G02X384131Y32066I83J182D01*
G01X384115Y32090D01*
X384107Y32118D01*
G02X384099Y32174I192J56D01*
G01Y32212D01*
G02X384132Y32322I200J0D01*
G01X384147Y32345D01*
X384189Y32381D01*
X384218Y32394D01*
G03X384219Y35142I-605J1374D01*
G01X384218D01*
X384216Y35143D01*
G02X384131Y35216I83J182D01*
G01X384115Y35240D01*
X384107Y35268D01*
G02X384099Y35324I192J56D01*
G01Y50301D01*
X384100Y50302D01*
X381720Y52682D01*
G02X381670Y52861I145J137D01*
G01Y52864D01*
X381681Y52903D01*
X381779Y53218D01*
Y53219D01*
G02X381837Y53308I191J-61D01*
G01X381857Y53325D01*
X381906Y53349D01*
X381933Y53354D01*
G03X388796Y61614I-1539J8260D01*
G03X380394Y70016I-8402J0D01*
G03X371992Y61630I0J-8402D01*
G01Y61613D01*
G03X373515Y56789I8402J0D01*
G01X373518Y56785D01*
X373547Y56741D01*
G02X373566Y56560I-168J-109D01*
G02X373548Y56524I-187J71D01*
G01X373539Y56511D01*
X373508Y56475D01*
X373502Y56468D01*
X373492Y56457D01*
X373461Y56423D01*
X373459Y56421D01*
G03X373427Y56377I144J-139D01*
G01X373357Y56240D01*
X373334Y56217D01*
X373306Y56188D01*
X373269Y56172D01*
G02X373213Y56157I-79J184D01*
G02X373191Y56156I-20J199D01*
G01X348436D01*
G03X348294Y56097I0J-200D01*
G01X345613Y53416D01*
G02X345563Y53380I-140J142D01*
G02X345472Y53358I-91J178D01*
G01X339900D01*
G03X339758Y53299I0J-200D01*
G01X335490Y49031D01*
G03X335431Y48889I141J-142D01*
G01Y4972D01*
G02X335423Y4916I-200J0D01*
G02X335417Y4898I-193J54D01*
G01X335402Y4862D01*
X334097Y3557D01*
G02X334047Y3521I-140J142D01*
G02X333956Y3499I-91J178D01*
G01X333412D01*
G03X333270Y3440I0J-200D01*
G01X332278Y2448D01*
G02X332228Y2412I-140J142D01*
G02X332137Y2390I-91J178D01*
G01X281834D01*
G02X281778Y2398I0J200D01*
G02X281760Y2404I54J193D01*
G01X281724Y2419D01*
X278233Y5910D01*
G02X278197Y5960I142J140D01*
G02X278175Y6051I178J91D01*
G01Y15609D01*
G02X278179Y15646I200J-3D01*
G01Y15648D01*
G02X278232Y15749I196J-39D01*
G01X280235Y17752D01*
G03X280287Y17843I-142J141D01*
G01Y17844D01*
X280296Y17878D01*
X280315Y17907D01*
G02X280356Y17951I165J-113D01*
G01X280633Y18152D01*
G02X280708Y18186I118J-161D01*
G01X280747Y18194D01*
X280815Y18184D01*
X280830Y18179D01*
G03X281270Y18111I447J1434D01*
G01X281297D01*
G03Y21115I-19J1502D01*
G01X281276D01*
G03X280830Y21047I1J-1502D01*
G01X280815Y21042D01*
X280781Y21037D01*
X280747D01*
G02X280688Y21046I0J200D01*
G01X280657Y21056D01*
X280404Y21240D01*
X280375Y21261D01*
X280373Y21263D01*
X280366Y21267D01*
G02X280313Y21334I127J155D01*
G01Y21335D01*
G02X280292Y21424I179J89D01*
G01Y50478D01*
G03X280233Y50620I-200J0D01*
G01X278308Y52545D01*
G02X278251Y52713I141J142D01*
G01X278255Y52740D01*
X278388Y53098D01*
G02X278514Y53212I184J-77D01*
G01X278557Y53221D01*
G03X286442Y61614I-524J8393D01*
G03X269622I-8410J0D01*
G03X271431Y56403I8410J0D01*
G01X271436Y56397D01*
G02X271454Y56192I-162J-118D01*
G01X271318Y55910D01*
G02X271281Y55857I-180J86D01*
G02X271278Y55854I-143J140D01*
G01X271245Y55821D01*
G02X271178Y55777I-141J142D01*
G01X271144Y55763D01*
X235884D01*
G03X235742Y55704I0J-200D01*
G01X230527Y50489D01*
G03X230468Y50347I141J-142D01*
G01Y8233D01*
G02X230467Y8215I-200J2D01*
G02X230452Y8159I-199J23D01*
G01X230438Y8127D01*
X230412Y8100D01*
G03X230402Y8088I147J-133D01*
G01X230395Y8079D01*
X228185Y5869D01*
G02X228135Y5833I-140J142D01*
G02X228044Y5811I-91J178D01*
G01X181012D01*
G02X180973Y5815I1J200D01*
G01X180972D01*
X180913Y5827D01*
X180882Y5841D01*
X180851Y5869D01*
X180849Y5871D01*
G03X180842Y5877I-132J-147D01*
G01X180833Y5884D01*
X178492Y8225D01*
G02X178456Y8275I142J140D01*
G02X178434Y8366I178J91D01*
G01Y52949D01*
G03X178390Y53074I-200J0D01*
G01X178386Y53079D01*
G02X178351Y53154I160J120D01*
G01X178340Y53198D01*
X178366Y53322D01*
Y53324D01*
X178423Y53579D01*
G02X178450Y53641I194J-48D01*
G01X178462Y53657D01*
G02X178512Y53701I155J-126D01*
G01X178543Y53719D01*
X178560Y53725D01*
G03X184071Y61614I-2891J7889D01*
G03X175669Y70016I-8402J0D01*
G03X167267Y61623I0J-8402D01*
G01Y61613D01*
G03X168538Y57170I8402J0D01*
G01X168541Y57165D01*
X168552Y57143D01*
Y57011D01*
G02X168527Y56915I-200J1D01*
G01X168395Y56674D01*
G02X168361Y56629I-175J97D01*
G01X168300Y56568D01*
X168284Y56559D01*
X168260Y56552D01*
G02X168207Y56545I-52J193D01*
G01X133379D01*
G03X133237Y56486I0J-200D01*
G01X128150Y51399D01*
G03X128091Y51257I141J-142D01*
G01Y7583D01*
G02X128090Y7565I-200J2D01*
G02X128075Y7509I-199J23D01*
G01X128061Y7477D01*
X128035Y7450D01*
G03X128025Y7438I149J-134D01*
G01X128018Y7429D01*
X126198Y5609D01*
G02X126148Y5573I-140J142D01*
G02X126057Y5551I-91J178D01*
G01X77932D01*
G02X77790Y5610I0J200D01*
G01X76759Y6641D01*
G02X76700Y6783I141J142D01*
G01Y46017D01*
G03X76641Y46159I-200J0D01*
G01X69859Y52941D01*
G03X69717Y53000I-142J-141D01*
G01X32583D01*
G03X32441Y52941I0J-200D01*
G01X28459Y48959D01*
G03X28400Y48817I141J-142D01*
G01Y5215D01*
G02X28331Y5064I-200J0D01*
G01X25940Y2996D01*
G02X25817Y2947I-131J151D01*
G01X6947Y2145D01*
G02X6797Y2203I-9J200D01*
G01X2759Y6241D01*
G02X2700Y6383I141J142D01*
G01Y107055D01*
G02X2824Y107240I200J0D01*
G01X2880Y107264D01*
X2998Y107240D01*
X6697Y103541D01*
G02X6738Y103481I-142J-141D01*
G01X6743Y103470D01*
G02X6725Y103295I-188J-69D01*
G01Y103294D01*
G03X6498Y102500I1275J-794D01*
G03X7818Y101009I1502J0D01*
G02X7945Y100943I-23J-199D01*
G01X7968Y100916D01*
X7994Y100848D01*
Y98838D01*
G02X7993Y98818I-200J0D01*
G02X7938Y98699I-199J20D01*
G01X6369Y97131D01*
G03X5694Y95501I1631J-1630D01*
G01Y93199D01*
G03X6369Y91569I2306J0D01*
G01X7807Y90131D01*
G02X7865Y89984I-142J-141D01*
G01X7856Y89691D01*
G02X7838Y89613I-200J5D01*
G01X7821Y89577D01*
X7790Y89549D01*
G03X7284Y88425I995J-1124D01*
G03X8786Y86923I1502J0D01*
G03X10094Y87687I0J1502D01*
G02X10188Y87772I174J-98D01*
G01X10307Y87818D01*
X10308D01*
G02X10435Y87824I72J-186D01*
G03X11197Y87694I763J2176D01*
G01X11299D01*
G03X12786Y86401I1487J209D01*
G03X12986Y86414I3J1502D01*
G03X14244Y87542I-200J1489D01*
G01X14246Y87552D01*
G02X14426Y87694I192J-58D01*
G01X18000D01*
G03X20306Y90000I0J2306D01*
G01Y90002D01*
G03X20048Y91061I-2306J-1D01*
G02X20038Y91224I177J93D01*
G02X20054Y91258I188J-68D01*
G01X20232Y91550D01*
G02X20403Y91646I171J-104D01*
G01X41510D01*
G02X41624Y91611I1J-200D01*
G02X41640Y91598I-118J-162D01*
G01X44357Y88881D01*
G03X45987Y88206I1630J1631D01*
G01X45988D01*
G03X48294Y90512I0J2306D01*
G03X48293Y90586I-2306J6D01*
G01Y90587D01*
G02X48338Y90718I200J5D01*
G01X48503Y90922D01*
G02X48624Y90993I155J-126D01*
G03X48949Y91089I-260J1480D01*
G01X48967Y91097D01*
X49043Y91113D01*
G02X49143Y91087I1J-200D01*
G01X49195Y91044D01*
G02X49244Y90913I-151J-131D01*
G01Y90615D01*
G03X53856I2306J0D01*
G01Y92398D01*
G03X53181Y94028I-2306J0D01*
G01X49816Y97393D01*
G03X48186Y98068I-1630J-1631D01*
G01X37034D01*
X37033D01*
G02X36851Y98187I1J200D01*
G01X36847Y98198D01*
G03X34037I-1405J-531D01*
G01X34033Y98187D01*
G02X33851Y98068I-183J81D01*
G01X28180D01*
X28179D01*
G02X27997Y98187I1J200D01*
G01X27993Y98198D01*
G03X25183I-1405J-531D01*
G01X25179Y98187D01*
G02X24997Y98068I-183J81D01*
G01X20276D01*
G02X20162Y98103I-1J200D01*
G02X20146Y98116I118J162D01*
G01X19631Y98631D01*
G03X18001Y99306I-1630J-1631D01*
G01X13011D01*
G02X12938Y99320I0J200D01*
G01X12899Y99335D01*
X12666Y99563D01*
G02X12659Y99570I138J145D01*
G02X12606Y99698I147J136D01*
G01Y103201D01*
G03X11931Y104831I-2306J0D01*
G01X8668Y108094D01*
G02X8632Y108144I142J140D01*
G02X8610Y108235I178J91D01*
G01Y111943D01*
G02X8733Y112127I200J-1D01*
G01X8734D01*
G02X8848Y112139I77J-185D01*
G01X8877Y112133D01*
X8929Y112105D01*
X9380Y111654D01*
G03X10302Y111272I923J924D01*
G01X23069D01*
G02X23110Y111268I1J-200D01*
G02X23210Y111214I-41J-196D01*
G01X28786Y105637D01*
G03X29710Y105254I924J923D01*
G01X34417D01*
G02X34433Y105253I-4J-200D01*
G02X34498Y105237I-15J-199D01*
G01X34509Y105231D01*
G03X34572Y105201I677J1340D01*
G02X34603Y105183I-85J-182D01*
G02X34554Y104829I-114J-165D01*
G03X33546Y103411I493J-1418D01*
G03X36550I1502J0D01*
G03X35682Y104772I-1501J0D01*
G02X35701Y105143I84J182D01*
G03X35905Y105231I-491J1419D01*
G01X35916Y105237D01*
G02X35981Y105253I80J-183D01*
G02X35997Y105254I20J-199D01*
G01X54680D01*
G02X54718Y105250I-2J-200D01*
G02X54820Y105197I-37J-196D01*
G01X60392Y99625D01*
G02X60435Y99408I-142J-141D01*
G01X60426Y99386D01*
X60412Y99351D01*
X60361Y99317D01*
G02X60251Y99284I-110J167D01*
G01X58478D01*
G02X58460Y99285I2J200D01*
G02X58338Y99341I18J199D01*
G01X57678Y100002D01*
X57354Y100326D01*
G02X57308Y100396I141J143D01*
G01X57305Y100407D01*
G03X55871Y101463I-1434J-446D01*
G03X54369Y99961I0J-1502D01*
G03X55424Y98527I1502J0D01*
G01X55425D01*
X55436Y98524D01*
G02X55506Y98478I-73J-187D01*
G01X55803Y98181D01*
G02X55842Y97997I-153J-129D01*
G01X55746Y97703D01*
G02X55685Y97614I-189J64D01*
G01X55592Y97534D01*
X55543Y97511D01*
X55517Y97507D01*
G03X53614Y95236I404J-2271D01*
G03X53703Y94602I2307J1D01*
G03X54290Y93604I2218J633D01*
G01X58556Y89338D01*
G03X60187Y88662I1632J1631D01*
G01X78755D01*
G02X78939Y88539I-1J-200D01*
G01Y88538D01*
G02X78951Y88424I-185J-77D01*
G01X78945Y88395D01*
X78917Y88343D01*
X78576Y88002D01*
G03X78194Y87080I924J-923D01*
G01Y76624D01*
G02X78191Y76588I-200J-1D01*
G02X78136Y76483I-197J36D01*
G01X73998Y72346D01*
G02X73857Y72288I-141J142D01*
G01X8061D01*
G02X8045Y72289I4J200D01*
G02X7980Y72305I15J199D01*
G01X7969Y72311D01*
G03X7271Y72483I-698J-1330D01*
G03Y69479I0J-1502D01*
G03X7969Y69651I0J1502D01*
G01X7995Y69664D01*
X8037Y69674D01*
X54528D01*
X54535D01*
G02X54700Y69576I-7J-200D01*
G02X54706Y69565I-173J-101D01*
G01X54869Y69245D01*
G02X54861Y69054I-180J-88D01*
G01X54851Y69040D01*
G03X58240Y63021I3082J-2229D01*
G03X61014Y69040I-307J3790D01*
G01X61013Y69041D01*
G02X60977Y69141I163J115D01*
G01X60974Y69170D01*
X60985Y69223D01*
X61160Y69565D01*
G02X61330Y69674I178J-91D01*
G01X68972D01*
G02X69165Y69525I0J-200D01*
G01X69214Y69338D01*
X69266Y69142D01*
G02X69169Y68926I-196J-42D01*
G03X64905Y61614I4137J-7312D01*
G03X81709I8402J0D01*
G03X75812Y69634I-8402J0D01*
G01X75810D01*
X75807Y69635D01*
G02X75724Y69688I63J190D01*
G01X75707Y69706D01*
X75683Y69750D01*
X75672Y69792D01*
X75592Y70119D01*
G02X75604Y70235I196J38D01*
G01X75612Y70252D01*
G02X75646Y70298I176J-95D01*
G01X80424Y75076D01*
G03X80806Y75998I-924J923D01*
G01Y86454D01*
G02X80817Y86519I200J0D01*
G02X80864Y86595I189J-65D01*
G01X104324Y110054D01*
G03X104706Y110976I-924J923D01*
G01Y132479D01*
G02X104720Y132554I200J1D01*
G02X104764Y132620I185J-76D01*
G01X151163Y179018D01*
G02X151371Y179064I141J-142D01*
G01X151380Y179060D01*
G02X151472Y178985I-75J-185D01*
G01X151487Y178962D01*
X151504Y178907D01*
Y173435D01*
G02X151494Y173372I-200J-1D01*
G02X151446Y173294I-190J63D01*
G01X130557Y152406D01*
G03X130174Y151482I923J-924D01*
G01Y144552D01*
G02X130173Y144536I-200J4D01*
G02X130157Y144471I-199J15D01*
G01X130151Y144460D01*
G03X130058Y144242I1331J-697D01*
G03X130057Y144240I176J-89D01*
G03X130051Y144222I1422J-484D01*
G03X130047Y144209I1434J-448D01*
G01Y144208D01*
X130044Y144197D01*
G02X129998Y144127I-187J73D01*
G01X124129Y138258D01*
G03X123746Y137334I923J-924D01*
G01Y127770D01*
Y127765D01*
G02X123690Y127631I-200J5D01*
G02X123675Y127617I-144J139D01*
G01X123441Y127420D01*
G02X123362Y127380I-128J154D01*
G01X123320Y127369D01*
X123276Y127377D01*
G03X122867Y127414I-412J-2270D01*
G03X120560Y125107I0J-2307D01*
G01Y121306D01*
G02X120466Y121137I-200J1D01*
G01X120180Y120957D01*
G02X120084Y120926I-107J169D01*
G01X120033Y120924D01*
X119987Y120946D01*
G03X119333Y121096I-654J-1351D01*
G03X117831Y119594I0J-1502D01*
G03X118377Y118435I1503J0D01*
G01X118394Y118422D01*
X118421Y118388D01*
X118467Y118293D01*
G02X118487Y118206I-180J-87D01*
G01Y117982D01*
G02X118467Y117895I-200J0D01*
G01X118421Y117800D01*
X118394Y117766D01*
X118377Y117753D01*
G03X117831Y116594I957J-1159D01*
G03X119333Y115092I1502J0D01*
G01Y115091D01*
G03X120356Y115493I0J1503D01*
G01X120387Y115523D01*
X120388Y115524D01*
X120429Y115538D01*
G02X120515Y115547I63J-190D01*
G01X120665Y115530D01*
X120667D01*
X120817Y115512D01*
G02X120899Y115484I-22J-199D01*
G01X120934Y115462D01*
X120959Y115427D01*
Y115425D01*
G03X121236Y115092I1904J1302D01*
G01X126335Y109994D01*
X130846Y105482D01*
G02X130859Y105466I-149J-134D01*
G02X130894Y105352I-165J-113D01*
G01Y95111D01*
G03X135506I2306J0D01*
G01Y105054D01*
G02X135706Y105254I200J0D01*
G01X136779D01*
G02X136795Y105253I-4J-200D01*
G02X136860Y105237I-15J-199D01*
G01X136871Y105231D01*
G03X136934Y105201I677J1340D01*
G02X136965Y105183I-85J-182D01*
G02X136916Y104829I-114J-165D01*
G03X135908Y103411I493J-1418D01*
G03X138912I1502J0D01*
G03X138311Y104612I-1502J-1D01*
G01X138291Y104627D01*
X138260Y104665D01*
X138250Y104687D01*
G02X138232Y104782I182J84D01*
G01X138246Y105065D01*
G02X138274Y105156I200J-12D01*
G01X138332Y105253D01*
X138364Y105287D01*
X138384Y105299D01*
G03X139071Y106561I-816J1262D01*
G03X137569Y108063I-1502J0D01*
G03X136871Y107891I0J-1502D01*
G01X136845Y107878D01*
X136803Y107868D01*
X136214D01*
G02X136123Y107890I0J200D01*
G02X136073Y107926I90J178D01*
G01X126418Y117581D01*
G02X126382Y117631I142J140D01*
G02X126360Y117722I178J91D01*
G01Y136710D01*
G02X126364Y136748I200J-2D01*
G02X126417Y136850I196J-37D01*
G01X131846Y142279D01*
G02X131916Y142325I143J-141D01*
G01X131927Y142328D01*
G03X132983Y143762I-446J1434D01*
G03X132811Y144460I-1502J0D01*
G01X132798Y144486D01*
X132788Y144528D01*
Y150858D01*
G02X132792Y150896I200J-2D01*
G02X132845Y150998I196J-37D01*
G01X153734Y171887D01*
G03X154116Y172809I-924J923D01*
G01Y293642D01*
G02X154125Y293701I200J0D01*
G02X154174Y293783I191J-59D01*
G01X164582Y304191D01*
X170580Y310188D01*
G02X170650Y310234I143J-141D01*
G01X170661Y310237D01*
G03X171717Y311671I-446J1434D01*
G03X170215Y313173I-1502J0D01*
G03X168781Y312118I0J-1502D01*
G01Y312117D01*
X168778Y312106D01*
G02X168732Y312036I-187J73D01*
G01X166538Y309842D01*
G02X166365Y309787I-140J142D01*
G01X166027Y309855D01*
G02X165891Y309962I44J195D01*
G01X165886Y309974D01*
G03X164496Y310907I-1390J-569D01*
G03X164296Y310894I-3J-1502D01*
G03X163446Y310479I200J-1489D01*
G03X163062Y309852I1050J-1074D01*
G01Y309851D01*
X163059Y309840D01*
G02X163013Y309770I-187J73D01*
G01X152097Y298854D01*
G02X151880Y298811I-141J142D01*
G01X151858Y298820D01*
X151823Y298834D01*
X151789Y298885D01*
G02X151756Y298995I167J110D01*
G01Y351850D01*
G03X151081Y353480I-2306J0D01*
G01X121854Y382707D01*
G02X121841Y382723I149J134D01*
G02X121806Y382837I165J113D01*
G01Y385002D01*
G03X121131Y386632I-2306J0D01*
G01X108416Y399347D01*
G02X108403Y399363I149J134D01*
G02X108368Y399477I165J113D01*
G01Y413600D01*
G02X108568Y413800I200J0D01*
G01X110215D01*
G03X110415Y414000I0J200D01*
G01Y428770D01*
G02X110419Y428807I200J-3D01*
G01Y428809D01*
G02X110472Y428910I196J-39D01*
G01X118869Y437307D01*
G02X118975Y437361I140J-143D01*
G01X118977D01*
G02X119009Y437364I35J-197D01*
G01X128954D01*
G02X129073Y437325I0J-200D01*
G02X129084Y437316I-121J-159D01*
G01X129174Y437042D01*
X129426Y436275D01*
G03X130347Y434758I3730J1227D01*
G01X132211Y432850D01*
G03X132889Y432296I2808J2745D01*
G03X133541Y431957I2129J3299D01*
G01X136329Y430823D01*
X136650Y430692D01*
G02X136652Y430642I-198J-33D01*
G01X136650Y430619D01*
X136605Y430501D01*
Y430499D01*
G03X136583Y430441I1674J-668D01*
G01Y430439D01*
G03X136569Y430397I1703J-591D01*
G01Y430395D01*
G03X136559Y430363I1715J-553D01*
G01X136550Y430333D01*
X136543Y430306D01*
G03X136537Y430281I1750J-433D01*
G01Y430279D01*
G03X136488Y429860I1753J-417D01*
G01Y426460D01*
G03X140092I1802J0D01*
G01Y428420D01*
G02X140215Y428604I200J-1D01*
G01X140308D01*
G02X140340Y428601I-3J-200D01*
G01X140342D01*
G02X140448Y428547I-34J-197D01*
G01X140919Y428076D01*
G03X141509Y427591I2754J2749D01*
G01X144041Y425900D01*
X147053Y423887D01*
G02X147121Y423631I-111J-167D01*
G01X147118Y423625D01*
X147116Y423622D01*
G03X146890Y422760I1576J-874D01*
G01Y419347D01*
G03X150494I1802J0D01*
G01Y421214D01*
G02X150515Y421303I200J0D01*
G01Y421304D01*
G02X150588Y421384I179J-90D01*
G01X150600Y421390D01*
X150610Y421396D01*
G02X150643Y421408I85J-181D01*
G01X150684Y421419D01*
X150726Y421412D01*
G02X150804Y421381I-33J-197D01*
G01X151255Y421082D01*
X151263Y421077D01*
X152485Y420103D01*
X153084Y419625D01*
X154729Y418314D01*
X154731D01*
X154781Y418274D01*
G02X154798Y418259I-124J-157D01*
G01X175945Y397112D01*
G02X175988Y397048I-141J-141D01*
G01X176004Y397010D01*
Y396869D01*
X175988Y396832D01*
G03X175867Y396242I1381J-591D01*
G01Y396240D01*
G03X177339Y394738I1502J0D01*
G01X177367D01*
G03X177759Y394789I4J1502D01*
G03X177839Y394813I-392J1450D01*
G03X177996Y394875I-472J1426D01*
G01X178021Y394887D01*
X178049Y394891D01*
G02X178222Y394835I32J-197D01*
G01X181878Y391179D01*
G03X182020Y391120I142J141D01*
G01X197527D01*
G02X197568Y391115I-4J-200D01*
G01X201715Y389042D01*
G02X201771Y388990I-106J-170D01*
G01X201788Y388966D01*
X201796Y388918D01*
G03X203279Y387651I1484J236D01*
G01X203281D01*
G03X203415Y387658I-11J1502D01*
G01X203457Y387662D01*
G03X204409Y388162I-177J1494D01*
G02X204476Y388212I150J-132D01*
G01X204480Y388214D01*
X209382D01*
X209411Y388202D01*
X209438Y388174D01*
X209459Y388153D01*
G03X210577Y387651I1122J1003D01*
G01X210581D01*
G03X210854Y387676I0J1502D01*
G01X210881D01*
G03X213014Y387068I2099J3319D01*
G01X213015D01*
G03X214676Y387453I-35J3927D01*
G01X214724Y387476D01*
G02X214828Y387486I70J-187D01*
G01X214833Y387485D01*
X221381Y380937D01*
G02X221434Y380836I-143J-140D01*
G01Y380834D01*
G02X221438Y380797I-196J-40D01*
G01Y380442D01*
G02X221419Y380358I-200J1D01*
G01Y380357D01*
G03X221294Y379800I1181J-558D01*
G01Y265281D01*
G02X221235Y265139I-200J0D01*
G01X219796Y263699D01*
X218379Y262282D01*
G02X218334Y262249I-140J143D01*
G02X218289Y262232I-93J177D01*
G02X218241Y262226I-49J194D01*
G01X212185D01*
G03X212043Y262167I0J-200D01*
G01X211554Y261678D01*
X211542Y261669D01*
G03X211509Y261644I772J-1054D01*
G03X211394Y261542I808J-1027D01*
G01X207996Y258144D01*
G02X207923Y258130I-73J186D01*
G01X190458D01*
G02X190402Y258138I0J200D01*
G02X190384Y258144I54J193D01*
G01X190348Y258159D01*
X188863Y259644D01*
G03X188721Y259703I-142J-141D01*
G01X188256D01*
X188232Y259709D01*
G03X188191Y259718I-301J-1271D01*
G01X188189D01*
G03X187919Y259746I-269J-1278D01*
G01X185265D01*
G03X184995Y259718I-1J-1306D01*
G01X184993D01*
G03X184952Y259709I260J-1280D01*
G01X184928Y259703D01*
X184819D01*
G03X184677Y259644I0J-200D01*
G01X184595Y259562D01*
X184575Y259550D01*
G03X184345Y259368I691J-1109D01*
G03X184338Y259361I920J-927D01*
G01X182729Y257752D01*
X182703Y257744D01*
G03X182107Y257405I425J-1441D01*
G03X181626Y256305I1022J-1102D01*
G01Y256300D01*
G03X181633Y256154I1502J-1D01*
G01X181634Y256144D01*
X181632Y256106D01*
G02X181581Y255990I-199J18D01*
G01X181412Y255800D01*
X181380Y255764D01*
G02X181294Y255714I-140J142D01*
G01X181292Y255713D01*
X181261Y255704D01*
X179195D01*
G02X179120Y255719I1J200D01*
G01X179082Y255734D01*
X179054Y255763D01*
X175064Y259753D01*
X175061Y259757D01*
G03X174532Y260086I-913J-879D01*
G01X174528Y260088D01*
X174496Y260100D01*
X174484Y260103D01*
G03X174476Y260105I-53J-193D01*
G01X174461Y260108D01*
G03X174267Y260142I-315J-1228D01*
G01X174246Y260146D01*
X174238Y260148D01*
G03X173921Y260186I-313J-1268D01*
G01X161092D01*
X161077Y260194D01*
G03X160349Y260382I-728J-1316D01*
G03Y257378I0J-1502D01*
G03X161077Y257566I0J1504D01*
G01X161092Y257574D01*
X173297D01*
G02X173333Y257571I1J-200D01*
G02X173438Y257516I-36J-197D01*
G01X177479Y253474D01*
G03X178059Y253138I923J925D01*
G01X178085Y253131D01*
X178105Y253119D01*
G02X178146Y253088I-99J-174D01*
G01X180302Y250931D01*
X180305Y250927D01*
G03X180875Y250584I916J877D01*
G01X180886Y250582D01*
X180897Y250579D01*
G03X181219Y250536I327J1225D01*
G01X189643D01*
G02X189816Y250423I-7J-200D01*
G01X189914Y250179D01*
Y250177D01*
X189953Y250083D01*
G02X189959Y249986I-191J-60D01*
G01X189956Y249972D01*
G02X189910Y249887I-194J50D01*
G02X189900Y249877I-146J136D01*
G03X189421Y248765I1051J-1112D01*
G03X190952Y247234I1531J0D01*
G03X191930Y247587I0J1531D01*
G01X191957Y247609D01*
X191990Y247621D01*
G02X192058Y247633I68J-188D01*
G01X192097D01*
G03X192153Y247641I0J200D01*
G01X192167Y247644D01*
X192379D01*
G02X192504Y247600I0J-200D01*
G01X192505Y247599D01*
G03X192508Y247597I834J1248D01*
G03X192526Y247583I931J1178D01*
G02X192536Y247575I-120J-160D01*
G03X192539Y247572I1060J1057D01*
G03X192626Y247510I915J1192D01*
G01X192630Y247508D01*
X192661Y247487D01*
X192675Y247479D01*
G03X192949Y247349I777J1285D01*
G03X192952Y247348I64J186D01*
G01X192956Y247347D01*
X192961Y247345D01*
X192967Y247343D01*
G03X193372Y247265I484J1422D01*
G03X193449Y247263I77J1499D01*
G01X193452D01*
G03X193515Y247264I8J1502D01*
G01X193532Y247265D01*
G03X194386Y247589I-81J1500D01*
G01X194387Y247590D01*
X194399Y247600D01*
G02X194505Y247633I110J-167D01*
G01X194597D01*
G03X194680Y247651I0J200D01*
G01X194734Y247676D01*
G02X194812Y247695I85J-181D01*
G02X194846Y247693I5J-200D01*
G02X194950Y247645I-28J-198D01*
G01X194951Y247644D01*
G03X195950Y247263I1000J1122D01*
G01X195952D01*
G03X197454Y248765I0J1502D01*
G03X197021Y249820I-1502J0D01*
G01X197020Y249821D01*
X196996Y249846D01*
X196969Y249904D01*
G02X196965Y249914I184J79D01*
G01X196949Y249954D01*
G02X196950Y250077I191J60D01*
G01X197013Y250236D01*
X197021Y250256D01*
Y250258D01*
X197087Y250418D01*
G02X197090Y250425I185J-75D01*
G02X197257Y250536I179J-89D01*
G01X201949D01*
G02X201981Y250533I-3J-200D01*
G01X201983D01*
G02X202089Y250479I-34J-197D01*
G01X202392Y250176D01*
G02X202410Y250155I-142J-140D01*
G01Y228983D01*
G02X202405Y228976I-165J113D01*
G01X202396Y228965D01*
X201083Y227652D01*
G03X200802Y227225I896J-896D01*
G02X200792Y227203I-187J72D01*
G01X200775Y227172D01*
G03X200510Y226384I1041J-789D01*
G01Y222748D01*
G02X200419Y222680I-160J120D01*
G01X200248Y222617D01*
X200066Y222550D01*
G02X200036Y222542I-66J189D01*
G02X199945Y222545I-39J196D01*
G01X199916Y222553D01*
X199864Y222586D01*
X199844Y222610D01*
G03X198695Y223144I-1149J-969D01*
G03X197193Y221642I0J-1502D01*
G03X198519Y220150I1502J0D01*
G01X198577Y220144D01*
G03X198695Y220139I123J1498D01*
G03X199835Y220663I-1J1503D01*
G01X199840Y220669D01*
X199857Y220686D01*
G02X199982Y220744I142J-141D01*
G02X200067Y220732I15J-199D01*
G01X200109Y220717D01*
X200418Y220604D01*
G02X200460Y220583I-68J-188D01*
G02X200510Y220536I-110J-167D01*
G01Y216980D01*
G03X200892Y216058I1306J1D01*
G01X208467Y208483D01*
X208492Y208441D01*
X208499Y208418D01*
G03X211369I1435J446D01*
G01X211376Y208441D01*
X211401Y208483D01*
X214042Y211124D01*
G03X214424Y212046I-924J923D01*
G01Y216313D01*
G02X214451Y216343I161J-118D01*
G01X214672Y216540D01*
G02X214805Y216591I133J-149D01*
G01X214825D01*
X214834Y216590D01*
G03X214980Y216583I145J1495D01*
G03X214982I1J1502D01*
G01X214983D01*
G03X215183Y216596I3J1502D01*
G03X216062Y217040I-200J1489D01*
G01X216090Y217069D01*
X216205Y217119D01*
G02X216273Y217133I74J-186D01*
G01X216491D01*
X216540Y217123D01*
X216563Y217119D01*
X216676Y217069D01*
X216703Y217041D01*
G03X217783Y216583I1080J1044D01*
G03Y219587I0J1502D01*
G03X216704Y219130I0J-1502D01*
G01X216676Y219101D01*
X216561Y219051D01*
G02X216493Y219037I-74J186D01*
G01X216300D01*
G02X216260Y219041I0J200D01*
G01X216217Y219050D01*
X216195Y219054D01*
X216090Y219101D01*
X216063Y219130D01*
G03X215687Y219412I-1078J-1046D01*
G03X215596Y219456I-699J-1329D01*
G01X215570Y219469D01*
G02X215523Y219502I90J178D01*
G01X215502Y219521D01*
X215487Y219547D01*
X215442Y219624D01*
Y219626D01*
X215387Y219713D01*
X215382Y219720D01*
X215378Y219727D01*
G02X215372Y219901I177J93D01*
G01X215377Y219913D01*
X214512Y220778D01*
G03X214370Y220837I-142J-141D01*
G01X210841D01*
G02X210786Y220845I1J200D01*
G01X210709Y220867D01*
X210687Y220880D01*
G03X210475Y220981I-666J-1124D01*
G03X210020Y221062I-453J-1225D01*
G01X209803D01*
G02X209788Y221063I6J200D01*
G02X209663Y221119I14J199D01*
G01X209258Y221525D01*
X209059Y221724D01*
G02X209057Y221752I198J28D01*
G01Y225407D01*
G02X209059Y225430I200J-6D01*
G01Y225432D01*
G02X209107Y225539I198J-25D01*
G01X209460Y225891D01*
G03X209830Y226784I-897J895D01*
G01Y227844D01*
X209844Y227879D01*
G03X209938Y228364I-1213J487D01*
G01Y229666D01*
G02X209942Y229704I200J-2D01*
G02X209995Y229806I196J-37D01*
G01X210602Y230413D01*
G03X210972Y231306I-897J895D01*
G01Y246473D01*
G02X210976Y246512I200J-1D01*
G01X210983Y246545D01*
G02X211029Y246636I196J-42D01*
G02X211051Y246657I149J-134D01*
G01X211279Y246846D01*
G02X211350Y246884I128J-154D01*
G01X211397Y246898D01*
X211441Y246890D01*
G03X211685Y246869I250J1481D01*
G01X211691D01*
G03X213193Y248371I0J1502D01*
G03X211693Y249873I-1502J0D01*
G01X211688D01*
G03X211441Y249852I3J-1502D01*
G01X211398Y249845D01*
X211354Y249857D01*
G02X211278Y249896I51J193D01*
G01X211045Y250091D01*
G02X211043Y250093I140J142D01*
G02X210992Y250160I130J152D01*
G01X210991D01*
G02X210976Y250203I180J87D01*
G02X210972Y250245I196J40D01*
G01Y254161D01*
G02X210975Y254193I200J-3D01*
G01Y254195D01*
G02X211029Y254301I197J-34D01*
G01X212112Y255384D01*
G02X212213Y255437I140J-143D01*
G01X212215D01*
G02X212252Y255441I40J-196D01*
G01X233211D01*
G02X233278Y255429I-1J-200D01*
G01X233399Y255308D01*
X233417Y255268D01*
X233408Y255210D01*
G02X233407Y255207I-188J61D01*
G02X233389Y255151I-197J32D01*
G02X233359Y255107I-179J90D01*
G01X233283Y255022D01*
X233250Y255005D01*
X233218Y254988D01*
G03X231616Y253198I199J-1790D01*
G03X233417Y251397I1801J0D01*
G03X235151Y252712I0J1801D01*
G01X235161Y252749D01*
G02X235162Y252751I176J-87D01*
G01X235164Y252760D01*
X235165Y252764D01*
X235204Y252802D01*
G02X235291Y252852I140J-143D01*
G01X235300Y252854D01*
X235627Y252940D01*
G02X235646Y252944I51J-193D01*
G02X235813Y252893I31J-197D01*
G02X235819Y252888I-125J-156D01*
G01X236295Y252412D01*
X237263Y251445D01*
G02X237319Y251326I-143J-140D01*
G02X237320Y251305I-199J-20D01*
G01Y248568D01*
X237318Y248563D01*
X237279Y248534D01*
X237278D01*
X237092Y248394D01*
X237019Y248339D01*
G02X237013Y248335I-114J165D01*
G01X236991Y248323D01*
G02X236890Y248303I-88J180D01*
G01X236861Y248307D01*
X236843Y248312D01*
G03X236408Y248376I-434J-1438D01*
G01X236406D01*
G03X234904Y246874I0J-1502D01*
G03X236399Y245372I1502J0D01*
G01X236409D01*
G03X237036Y245510I-2J1502D01*
G01X237064Y245523D01*
X237069Y245525D01*
X237070Y245526D01*
X237084Y245529D01*
X237119D01*
G02X237227Y245497I0J-200D01*
G01X237312Y245443D01*
X237320Y245427D01*
Y245041D01*
X237315Y245031D01*
G03X237124Y244298I1311J-733D01*
G01Y244297D01*
G03X238626Y242795I1502J0D01*
G01X238629D01*
G03X239336Y242972I-1J1504D01*
G01X239349Y242978D01*
X239372Y242990D01*
X242159D01*
G02X242240Y242830I-119J-161D01*
G01Y231775D01*
G02X242217Y231683I-200J1D01*
G01X242200Y231653D01*
X242165Y231617D01*
X242146Y231606D01*
X242141Y231603D01*
X241964Y231499D01*
X241851Y231433D01*
G02X241772Y231408I-99J174D01*
G01X241732Y231406D01*
X241649Y231426D01*
X241625Y231439D01*
G03X240913Y231619I-713J-1323D01*
G01X240909D01*
G03Y228615I0J-1502D01*
G01X240912D01*
G03X241624Y228795I-1J1502D01*
G01X241646Y228807D01*
X241719Y228826D01*
G02X241894Y228788I50J-194D01*
G01X241942Y228750D01*
G03X241964Y228735I123J157D01*
G01X242142Y228629D01*
G02X242147Y228626I-100J-173D01*
G03X242150Y228624I112J165D01*
G02X242234Y228506I-110J-167D01*
G02X242240Y228457I-194J-49D01*
G01Y215996D01*
G02X242221Y215918I-200J7D01*
G01X242199Y215909D01*
X242117Y215875D01*
G02X241899Y215917I-78J184D01*
G01X228790Y229027D01*
X228765Y229069D01*
X228758Y229092D01*
G03X227323Y230148I-1435J-447D01*
G03X225821Y228646I0J-1502D01*
G01X225820D01*
G03X226877Y227211I1503J0D01*
G01X226878D01*
G02X226960Y227161I-60J-191D01*
G01X240908Y213213D01*
G02X240910Y213184I-198J-28D01*
G01Y181729D01*
G02X240902Y181673I-200J0D01*
G02X240896Y181655I-193J54D01*
G01X240881Y181619D01*
X217958Y158695D01*
G02X217936Y158676I-141J141D01*
G01X206561D01*
X206546Y158684D01*
G03X205818Y158872I-728J-1316D01*
G03X204316Y157370I0J-1502D01*
G03X205810Y155868I1502J0D01*
G01X205821D01*
G03X206546Y156056I-3J1502D01*
G01X206561Y156064D01*
X216726D01*
G02X216911Y155940I0J-200D01*
G01X216956Y155831D01*
X216951Y155806D01*
X216309Y155165D01*
X203716Y142572D01*
G02X203695Y142554I-140J142D01*
G01X199758D01*
G02X199723Y142586I117J163D01*
G01X199595Y142763D01*
X199530Y142854D01*
G02X199497Y142960I167J110D01*
G01Y143039D01*
X199506Y143069D01*
G03X199575Y143518I-1433J450D01*
G03X198073Y145020I-1502J0D01*
G03X196571Y143529I0J-1502D01*
G01Y143515D01*
G03X196640Y143066I1502J1D01*
G01X196643Y143056D01*
X196649Y143037D01*
X196654Y142996D01*
G02X196655Y142955I-198J-25D01*
G01X196651Y142900D01*
X196432Y142597D01*
G02X196390Y142554I-162J117D01*
G01X194332D01*
X194309Y142566D01*
X194296Y142572D01*
G03X193589Y142749I-708J-1327D01*
G01X193586D01*
G03Y139745I0J-1502D01*
G01X193589D01*
G03X194296Y139922I-1J1504D01*
G01X194309Y139928D01*
X194332Y139940D01*
X203051D01*
G02X203228Y139832I-1J-200D01*
G01X203269Y139734D01*
Y139720D01*
X203255Y139686D01*
G02X203211Y139619I-186J74D01*
G01X202545Y138954D01*
X196484Y132893D01*
G03X196233Y132535I896J-895D01*
G03X196186Y132421I1146J-539D01*
G01X196173Y132382D01*
X196164Y132358D01*
G03X196158Y132336I190J-64D01*
G01X196157Y132329D01*
X196154Y132318D01*
G03X196137Y132241I1227J-311D01*
G01Y132236D01*
X196133Y132217D01*
G03X196117Y132108I1244J-238D01*
G01Y132102D01*
G03X196114Y132008I1264J-87D01*
G01Y112973D01*
G02X196107Y112921I-200J0D01*
G01X196086Y112846D01*
X196074Y112825D01*
G03X195954Y112554I1307J-741D01*
G01Y112552D01*
G03X195946Y112529I1414J-505D01*
G01Y112528D01*
G02X195897Y112448I-190J62D01*
G01X195273Y111824D01*
G02X195245Y111822I-28J198D01*
G01X183800D01*
G03X182904Y111451I0J-1267D01*
G01X180819Y109365D01*
G02X180704Y109308I-142J141D01*
G02X180677Y109306I-28J198D01*
G01X179963D01*
G02X179782Y109423I1J200D01*
G01X179735Y109532D01*
X179635Y109765D01*
G02X179619Y109845I184J78D01*
G01X179673Y109980D01*
X179698Y110007D01*
G03X180170Y111222I-1331J1216D01*
G01Y114623D01*
G03X176564I-1803J0D01*
G01Y111222D01*
G03X177036Y110007I1803J1D01*
G01X177061Y109980D01*
X177115Y109845D01*
G02X177099Y109765I-200J-2D01*
G01X176999Y109532D01*
X176952Y109423D01*
G02X176771Y109306I-182J83D01*
G01X176512D01*
G03X175590Y108924I1J-1306D01*
G01X171362Y104696D01*
G02X171249Y104730I58J396D01*
G01X171247D01*
G02X171020Y105091I173J361D01*
G01Y107649D01*
G03X167416I-1802J0D01*
G01Y105252D01*
X167415Y104249D01*
G03X168583Y102561I1804J0D01*
G01X168606Y102552D01*
X168625Y102539D01*
G02X168660Y102509I-112J-166D01*
G01X168722Y102441D01*
G02X168767Y102358I-148J-134D01*
G01X168790Y102257D01*
G02X168737Y102071I-195J-45D01*
G01X167992Y101326D01*
G02X167942Y101290I-140J142D01*
G02X167851Y101268I-91J178D01*
G01X158976D01*
X158953Y101280D01*
X158931Y101291D01*
G03X158233Y101463I-698J-1330D01*
G03X156731Y99961I0J-1502D01*
G03X157856Y98507I1502J0D01*
G01X157883Y98500D01*
X157909Y98485D01*
G02X157949Y98454I-102J-172D01*
G01X157981Y98422D01*
G02X158037Y98252I-142J-141D01*
G01X156652Y96867D01*
G03X156009Y95623I1631J-1631D01*
G01X155992Y95526D01*
G02X155918Y95481I-139J144D01*
G01X155882Y95469D01*
X155612Y95385D01*
X155574Y95373D01*
G02X155488Y95367I-57J192D01*
G01X154695Y96160D01*
G03X153773Y96542I-923J-924D01*
G01X149093D01*
X149078Y96550D01*
G03X148350Y96738I-728J-1316D01*
G03X146848Y95236I0J-1502D01*
G03X148342Y93734I1502J0D01*
G01X148353D01*
G03X149078Y93922I-3J1502D01*
G01X149093Y93930D01*
X153147D01*
X153160D01*
G02X153287Y93873I-13J-200D01*
G01X153601Y93558D01*
X153755Y93404D01*
G02X153753Y93335I-198J-29D01*
G01X153733Y93270D01*
Y93268D01*
X153642Y92978D01*
G02X153597Y92902I-190J61D01*
G01X153585Y92900D01*
X153500Y92885D01*
G03X151757Y91437I412J-2270D01*
G01X151722Y91346D01*
X151707Y91333D01*
X151332Y91254D01*
X151312Y91250D01*
X151281Y91243D01*
X151264Y91248D01*
X150231Y92281D01*
G03X148601Y92956I-1630J-1631D01*
G01X148600D01*
G03X146294Y90650I0J-2306D01*
G01Y90649D01*
G03X146969Y89019I2306J0D01*
G01X149419Y86569D01*
G03X151049Y85894I1630J1631D01*
G01X165269D01*
X165270D01*
G02X165413Y85833I-1J-200D01*
G02X165421Y85824I-145J-137D01*
G01X165619Y85591D01*
G02X165660Y85516I-151J-131D01*
G01X165671Y85476D01*
X165668Y85455D01*
G03X165645Y85197I1479J-262D01*
G01Y85180D01*
G03X166051Y84166I1502J13D01*
G01X166078Y84138D01*
X166092Y84103D01*
G02X166102Y84067I-187J-71D01*
G02X166105Y84032I-197J-35D01*
G01Y83755D01*
G02X166095Y83691I-200J-1D01*
G02X166092Y83684I-185J75D01*
G01X166079Y83650D01*
X166051Y83620D01*
G03Y81566I1096J-1027D01*
G01X166079Y81536D01*
X166092Y81502D01*
G02X166095Y81495I-182J-82D01*
G02X166105Y81431I-190J-63D01*
G01Y81155D01*
G02X166095Y81091I-200J-1D01*
G02X166092Y81084I-185J75D01*
G01X166079Y81050D01*
X166051Y81020D01*
G03Y78966I1096J-1027D01*
G01X166079Y78936D01*
X166092Y78902D01*
G02X166095Y78895I-182J-82D01*
G02X166105Y78831I-190J-63D01*
G01Y78555D01*
G02X166095Y78491I-200J-1D01*
G02X166092Y78484I-185J75D01*
G01X166079Y78450D01*
X166051Y78420D01*
G03Y76366I1096J-1027D01*
G01X166079Y76336D01*
X166092Y76302D01*
G02X166095Y76295I-182J-82D01*
G02X166105Y76231I-190J-63D01*
G01Y75955D01*
G02X166095Y75891I-200J-1D01*
G02X166092Y75884I-185J75D01*
G01X166079Y75850D01*
X166051Y75820D01*
G03X165645Y74793I1096J-1027D01*
G03X168649I1502J0D01*
G03X168243Y75820I-1502J0D01*
G01X168215Y75850D01*
X168202Y75884D01*
G02X168199Y75891I182J82D01*
G02X168189Y75955I190J63D01*
G01Y76231D01*
G02X168199Y76295I200J1D01*
G02X168202Y76302I185J-75D01*
G01X168215Y76336D01*
X168243Y76366D01*
G03Y78420I-1096J1027D01*
G01X168215Y78450D01*
X168202Y78484D01*
G02X168199Y78491I182J82D01*
G02X168189Y78555I190J63D01*
G01Y78831D01*
G02X168199Y78895I200J1D01*
G02X168202Y78902I185J-75D01*
G01X168215Y78936D01*
X168243Y78966D01*
G03Y81020I-1096J1027D01*
G01X168215Y81050D01*
X168202Y81084D01*
G02X168199Y81091I182J82D01*
G02X168189Y81155I190J63D01*
G01Y81431D01*
G02X168199Y81495I200J1D01*
G02X168202Y81502I185J-75D01*
G01X168215Y81536D01*
X168243Y81566D01*
G03Y83620I-1096J1027D01*
G01X168215Y83650D01*
X168202Y83684D01*
G02X168199Y83691I182J82D01*
G02X168189Y83755I190J63D01*
G01Y84032D01*
G02X168192Y84067I200J0D01*
G02X168202Y84103I197J-35D01*
G01X168216Y84138D01*
X168245Y84168D01*
G03X168649Y85178I-1098J1025D01*
G01Y85195D01*
G03X168629Y85437I-1502J-2D01*
G01X168626Y85457D01*
Y85459D01*
X168624Y85473D01*
X168623Y85476D01*
X168634Y85515D01*
G02X168674Y85590I192J-54D01*
G01X168772Y85706D01*
X168873Y85824D01*
G02X169024Y85894I152J-130D01*
G01X186544D01*
G02X186658Y85859I1J-200D01*
G02X186674Y85846I-118J-162D01*
G01X187515Y85005D01*
G02X187517Y84976I-198J-28D01*
G01Y84913D01*
X187505Y84867D01*
X187488Y84834D01*
G03X187318Y84143I1332J-694D01*
G01Y84110D01*
G03X188820Y82638I1502J30D01*
G01X188834D01*
G03X188869Y82639I-25J1502D01*
G01X188890Y82640D01*
X188935Y82631D01*
G02X189031Y82585I-35J-197D01*
G01X189240Y82384D01*
G02X189262Y82359I-139J-144D01*
G01Y78752D01*
X189261Y76587D01*
G03X190051Y74849I2307J0D01*
G01X190117Y74792D01*
X190119Y74769D01*
X190121Y74691D01*
X190126Y74497D01*
Y74490D01*
X190128Y74436D01*
X189937Y74246D01*
G03X189262Y72615I1631J-1630D01*
G01X189261Y72567D01*
G03X191568Y70308I2307J49D01*
G01X191604D01*
G03X192461Y70488I-37J2307D01*
G03X193200Y70984I-892J2127D01*
G01X195438Y73222D01*
G03X196114Y74853I-1631J1632D01*
G01Y84548D01*
G02X196185Y84607I160J-120D01*
G01X196467Y84726D01*
X196469D01*
X196537Y84754D01*
G02X196566Y84764I80J-184D01*
G02X196751Y84713I46J-195D01*
G02X196754Y84711I-107J-164D01*
G01X197961Y83505D01*
X198908Y82558D01*
G02X198964Y82384I-141J-142D01*
G01X198957Y82342D01*
X198911Y82058D01*
G02X198876Y81980I-196J41D01*
G01X198863Y81962D01*
X198829Y81933D01*
X198806Y81921D01*
X198805D01*
G03X197984Y80581I683J-1340D01*
G03X199486Y79079I1502J0D01*
G03X200988Y80576I0J1502D01*
G01Y80582D01*
G03X200912Y81053I-1502J-1D01*
G01X200911Y81056D01*
X200906Y81072D01*
X200900Y81116D01*
G02X200903Y81182I198J24D01*
G01X200912Y81220D01*
X200935Y81253D01*
X201129Y81525D01*
G02X201268Y81599I156J-125D01*
G01X201270D01*
G02X201285Y81600I21J-199D01*
G01X202190D01*
G02X202260Y81588I2J-200D01*
G01X202323Y81564D01*
G02X202382Y81530I-69J-188D01*
G03X203859Y80994I1478J1770D01*
G01X206785D01*
G03X208415Y81669I0J2306D01*
G01X211161Y84415D01*
G03X211836Y86045I-1631J1630D01*
G01Y86046D01*
G03X209530Y88352I-2306J0D01*
G01X209529D01*
G03X207899Y87677I0J-2306D01*
G01X207668Y87446D01*
G02X207645Y87444I-29J198D01*
G01X207596D01*
G02X207511Y87463I0J200D01*
G01X207467Y87491D01*
X207466Y87492D01*
X207460Y87497D01*
G03X205976Y88038I-1484J-1765D01*
G01X205358D01*
G02X205324Y88068I114J164D01*
G01X205246Y88164D01*
X205116Y88325D01*
G02X205106Y88341I165J114D01*
G02X205088Y88388I176J94D01*
G01X205075Y88438D01*
X205077Y88445D01*
X205085Y88485D01*
G03X205118Y88791I-1469J313D01*
G03Y88793I-1502J1D01*
G01Y88816D01*
G03X203616Y90303I-1502J-15D01*
G01X203614D01*
G03X203015Y90178I1J-1503D01*
G01X202996Y90170D01*
X202913Y90152D01*
G02X202782Y90202I1J200D01*
G01X202118Y90866D01*
G02X202105Y90882I149J134D01*
G02X202070Y90996I165J113D01*
G01Y102030D01*
G02X202105Y102143I200J0D01*
G01X202121Y102167D01*
X202169Y102204D01*
X202200Y102216D01*
G03X202314Y102265I-536J1403D01*
G03X202875Y102724I-643J1358D01*
G01Y102726D01*
G03X202893Y102750I-1192J913D01*
G03X202911Y102776I-1226J868D01*
G03X203104Y103175I-1241J846D01*
G01X203107Y103184D01*
Y103185D01*
X203109Y103189D01*
G02X203153Y103257I186J-72D01*
G01X208745Y108849D01*
G03X209128Y109773I-923J924D01*
G01Y114702D01*
G02X209129Y114723I200J1D01*
G02X209177Y114834I199J-20D01*
G02X209194Y114851I150J-133D01*
G01X209416Y115050D01*
G02X209487Y115091I133J-149D01*
G01X209527Y115104D01*
X209569Y115100D01*
G03X209726Y115092I155J1494D01*
G03X211218Y116418I0J1502D01*
G01X211224Y116472D01*
G03X211229Y116594I-1498J122D01*
G03X210690Y117747I-1503J0D01*
G01X210682Y117753D01*
X210666Y117769D01*
G02X210628Y117822I141J141D01*
G01X210602Y117875D01*
X210601Y117878D01*
X210591Y117898D01*
G02X210576Y117942I181J86D01*
G02X210572Y117981I196J40D01*
G01Y118190D01*
G02X210573Y118203I200J-9D01*
G01X210580Y118269D01*
X210596Y118302D01*
X210617Y118344D01*
G03X210619Y118348I-178J91D01*
G01X210624Y118359D01*
G02X210664Y118417I182J-83D01*
G01X210682Y118435D01*
X210689Y118441D01*
G03X211228Y119594I-964J1153D01*
G03X209726Y121096I-1502J0D01*
G01X209723D01*
G03X209569Y121088I1J-1502D01*
G01X209568D01*
G02X209421Y121133I-19J199D01*
G01X209194Y121337D01*
G02X209179Y121352I134J149D01*
G02X209129Y121462I149J134D01*
G02X209128Y121486I199J20D01*
G01Y122490D01*
G02X209187Y122632I200J0D01*
G02X209213Y122653I138J-144D01*
G01X209478Y122841D01*
G02X209567Y122876I116J-163D01*
G01X209615Y122882D01*
X209630Y122877D01*
G03X210157Y122781I528J1406D01*
G01X210160D01*
G03Y125785I0J1502D01*
G01X210157D01*
G03X209630Y125689I1J-1502D01*
G01X209615Y125684D01*
X209567Y125690D01*
G02X209478Y125725I27J198D01*
G01X209213Y125913D01*
G02X209187Y125934I112J165D01*
G02X209128Y126076I141J142D01*
G01Y131370D01*
G02X209133Y131412I200J-2D01*
G02X209185Y131510I196J-41D01*
G01X225793Y148118D01*
G02X225952Y148163I129J-153D01*
G01X225991Y148157D01*
X226271Y148115D01*
G02X226358Y148080I-29J-198D01*
G01X226375Y148067D01*
X226405Y148034D01*
X226417Y148011D01*
G03X227743Y147215I1326J706D01*
G03X229245Y148717I0J1502D01*
G03X228449Y150043I-1502J0D01*
G01X228447Y150044D01*
G02X228379Y150104I95J176D01*
G01X228366Y150122D01*
X228348Y150165D01*
X228303Y150469D01*
X228297Y150508D01*
G02X228342Y150667I198J30D01*
G01X232235Y154560D01*
G02X232443Y154606I140J-142D01*
G01X232452Y154602D01*
G02X232544Y154527I-75J-185D01*
G01X232559Y154504D01*
X232576Y154449D01*
Y144568D01*
G03X232570Y144559I1246J-837D01*
G01X232559Y144542D01*
X232546Y144519D01*
G03X232409Y144209I1296J-758D01*
G01Y144207D01*
G02X232360Y144127I-190J62D01*
G01X226491Y138258D01*
G03X226108Y137334I923J-924D01*
G01Y127601D01*
G02X226091Y127581I-161J119D01*
G01X225884Y127411D01*
X225840Y127375D01*
G02X225791Y127345I-128J154D01*
G01X225708Y127363D01*
G03X225229Y127414I-482J-2256D01*
G03X222922Y125107I0J-2307D01*
G01Y121166D01*
G02X222878Y121123I-160J120D01*
G01X222741Y121039D01*
X222593Y120948D01*
G02X222552Y120929I-104J171D01*
G01X222543Y120926D01*
G02X222398Y120940I-55J192D01*
G01X222397D01*
X222355Y120961D01*
G03X221696Y121112I-660J-1367D01*
G01X221695D01*
G03X220177Y119594I0J-1518D01*
G03X220752Y118405I1517J0D01*
G01X220771Y118390D01*
X220798Y118357D01*
X220816Y118319D01*
X220828Y118296D01*
G02X220849Y118207I-179J-89D01*
G01Y117983D01*
G02X220831Y117900I-200J0D01*
G01X220818Y117873D01*
Y117871D01*
X220791Y117817D01*
G02X220758Y117772I-176J95D01*
G01X220739Y117753D01*
X220732Y117747D01*
G03X220193Y116594I964J-1153D01*
G03X221695Y115092I1502J0D01*
G03X222772Y115547I0J1502D01*
G01X222799Y115575D01*
X222939Y115637D01*
X222988Y115635D01*
X223091Y115630D01*
G02X223130Y115624I-11J-200D01*
G02X223253Y115533I-48J-194D01*
G01Y115532D01*
G03X223261Y115520I1922J1273D01*
G01X223265Y115513D01*
G03X223598Y115092I1963J1211D01*
G01X233208Y105482D01*
G02X233221Y105466I-149J-134D01*
G02X233256Y105352I-165J-113D01*
G01Y95111D01*
G03X237868I2306J0D01*
G01Y105214D01*
G02X237908Y105254I160J-120D01*
G01X239139D01*
G02X239216Y105239I1J-200D01*
G01X239235Y105229D01*
G03X239264Y105215I668J1346D01*
G01X239279Y105208D01*
X239295Y105200D01*
X239341Y105154D01*
G02X239349Y104881I-142J-141D01*
G01X239308Y104840D01*
X239266Y104825D01*
G03X238270Y103411I506J-1414D01*
G03X239772Y101909I1502J0D01*
G03X241264Y103235I0J1502D01*
G01X241270Y103289D01*
G03X240690Y104601I-1498J122D01*
G01X240672Y104615D01*
X240639Y104655D01*
G02X240603Y104720I154J128D01*
G01X240592Y104754D01*
X240594Y104792D01*
X240600Y104914D01*
Y104916D01*
X240610Y105071D01*
G02X240611Y105082I200J-13D01*
G02X240637Y105159I199J-24D01*
G01X240653Y105186D01*
X240673Y105218D01*
G02X240702Y105255I171J-104D01*
G01X240747Y105300D01*
X240764Y105311D01*
G03X241433Y106561I-833J1250D01*
G03X239944Y108063I-1502J0D01*
G01X239908D01*
G03X239225Y107891I15J-1503D01*
G02X239132Y107868I-93J177D01*
G01X238497D01*
X238478Y107888D01*
G03X238471Y107894I-132J-147D01*
G01X238466Y107898D01*
X228729Y117635D01*
G02X228722Y117644I154J127D01*
G01Y136710D01*
G02X228726Y136748I200J-2D01*
G02X228779Y136850I196J-37D01*
G01X234242Y142313D01*
X234268Y142321D01*
G03X235345Y143749I-425J1441D01*
G01Y143776D01*
G03X235295Y144148I-1502J-13D01*
G03X235230Y144342I-1454J-379D01*
G03X235229Y144344I-179J-88D01*
G03X235189Y144431I-1385J-584D01*
G01X235188Y144433D01*
Y153309D01*
G02X235209Y153334I163J-116D01*
G01X256991Y175116D01*
X256995Y175119D01*
G03X257338Y175689I-877J916D01*
G01X257340Y175700D01*
X257343Y175711D01*
G03X257386Y176033I-1225J327D01*
G01Y295889D01*
G02X257388Y295917I200J0D01*
G01X260924Y299453D01*
G03X261306Y300375I-924J923D01*
G01Y303272D01*
X261307Y314453D01*
G03X261148Y315076I-1307J-2D01*
G01X261147Y315078D01*
G02X261124Y315170I177J93D01*
G01Y317156D01*
G03X261065Y317298I-200J0D01*
G01X245312Y333051D01*
G02X245276Y333101I142J140D01*
G02X245254Y333192I178J91D01*
G01Y340369D01*
G03X245195Y340511I-200J0D01*
G01X235921Y349785D01*
G02X235885Y349835I142J140D01*
G02X235863Y349926I178J91D01*
G01Y361631D01*
G02X235867Y361668I200J-3D01*
G01Y361670D01*
G02X235920Y361771I196J-39D01*
G01X239454Y365305D01*
G02X239736I141J-142D01*
G01X309479Y295561D01*
G02X309532Y295460I-143J-140D01*
G02X309536Y295421I-196J-40D01*
G01Y262327D01*
G02X309514Y262236I-200J0D01*
G02X309478Y262186I-178J90D01*
G01X304852Y257560D01*
G02X304801Y257523I-142J141D01*
G02X304768Y257510I-90J179D01*
G02X304712Y257502I-56J192D01*
G01X293150D01*
G02X293059Y257524I0J200D01*
G02X293009Y257560I90J178D01*
G01X291205Y259364D01*
G03X290283Y259746I-923J-924D01*
G01X287625D01*
G03X286703Y259364I1J-1306D01*
G01X285109Y257770D01*
X285067Y257745D01*
X285044Y257738D01*
G03X283988Y256301I446J-1434D01*
G01Y256271D01*
G03X283995Y256154I1502J31D01*
G01X283996Y256144D01*
X283994Y256106D01*
G02X283943Y255990I-199J18D01*
G01X283774Y255800D01*
X283742Y255764D01*
G02X283656Y255714I-140J142D01*
G01X283654Y255713D01*
X283623Y255704D01*
X281556D01*
G02X281481Y255719I1J200D01*
G01X281443Y255734D01*
X281415Y255763D01*
X277403Y259776D01*
G03X277354Y259823I-901J-890D01*
G03X277350Y259826I-780J-1036D01*
G01X277347Y259829D01*
G03X276449Y260186I-898J-951D01*
G01X263454D01*
X263439Y260194D01*
G03X262711Y260382I-728J-1316D01*
G03Y257378I0J-1502D01*
G03X263439Y257566I0J1504D01*
G01X263454Y257574D01*
X275825D01*
G02X275861Y257571I1J-200D01*
G02X275966Y257516I-36J-197D01*
G01X280007Y253474D01*
G03X280929Y253092I923J924D01*
G01X303972D01*
G02X304063Y253070I0J-200D01*
G02X304113Y253034I-90J-178D01*
G01X304714Y252433D01*
G02X304750Y252383I-142J-140D01*
G02X304772Y252292I-178J-91D01*
G01Y228766D01*
X304753Y228748D01*
X303282Y227278D01*
G03X302987Y226813I896J-895D01*
G03X302912Y226382I1191J-429D01*
G01Y224290D01*
X302901Y224258D01*
G03X302832Y223839I1238J-419D01*
G01Y222708D01*
G02X302792Y222684I-122J158D01*
G01X302415Y222547D01*
G02X302306Y222545I-58J191D01*
G01X302278Y222553D01*
X302227Y222585D01*
X302206Y222610D01*
G03X301057Y223144I-1149J-969D01*
G03X299555Y221642I0J-1502D01*
G03X300881Y220150I1502J0D01*
G01X300939Y220144D01*
G03X301057Y220139I123J1498D01*
G01X301137D01*
X301184Y220144D01*
X301186D01*
G03X302197Y220663I-129J1496D01*
G01X302202Y220669D01*
X302219Y220686D01*
G02X302344Y220744I142J-141D01*
G02X302429Y220732I15J-199D01*
G01X302471Y220717D01*
X302791Y220600D01*
G02X302832Y220576I-80J-183D01*
G01Y216965D01*
G03X303215Y216041I1306J0D01*
G01X310872Y208385D01*
X310887Y208343D01*
G03X313705I1409J521D01*
G01X313720Y208385D01*
X315559Y210223D01*
G03X315942Y211147I-923J924D01*
G01Y216680D01*
G02X315959Y216692I124J-157D01*
G01X316116Y216776D01*
X316118D01*
X316274Y216858D01*
G02X316425Y216872I93J-177D01*
G01X316487Y216851D01*
X316509Y216836D01*
G03X317342Y216582I836J1249D01*
G01X317388Y216583D01*
G03X318426Y217041I-43J1502D01*
G01X318453Y217069D01*
X318559Y217116D01*
G02X318638Y217133I81J-183D01*
G01X318833D01*
G02X318876Y217128I-1J-200D01*
G01X318910Y217121D01*
G02X318948Y217109I-41J-196D01*
G01X319038Y217069D01*
X319065Y217041D01*
G03X320145Y216583I1080J1044D01*
G03Y219587I0J1502D01*
G03X319066Y219130I0J-1502D01*
G01X319063Y219127D01*
G02X319004Y219086I-142J141D01*
G01X318931Y219054D01*
X318892Y219037D01*
X318659D01*
G02X318620Y219041I1J200D01*
G01X318580Y219050D01*
G02X318541Y219062I39J196D01*
G01X318452Y219101D01*
X318424Y219130D01*
G03X317345Y219587I-1079J-1045D01*
G03X317203Y219581I-8J-1502D01*
G01X317169Y219577D01*
G03X316490Y219320I177J-1492D01*
G01X316465Y219303D01*
X316418Y219286D01*
X316390Y219285D01*
G02X316299Y219300I-14J199D01*
G01X316019Y219446D01*
X315969Y219472D01*
G02X315942Y219489I93J177D01*
G01Y243841D01*
G02X315946Y243879I200J-2D01*
G02X315999Y243981I196J-37D01*
G01X317224Y245206D01*
G03X317606Y246128I-924J923D01*
G01Y293038D01*
G03X317224Y293960I-1306J-1D01*
G01X244851Y366333D01*
G02X244907Y366447I198J-27D01*
G01X246382Y367922D01*
G03X246441Y368064I-141J142D01*
G01Y376657D01*
G02X246445Y376694I200J-3D01*
G01Y376696D01*
G02X246498Y376797I196J-39D01*
G01X246561Y376860D01*
X246564D01*
X252909Y383205D01*
G02X253010Y383258I140J-143D01*
G01X253012D01*
G02X253049Y383262I40J-196D01*
G01X261019D01*
G02X261056Y383258I-3J-200D01*
G01X261058D01*
G02X261159Y383205I-39J-196D01*
G01X261187Y383177D01*
G03X261469I141J142D01*
G01X262369Y384077D01*
G02X262475Y384131I140J-143D01*
G01X262477D01*
G02X262509Y384134I35J-197D01*
G01X272958D01*
G02X273118Y384054I0J-200D01*
G01Y382244D01*
X273106Y382221D01*
X273095Y382199D01*
G03X272923Y381502I1331J-698D01*
G01Y381500D01*
G03X275927I1502J0D01*
G01Y381502D01*
G03X275755Y382199I-1503J-1D01*
G01X275744Y382221D01*
X275732Y382244D01*
Y384053D01*
G02X275892Y384134I161J-119D01*
G01X277213D01*
G03X277413Y384334I0J200D01*
G01Y392275D01*
G03X277354Y392417I-200J0D01*
G01X276294Y393477D01*
G02X276248Y393550I142J141D01*
G01X276291Y393654D01*
G02X276476Y393778I185J-76D01*
G01X276831D01*
X276841Y393773D01*
G03X277574Y393582I733J1311D01*
G01X277575D01*
G03X279077Y395084I0J1502D01*
G03X277583Y396586I-1502J0D01*
G01X277572D01*
G03X276847Y396398I3J-1502D01*
G01X276832Y396390D01*
X273380D01*
X273362Y396409D01*
X266571Y403200D01*
G02X266545Y403232I141J141D01*
G01Y403234D01*
G02X266513Y403329I167J109D01*
G01Y403337D01*
G03X265041Y404809I-1502J-30D01*
G01X265039D01*
G02X264967Y404825I7J200D01*
G02X264904Y404867I77J184D01*
G01X250790Y418981D01*
G02X250754Y419031I142J140D01*
G02X250732Y419122I178J91D01*
G01Y437047D01*
G02X250736Y437084I200J-3D01*
G01Y437086D01*
G02X250789Y437187I196J-39D01*
G01X252329Y438727D01*
G02X252469Y438784I140J-143D01*
G01X252524D01*
X252843Y438639D01*
X252845D01*
X252922Y438606D01*
X252948Y438582D01*
G02X253013Y438435I-135J-148D01*
G01Y438412D01*
G03X253010Y438323I1499J-95D01*
G01Y438322D01*
G03X254512Y436821I1502J1D01*
G03X256014Y438323I0J1502D01*
G03X254513Y439825I-1502J0D01*
G01X254499D01*
G03X254452Y439824I8J-1502D01*
G01X254450D01*
G03X253944Y439713I64J-1501D01*
G01X253914Y439701D01*
X253851Y439697D01*
X253814Y439706D01*
G02X253757Y439730I48J194D01*
G02X253700Y439783I105J170D01*
G01X253669Y439825D01*
G02X253645Y440018I161J118D01*
G01X253648Y440025D01*
G02X253691Y440089I184J-77D01*
G01X253782Y440180D01*
G02X253888Y440234I140J-143D01*
G01X253890D01*
G02X253922Y440237I35J-197D01*
G01X270693D01*
G02X270748Y440229I-1J-200D01*
G01X270796Y440213D01*
X270801Y440210D01*
X270856Y440191D01*
X270881Y440172D01*
G03X271603Y439930I724J963D01*
G01X276951D01*
G02X277005Y439922I-2J-200D01*
G01X277007D01*
G02X277048Y439905I-56J-192D01*
G01X277132Y439854D01*
G02X277169Y439825I-104J-171D01*
G01X277191Y439803D01*
X277205Y439777D01*
G03X279861Y439793I1324J712D01*
G01X279875Y439820D01*
X279928Y439873D01*
G02X280029Y439926I140J-143D01*
G01X280031D01*
G02X280068Y439930I40J-196D01*
G01X282940D01*
G03X283662Y440172I-2J1205D01*
G01X283687Y440191D01*
X283742Y440210D01*
X283747Y440213D01*
X283795Y440229D01*
G02X283850Y440237I56J-192D01*
G01X284496D01*
G02X284551Y440229I-1J-200D01*
G01X284599Y440213D01*
X284604Y440210D01*
X284659Y440191D01*
X284684Y440172D01*
G03X285406Y439930I724J963D01*
G01X290778D01*
X290782D01*
G03X290891Y439933I21J1206D01*
G01X290899Y439934D01*
X291177D01*
X291213Y439920D01*
X291236Y439912D01*
X291278Y439883D01*
X291301Y439857D01*
X291310Y439848D01*
X291314Y439843D01*
G03X291350Y439804I1144J1020D01*
G03X291352Y439802I142J140D01*
G02X291369Y439783I-140J-143D01*
G02X291407Y439703I-157J-124D01*
G02X291411Y439660I-196J-40D01*
G01Y439434D01*
G02X291367Y439309I-200J0D01*
G03X291365Y439307I140J-142D01*
G02X291353Y439293I-157J123D01*
G01X291342Y439282D01*
X291309Y439243D01*
G03X291203Y437436I1144J-974D01*
G03X291355Y437244I1250J833D01*
G01X291358Y437241D01*
G02X291400Y437171I-147J-136D01*
G02X291407Y437145I-189J-65D01*
G02X291411Y437106I-196J-40D01*
G01Y436834D01*
G02X291367Y436709I-200J0D01*
G03X291365Y436707I140J-142D01*
G02X291353Y436693I-157J123D01*
G01X291342Y436682D01*
X291309Y436643D01*
G03X291203Y434836I1144J-974D01*
G03X291355Y434644I1250J833D01*
G01X291358Y434641D01*
G02X291400Y434571I-147J-136D01*
G02X291407Y434545I-189J-65D01*
G02X291411Y434506I-196J-40D01*
G01Y434234D01*
G02X291367Y434109I-200J0D01*
G03X291365Y434107I140J-142D01*
G02X291353Y434093I-157J123D01*
G01X291342Y434082D01*
X291309Y434043D01*
G03X291203Y432236I1144J-974D01*
G03X291355Y432044I1250J833D01*
G01X291358Y432041D01*
G02X291400Y431971I-147J-136D01*
G02X291407Y431945I-189J-65D01*
G02X291411Y431906I-196J-40D01*
G01Y431634D01*
G02X291367Y431509I-200J0D01*
G03X291365Y431507I140J-142D01*
G02X291353Y431493I-157J123D01*
G01X291342Y431482D01*
X291309Y431443D01*
X291308Y431442D01*
G03X291295Y431426I1159J-955D01*
G01X290921Y430985D01*
G03X290933Y430714I153J-129D01*
G01X290963Y430684D01*
X290957Y430604D01*
Y430601D01*
G03X290951Y430469I1496J-134D01*
G01Y430444D01*
G03X292453Y428967I1502J25D01*
G03X293527Y429419I0J1502D01*
G01X293535Y429427D01*
G02X293588Y429465I142J-141D01*
G01X293669Y429501D01*
G02X293746Y429517I78J-184D01*
G01X293961D01*
X294010Y429507D01*
X294033Y429503D01*
X294146Y429453D01*
X294173Y429425D01*
G03X295253Y428967I1080J1044D01*
G03X296755Y430469I0J1502D01*
G03X296349Y431496I-1502J0D01*
G01X296321Y431526D01*
X296308Y431560D01*
G02X296305Y431567I182J82D01*
G02X296295Y431631I190J63D01*
G01Y431905D01*
X296298Y431922D01*
X296306Y431970D01*
X296332Y432023D01*
X296352Y432045D01*
X296353Y432046D01*
G03X296367Y432061I-1091J1033D01*
G03X296370Y432065I-157J121D01*
G03X296410Y432111I-1113J1009D01*
G03X296427Y432132I-1159J956D01*
G03X296495Y432224I-1173J938D01*
G03X296554Y432318I-1242J845D01*
G01X296555Y432320D01*
X296564Y432335D01*
G03X296743Y432875I-1311J734D01*
G01X296744Y432889D01*
G03X296349Y434096I-1491J180D01*
G01X296321Y434126D01*
X296308Y434160D01*
G02X296305Y434167I182J82D01*
G02X296295Y434231I190J63D01*
G01Y434505D01*
X296298Y434522D01*
X296306Y434570D01*
X296332Y434623D01*
X296352Y434645D01*
X296353Y434646D01*
G03X296367Y434661I-1091J1033D01*
G03X296370Y434665I-157J121D01*
G03X296410Y434711I-1113J1009D01*
G03X296427Y434732I-1159J956D01*
G03X296495Y434824I-1173J938D01*
G03X296554Y434918I-1242J845D01*
G01X296555Y434920D01*
X296564Y434935D01*
G03X296743Y435475I-1311J734D01*
G01X296744Y435489D01*
G03X296349Y436696I-1491J180D01*
G01X296321Y436726D01*
X296308Y436760D01*
G02X296305Y436767I182J82D01*
G02X296295Y436831I190J63D01*
G01Y437105D01*
X296298Y437122D01*
X296306Y437170D01*
X296332Y437223D01*
X296352Y437245D01*
X296353Y437246D01*
G03X296367Y437261I-1091J1033D01*
G03X296370Y437265I-157J121D01*
G03X296410Y437311I-1113J1009D01*
G03X296427Y437332I-1159J956D01*
G03X296495Y437424I-1173J938D01*
G03X296554Y437518I-1242J845D01*
G01X296555Y437520D01*
X296564Y437535D01*
G03X296743Y438075I-1311J734D01*
G01X296744Y438089D01*
G03X296349Y439296I-1491J180D01*
G01X296321Y439326D01*
X296308Y439360D01*
G02X296305Y439367I182J82D01*
G02X296295Y439431I190J63D01*
G01Y439662D01*
G02X296309Y439735I200J0D01*
G01X296322Y439769D01*
X296351Y439799D01*
G03X296406Y439859I-1102J1066D01*
G02X296508Y439922I151J-131D01*
G01X296533Y439928D01*
G02X296581Y439934I49J-194D01*
G01X296807D01*
X296815Y439933D01*
G03X296924Y439930I88J1203D01*
G01X297191D01*
G03X297266Y439945I-1J200D01*
G01X297626Y440092D01*
X297632Y440094D01*
G03X297713Y440145I-63J190D01*
G01X297738Y440171D01*
X297747Y440180D01*
X297759Y440191D01*
G02X297866Y440236I128J-154D01*
G02X297885Y440237I20J-199D01*
G01X301430D01*
G02X301515Y440218I0J-200D01*
G01X301532Y440210D01*
X301586Y440185D01*
X301612Y440159D01*
X302089Y439681D01*
X303193Y438577D01*
G02X303246Y438476I-143J-140D01*
G01Y438474D01*
G02X303250Y438437I-196J-40D01*
G01Y427398D01*
G03X303283Y427112I1267J1D01*
G01X303288Y427090D01*
X303301Y427036D01*
G03X303307Y427018I192J54D01*
G01X303310Y427010D01*
X303316Y426992D01*
Y426991D01*
X303319Y426983D01*
X303321Y426978D01*
X303322Y426974D01*
G03X303418Y426767I1193J428D01*
G03X303537Y426594I1100J629D01*
G01X303540Y426590D01*
X303686Y426393D01*
G03X303705Y426371I160J119D01*
G01X305145Y424931D01*
X305151Y424924D01*
G03X305230Y424837I1006J834D01*
G01X309799Y420268D01*
G02X309852Y420166I-143J-139D01*
G02X309856Y420128I-196J-40D01*
G01Y368599D01*
G02X309834Y368508I-200J0D01*
G02X309798Y368458I-178J90D01*
G01X305797Y364457D01*
G03X305738Y364315I141J-142D01*
G01Y362087D01*
X305720Y362047D01*
G03X305600Y361502I1187J-547D01*
G01Y346228D01*
G03X305720Y345683I1307J2D01*
G01X305738Y345643D01*
Y345476D01*
G03X305797Y345334I200J0D01*
G01X311855Y339276D01*
G02X311874Y339254I-141J-141D01*
G01Y329648D01*
G03X312256Y328726I1306J1D01*
G01X317041Y323941D01*
X317066Y323899D01*
X317073Y323876D01*
G03X318508Y322820I1435J447D01*
G03X319882Y323711I0J1505D01*
G01X319894Y323737D01*
X319913Y323759D01*
G02X319952Y323794I152J-130D01*
G01X319983Y323815D01*
X320010Y323824D01*
X320032Y323831D01*
X320298Y323881D01*
G02X320338Y323884I35J-197D01*
G01X320412Y323883D01*
G02X320482Y323864I-16J-199D01*
G01X320508Y323850D01*
G02X320539Y323825I-109J-167D01*
G01X325909Y318455D01*
G03X326051Y318396I142J141D01*
G01X343963D01*
G02X343991Y318394I0J-200D01*
G01X347339Y315046D01*
X347364Y315004D01*
X347371Y314981D01*
G03X347543Y314614I1434J448D01*
G03X348056Y314125I1264J812D01*
G01X348077Y314113D01*
X348107Y314085D01*
X348142Y314035D01*
X348197Y313957D01*
X348204Y313909D01*
X348234Y313707D01*
Y313705D01*
X348244Y313646D01*
G02X348208Y313494I-197J-34D01*
G01X348194Y313476D01*
X334826Y300109D01*
G03X334575Y299751I896J-895D01*
G03X334528Y299637I1146J-539D01*
G01X334515Y299598D01*
X334506Y299574D01*
G03X334500Y299552I189J-63D01*
G01X334499Y299545D01*
X334496Y299534D01*
G03X334479Y299457I1227J-311D01*
G01Y299452D01*
X334475Y299433D01*
G03X334459Y299324I1244J-238D01*
G01Y299318D01*
G03X334456Y299224I1264J-87D01*
G01Y257657D01*
G02X334409Y257529I-200J1D01*
G02X334321Y257468I-154J128D01*
G01X334277Y257453D01*
X334276D01*
X334271Y257451D01*
X334153Y257406D01*
X333970Y257336D01*
X333949Y257330D01*
G02X333858Y257332I-41J196D01*
G01X333837Y257339D01*
G02X333760Y257391I70J187D01*
G01X333758Y257393D01*
G03X332635Y257896I-1123J-1002D01*
G03X331133Y256394I0J-1502D01*
G03X332459Y254902I1502J0D01*
G01X332517Y254895D01*
G03X332635Y254891I110J1499D01*
G03X334062Y255917I0J1505D01*
G01X334066Y255930D01*
X334094Y255986D01*
G02X334140Y256033I164J-114D01*
G01X334164Y256050D01*
X334222Y256069D01*
X334258D01*
X334348Y256048D01*
G02X334456Y255870I-93J-178D01*
G01Y255505D01*
G02X334446Y255443I-200J0D01*
G02X334442Y255431I-192J57D01*
G01X334428Y255397D01*
X334400Y255368D01*
X334396Y255363D01*
X334390Y255356D01*
X333065Y254032D01*
G03X332694Y253136I896J-896D01*
G01Y250872D01*
X332683Y250841D01*
G03X332614Y250423I1238J-419D01*
G01Y246379D01*
G03X332997Y245455I1306J0D01*
G01X334976Y243476D01*
G03X335746Y243102I924J924D01*
G01X335748D01*
G02X335786Y243094I-22J-199D01*
G03X336182Y243030I398J1203D01*
G01X340095D01*
G02X340134Y243026I-1J-200D01*
G01X340223Y243003D01*
X340247Y242990D01*
G03X340613Y242842I742J1308D01*
G03X340996Y242795I373J1456D01*
G01X341014D01*
G03X341188Y242808I-25J1502D01*
G03X341475Y242876I-201J1489D01*
G03X341701Y242975I-488J1420D01*
G01X341707Y242978D01*
X341732Y242990D01*
X342368D01*
G02X342406Y242986I-2J-200D01*
G02X342508Y242933I-37J-196D01*
G01X345720Y239721D01*
G02X345721Y239713I-198J-29D01*
G01X345722Y239701D01*
Y214878D01*
G02X345703Y214798I-200J5D01*
G01X345681Y214789D01*
X345599Y214755D01*
G02X345381Y214797I-78J184D01*
G01X331152Y229027D01*
X331127Y229069D01*
X331120Y229092D01*
G03X329685Y230148I-1435J-447D01*
G03X328183Y228646I0J-1502D01*
G03X329239Y227211I1503J0D01*
G01X329262Y227204D01*
X329304Y227179D01*
X344294Y212190D01*
G02X344344Y212107I-141J-142D01*
G02X344352Y212049I-192J-56D01*
G01Y185181D01*
G02X344330Y185090I-200J0D01*
G02X344294Y185040I-178J90D01*
G01X317988Y158734D01*
G02X317938Y158698I-140J142D01*
G02X317847Y158676I-91J178D01*
G01X308923D01*
X308908Y158684D01*
G03X308180Y158872I-728J-1316D01*
G03X306678Y157370I0J-1502D01*
G03X308172Y155868I1502J0D01*
G01X308183D01*
G03X308908Y156056I-3J1502D01*
G01X308923Y156064D01*
X317433D01*
G02X317613Y155951I0J-200D01*
G01X317618Y155939D01*
G02X317629Y155821I-185J-77D01*
G01X317624Y155795D01*
X317597Y155745D01*
X304464Y142612D01*
G02X304414Y142576I-140J142D01*
G02X304323Y142554I-91J178D01*
G01X302120D01*
G02X302085Y142586I117J163D01*
G01X301957Y142763D01*
X301892Y142854D01*
G02X301859Y142960I167J110D01*
G01Y143039D01*
X301868Y143069D01*
G03X301937Y143518I-1433J450D01*
G03X300435Y145020I-1502J0D01*
G03X298933Y143529I0J-1502D01*
G01Y143515D01*
G03X299002Y143066I1502J1D01*
G01X299005Y143056D01*
X299011Y143037D01*
X299016Y142996D01*
G02X299017Y142955I-198J-25D01*
G01X299013Y142900D01*
X298794Y142597D01*
G02X298752Y142554I-162J117D01*
G01X296694D01*
X296671Y142566D01*
X296658Y142572D01*
G03X295951Y142749I-708J-1327D01*
G01X295948D01*
G03Y139745I0J-1502D01*
G01X295951D01*
G03X296658Y139922I-1J1504D01*
G01X296671Y139928D01*
X296694Y139940D01*
X303712D01*
G02X303887Y139835I-1J-200D01*
G01X303895Y139815D01*
G02X303907Y139699I-184J-78D01*
G01X303902Y139673D01*
X303874Y139621D01*
X298818Y134565D01*
G03X298436Y133643I924J-923D01*
G01Y112826D01*
X298428Y112811D01*
G03X298336Y112611I1315J-726D01*
G03X298308Y112530I1405J-531D01*
G01Y112528D01*
X298300Y112505D01*
X298276Y112465D01*
X297635Y111824D01*
G02X297607Y111822I-28J198D01*
G01X286162D01*
G03X285266Y111451I0J-1267D01*
G01X283181Y109365D01*
G02X283066Y109308I-142J141D01*
G02X283039Y109306I-28J198D01*
G01X282325D01*
G02X282144Y109423I1J200D01*
G01X282097Y109532D01*
X281997Y109765D01*
G02X281981Y109845I184J78D01*
G01X282035Y109980D01*
X282060Y110007D01*
G03X282532Y111222I-1331J1216D01*
G01Y114623D01*
G03X278926I-1803J0D01*
G01Y111222D01*
G03X279398Y110007I1803J1D01*
G01X279423Y109980D01*
X279477Y109845D01*
G02X279461Y109765I-200J-2D01*
G01X279361Y109532D01*
X279314Y109423D01*
G02X279133Y109306I-182J83D01*
G01X278874D01*
G03X277952Y108924I1J-1306D01*
G01X273724Y104696D01*
G02X273688Y104703I58J396D01*
G02X273497Y104810I93J389D01*
G02X273495Y104812I140J142D01*
G02X273382Y105090I287J279D01*
G01Y107649D01*
G03X269778I-1802J0D01*
G01Y105252D01*
X269777Y104249D01*
G03X270990Y102545I1803J0D01*
G01X270991D01*
X270993Y102544D01*
G02X271075Y102489I-67J-188D01*
G01X271092Y102470D01*
X271103Y102449D01*
G02X271121Y102400I-177J-93D01*
G01X271142Y102305D01*
Y102303D01*
X271154Y102253D01*
G02X271116Y102090I-196J-40D01*
G01X271112Y102085D01*
G02X271100Y102072I-153J129D01*
G01X270354Y101326D01*
G02X270304Y101290I-140J142D01*
G02X270213Y101268I-91J178D01*
G01X261338D01*
X261315Y101280D01*
X261293Y101291D01*
G03X260595Y101463I-698J-1330D01*
G03X259093Y99961I0J-1502D01*
G03X260218Y98507I1502J0D01*
G01X260245Y98500D01*
X260271Y98485D01*
G02X260311Y98454I-102J-172D01*
G01X260343Y98422D01*
G02X260399Y98252I-142J-141D01*
G01X259014Y96867D01*
G03X258371Y95623I1631J-1631D01*
G01X258354Y95526D01*
G02X258280Y95481I-139J144D01*
G01X258244Y95469D01*
X257974Y95385D01*
X257936Y95373D01*
G02X257850Y95367I-57J192D01*
G01X257057Y96160D01*
G03X256135Y96542I-923J-924D01*
G01X251455D01*
X251440Y96550D01*
G03X250712Y96738I-728J-1316D01*
G03X249210Y95236I0J-1502D01*
G03X250704Y93734I1502J0D01*
G01X250715D01*
G03X251440Y93922I-3J1502D01*
G01X251455Y93930D01*
X255509D01*
X255522D01*
G02X255649Y93873I-13J-200D01*
G01X255963Y93558D01*
X256117Y93404D01*
G02X256115Y93335I-198J-29D01*
G01X256095Y93270D01*
Y93268D01*
X256004Y92978D01*
G02X255959Y92902I-190J61D01*
G01X255947Y92900D01*
X255862Y92885D01*
G03X254119Y91437I412J-2270D01*
G01X254084Y91346D01*
X254069Y91333D01*
X253694Y91254D01*
X253674Y91250D01*
X253643Y91243D01*
X253626Y91248D01*
X252593Y92281D01*
G03X250963Y92956I-1630J-1631D01*
G01X250962D01*
G03X248656Y90650I0J-2306D01*
G01Y90649D01*
G03X249331Y89019I2306J0D01*
G01X251271Y87079D01*
G03X252901Y86404I1630J1631D01*
G01X267988D01*
G02X267994Y86395I-163J-115D01*
G01X267998Y86389D01*
X268118Y86191D01*
Y86189D01*
X268179Y86087D01*
G02X268198Y86040I-174J-98D01*
G02X268204Y85994I-194J-49D01*
G01X268205Y85948D01*
X268183Y85901D01*
X268181Y85897D01*
G03X268007Y85197I1328J-702D01*
G01Y85180D01*
G03X268413Y84166I1502J13D01*
G01X268440Y84138D01*
X268454Y84103D01*
G02X268464Y84067I-187J-71D01*
G02X268467Y84032I-197J-35D01*
G01Y83755D01*
G02X268457Y83691I-200J-1D01*
G02X268454Y83684I-185J75D01*
G01X268441Y83650D01*
X268413Y83620D01*
G03Y81566I1096J-1027D01*
G01X268441Y81536D01*
X268454Y81502D01*
G02X268457Y81495I-182J-82D01*
G02X268467Y81431I-190J-63D01*
G01Y81155D01*
G02X268457Y81091I-200J-1D01*
G02X268454Y81084I-185J75D01*
G01X268441Y81050D01*
X268413Y81020D01*
G03Y78966I1096J-1027D01*
G01X268441Y78936D01*
X268454Y78902D01*
G02X268457Y78895I-182J-82D01*
G02X268467Y78831I-190J-63D01*
G01Y78555D01*
G02X268457Y78491I-200J-1D01*
G02X268454Y78484I-185J75D01*
G01X268441Y78450D01*
X268413Y78420D01*
G03Y76366I1096J-1027D01*
G01X268441Y76336D01*
X268454Y76302D01*
G02X268457Y76295I-182J-82D01*
G02X268467Y76231I-190J-63D01*
G01Y75955D01*
G02X268457Y75891I-200J-1D01*
G02X268454Y75884I-185J75D01*
G01X268441Y75850D01*
X268413Y75820D01*
G03X268007Y74793I1096J-1027D01*
G03X271011I1502J0D01*
G03X270605Y75820I-1502J0D01*
G01X270577Y75850D01*
X270564Y75884D01*
G02X270561Y75891I182J82D01*
G02X270551Y75955I190J63D01*
G01Y76231D01*
G02X270561Y76295I200J1D01*
G02X270564Y76302I185J-75D01*
G01X270577Y76336D01*
X270605Y76366D01*
G03Y78420I-1096J1027D01*
G01X270577Y78450D01*
X270564Y78484D01*
G02X270561Y78491I182J82D01*
G02X270551Y78555I190J63D01*
G01Y78831D01*
G02X270561Y78895I200J1D01*
G02X270564Y78902I185J-75D01*
G01X270577Y78936D01*
X270605Y78966D01*
G03Y81020I-1096J1027D01*
G01X270577Y81050D01*
X270564Y81084D01*
G02X270561Y81091I182J82D01*
G02X270551Y81155I190J63D01*
G01Y81431D01*
G02X270561Y81495I200J1D01*
G02X270564Y81502I185J-75D01*
G01X270577Y81536D01*
X270605Y81566D01*
G03Y83620I-1096J1027D01*
G01X270577Y83650D01*
X270564Y83684D01*
G02X270561Y83691I182J82D01*
G02X270551Y83755I190J63D01*
G01Y84031D01*
G02X270561Y84095I200J1D01*
G02X270564Y84102I185J-75D01*
G01X270577Y84136D01*
X270605Y84166D01*
G03X271011Y85197I-1096J1027D01*
G01Y85202D01*
G03X270837Y85897I-1502J-7D01*
G01X270831Y85908D01*
G02X270814Y85993I183J81D01*
G01X270815Y86046D01*
X270900Y86189D01*
Y86191D01*
X271020Y86388D01*
G02X271031Y86404I170J-105D01*
G01X288396D01*
G02X288510Y86369I1J-200D01*
G02X288526Y86356I-118J-162D01*
G01X289877Y85005D01*
G02X289879Y84976I-198J-28D01*
G01Y84913D01*
X289867Y84867D01*
X289850Y84834D01*
G03X289680Y84143I1332J-694D01*
G01Y84110D01*
G03X291182Y82638I1502J30D01*
G01X291196D01*
G03X291231Y82639I-25J1502D01*
G01X291252Y82640D01*
X291297Y82631D01*
G02X291393Y82585I-35J-197D01*
G01X291602Y82384D01*
G02X291624Y82359I-139J-144D01*
G01Y78752D01*
X291623Y76587D01*
G03X292413Y74849I2307J0D01*
G01X292479Y74792D01*
X292481Y74769D01*
X292483Y74691D01*
X292488Y74497D01*
Y74490D01*
X292490Y74436D01*
X292299Y74246D01*
G03X291624Y72615I1631J-1630D01*
G01X291623Y72567D01*
G03X293930Y70308I2307J49D01*
G01X293966D01*
G03X294823Y70488I-37J2307D01*
G03X295562Y70984I-892J2127D01*
G01X297800Y73222D01*
G03X298476Y74853I-1631J1632D01*
G01Y84548D01*
G02X298547Y84607I160J-120D01*
G01X298829Y84726D01*
X298831D01*
X298899Y84754D01*
G02X298928Y84764I80J-184D01*
G02X299113Y84713I46J-195D01*
G02X299116Y84711I-107J-164D01*
G01X300323Y83505D01*
X301270Y82558D01*
G02X301326Y82384I-141J-142D01*
G01X301319Y82342D01*
X301273Y82057D01*
G02X301239Y81980I-196J41D01*
G01X301219Y81953D01*
X301197Y81942D01*
G03X300339Y80581I650J-1361D01*
G03X303357I1509J0D01*
G01Y80584D01*
G03X303274Y81076I-1509J-2D01*
G01X303261Y81114D01*
X303260Y81121D01*
G02X303291Y81245I199J16D01*
G01X303353Y81332D01*
Y81334D01*
X303484Y81516D01*
G02X303488Y81522I168J-108D01*
G02X303569Y81584I158J-123D01*
G01X303607Y81600D01*
X303806D01*
X303834Y81592D01*
G03X304499Y81494I665J2207D01*
G01X309647D01*
G03X311277Y82169I0J2306D01*
G01X313523Y84415D01*
G03X314198Y86045I-1631J1630D01*
G01Y86046D01*
G03X311892Y88352I-2306J0D01*
G01X311891D01*
G03X310261Y87677I0J-2306D01*
G01X310030Y87446D01*
G02X310007Y87444I-29J198D01*
G01X309958D01*
G02X309873Y87463I0J200D01*
G01X309829Y87491D01*
X309828Y87492D01*
X309822Y87497D01*
G03X308338Y88038I-1484J-1765D01*
G01X307720D01*
G02X307686Y88068I114J164D01*
G01X307608Y88164D01*
X307478Y88325D01*
G02X307468Y88341I165J114D01*
G02X307450Y88388I176J94D01*
G01X307437Y88438D01*
X307439Y88445D01*
X307447Y88485D01*
G03X307480Y88791I-1469J313D01*
G03Y88793I-1502J1D01*
G01Y88816D01*
G03X305978Y90303I-1502J-15D01*
G01X305977D01*
G03X305141Y90049I0J-1504D01*
G02X304900Y90062I-112J166D01*
G01X304480Y90482D01*
G02X304467Y90498I149J134D01*
G02X304432Y90612I165J113D01*
G01Y102030D01*
G02X304467Y102143I200J0D01*
G01X304483Y102167D01*
X304531Y102204D01*
X304562Y102216D01*
G03X304676Y102265I-536J1403D01*
G03X305237Y102724I-643J1358D01*
G01Y102726D01*
G03X305255Y102750I-1192J913D01*
G03X305273Y102776I-1226J868D01*
G03X305466Y103175I-1241J846D01*
G01X305469Y103184D01*
Y103185D01*
X305471Y103189D01*
G02X305515Y103257I186J-72D01*
G01X311107Y108849D01*
G03X311490Y109773I-923J924D01*
G01Y114701D01*
G02X311545Y114838I200J-1D01*
G01X311554Y114847D01*
X311776Y115048D01*
G02X311805Y115070I135J-148D01*
G02X311910Y115100I105J-170D01*
G01X311929D01*
X311938Y115099D01*
G03X312083Y115092I145J1495D01*
G03X312085I1J1502D01*
G01X312088D01*
G03X313580Y116418I0J1502D01*
G01X313586Y116475D01*
G03X313591Y116594I-1498J123D01*
G01Y116676D01*
X313585Y116725D01*
G03X313031Y117764I-1496J-131D01*
G01X313021Y117772D01*
X312986Y117808D01*
G02X312936Y117916I148J134D01*
G01Y117918D01*
G02X312934Y117943I198J28D01*
G01Y118190D01*
G02X312935Y118203I200J-9D01*
G01X312942Y118269D01*
X312958Y118302D01*
X312979Y118344D01*
G03X312981Y118348I-178J91D01*
G01X312986Y118359D01*
G02X313026Y118417I182J-83D01*
G01X313044Y118435D01*
X313051Y118441D01*
G03X313590Y119594I-964J1153D01*
G03X312088Y121096I-1502J0D01*
G01X312085D01*
G03X312083I-1J-1502D01*
G03X311925Y121088I-3J-1502D01*
G01X311886Y121086D01*
X311861Y121094D01*
X311850Y121097D01*
G02X311777Y121139I61J190D01*
G01X311728Y121183D01*
X311725Y121186D01*
X311548Y121346D01*
G02X311498Y121435I144J139D01*
G01X311490Y121474D01*
Y122489D01*
G02X311491Y122504I200J-6D01*
G01Y122506D01*
G02X311564Y122645I199J-16D01*
G01X311826Y122831D01*
X311859Y122854D01*
X311886Y122864D01*
G02X312019Y122867I71J-187D01*
G01X312051Y122856D01*
G03X312522Y122781I469J1427D01*
G03Y125785I0J1502D01*
G01X312519D01*
G03X312051Y125710I1J-1502D01*
G01X312021Y125700D01*
X311940D01*
G02X311824Y125737I0J200D01*
G01X311753Y125787D01*
X311565Y125921D01*
G02X311490Y126077I125J156D01*
G01Y130866D01*
G02X311494Y130904I200J-2D01*
G02X311547Y131006I196J-37D01*
G01X328344Y147803D01*
G02X328496Y147861I141J-142D01*
G01X328793Y147845D01*
G02X328873Y147824I-10J-200D01*
G01X328910Y147805D01*
X328937Y147771D01*
G03X330104Y147215I1167J947D01*
G01X330105D01*
G03X331597Y148541I0J1502D01*
G01X331603Y148595D01*
G03X331051Y149885I-1498J122D01*
G01X331018Y149912D01*
X330999Y149950D01*
G02X330977Y150031I177J92D01*
G01X330961Y150335D01*
G02X331006Y150464I200J3D01*
G01X331013Y150472D01*
G02X331019Y150478I145J-139D01*
G01X332202Y151661D01*
X334603Y154063D01*
G02X334883Y154061I139J-144D01*
G01X334884Y154060D01*
G02X334942Y153904I-141J-141D01*
G01Y153903D01*
G03X334938Y153799I1302J-102D01*
G01Y144651D01*
G02X334930Y144596I-200J1D01*
G01X334910Y144524D01*
X334902Y144509D01*
G03X334860Y144433I1294J-764D01*
G01Y144431D01*
G03X334769Y144207I1342J-676D01*
G01X334762Y144184D01*
X334737Y144142D01*
X328853Y138258D01*
G03X328470Y137334I923J-924D01*
G01Y127601D01*
G02X328453Y127581I-161J119D01*
G01X328246Y127411D01*
X328202Y127375D01*
G02X328153Y127345I-128J154D01*
G01X328070Y127363D01*
G03X327591Y127414I-482J-2256D01*
G03X325284Y125107I0J-2307D01*
G01Y121166D01*
G02X325240Y121123I-160J120D01*
G01X325103Y121039D01*
X324955Y120948D01*
G02X324914Y120929I-104J171D01*
G01X324905Y120926D01*
G02X324760Y120940I-55J192D01*
G01X324759D01*
X324717Y120961D01*
G03X324058Y121112I-660J-1367D01*
G01X324057D01*
G03X322539Y119594I0J-1518D01*
G03X323115Y118404I1517J0D01*
G02X323171Y118335I-124J-157D01*
G01X323189Y118298D01*
X323190Y118296D01*
G02X323211Y118207I-179J-89D01*
G01Y117983D01*
G02X323193Y117900I-200J0D01*
G01X323180Y117873D01*
Y117871D01*
X323153Y117817D01*
G02X323120Y117772I-176J95D01*
G01X323101Y117753D01*
X323094Y117747D01*
G03X322555Y116594I964J-1153D01*
G03X324057Y115092I1502J0D01*
G03X325132Y115545I0J1502D01*
G01X325140Y115553D01*
G02X325183Y115583I135J-148D01*
G01X325306Y115638D01*
X325352Y115635D01*
X325353D01*
X325402Y115633D01*
G02X325495Y115605I-10J-200D01*
G01X325613Y115534D01*
X325622Y115520D01*
G03X325960Y115090I1970J1200D01*
G01X335570Y105480D01*
G02X335583Y105464I-149J-134D01*
G02X335618Y105350I-165J-113D01*
G01Y95111D01*
G03X340230I2306J0D01*
G01Y105214D01*
G02X340270Y105254I160J-120D01*
G01X341502D01*
G02X341550Y105248I-1J-200D01*
G03X341562Y105241I766J1300D01*
G02X341622Y105191I-96J-176D01*
G01X341685Y105111D01*
X341689Y105099D01*
X341649Y104921D01*
G02X341552Y104796I-194J50D01*
G01X341536Y104789D01*
G03X340632Y103411I598J-1378D01*
G03X343636I1502J0D01*
G03X343055Y104598I-1503J0D01*
G01X343040Y104610D01*
X342978Y104680D01*
X342966Y104719D01*
X342954Y104754D01*
X342956Y104793D01*
X342962Y104914D01*
Y104916D01*
X342972Y105071D01*
G02X342973Y105082I200J-13D01*
G02X342999Y105159I199J-24D01*
G01X343015Y105186D01*
X343035Y105218D01*
G02X343064Y105255I171J-104D01*
G01X343086Y105277D01*
G03X343802Y106561I-793J1284D01*
G03X342293Y108070I-1509J0D01*
G03X341582Y107892I0J-1509D01*
G02X341487Y107868I-95J176D01*
G01X340859D01*
X340840Y107888D01*
G03X340833Y107894I-132J-147D01*
G01X340828Y107898D01*
X331091Y117635D01*
G02X331084Y117644I154J127D01*
G01Y136710D01*
G02X331088Y136748I200J-2D01*
G02X331141Y136850I196J-37D01*
G01X336604Y142313D01*
X336630Y142321D01*
G03X337707Y143749I-425J1441D01*
G01Y143776D01*
G03X337657Y144148I-1502J-13D01*
G03X337612Y144290I-1453J-382D01*
G01X337600Y144322D01*
X337578Y144375D01*
G03X337570Y144393I-1377J-601D01*
G01X337566Y144402D01*
X337559Y144416D01*
X337550Y144456D01*
Y153175D01*
G02X337561Y153240I200J0D01*
G02X337608Y153316I189J-65D01*
G01X360524Y176231D01*
G03X360906Y177153I-924J923D01*
G01Y206139D01*
Y206141D01*
G02X360982Y206296I200J-2D01*
G01X361246Y206496D01*
G02X361409Y206525I113J-165D01*
G03X361817Y206469I407J1454D01*
G01X361819D01*
G03X363328Y207978I0J1509D01*
G01Y207979D01*
G03X362996Y208924I-1510J0D01*
G01X362984Y208939D01*
X362982Y208941D01*
X362974Y208952D01*
X362963Y208982D01*
G02X362951Y209050I188J68D01*
G01Y209123D01*
G03X362943Y209179I-200J0D01*
G01X362940Y209193D01*
Y209439D01*
X362962Y209503D01*
X362976Y209520D01*
G03X363074Y209652I-1155J960D01*
G01X363098Y209688D01*
X363110Y209709D01*
G03X363235Y209975I-1290J769D01*
G03X363236Y209978I-186J64D01*
G01X363237Y209982D01*
X363239Y209987D01*
X363241Y209993D01*
G03X363319Y210398I-1422J484D01*
G03X363321Y210475I-1499J77D01*
G01Y210478D01*
G03X363320Y210541I-1502J8D01*
G01X363319Y210558D01*
G03X362995Y211412I-1500J-81D01*
G01X362994Y211413D01*
X362984Y211425D01*
G02X362951Y211531I167J110D01*
G01Y211623D01*
G03X362943Y211679I-200J0D01*
G01X362940Y211693D01*
Y211939D01*
X362962Y212003D01*
X362976Y212020D01*
G03X363074Y212152I-1155J960D01*
G01X363098Y212188D01*
X363110Y212209D01*
G03X363235Y212475I-1290J769D01*
G03X363236Y212478I-186J64D01*
G01X363237Y212482D01*
X363239Y212487D01*
X363241Y212493D01*
G03X363319Y212898I-1422J484D01*
G03X363321Y212975I-1499J77D01*
G01Y212978D01*
G03X363320Y213041I-1502J8D01*
G01X363319Y213058D01*
G03X362995Y213912I-1500J-81D01*
G01X362994Y213913D01*
X362984Y213925D01*
G02X362951Y214031I167J110D01*
G01Y214123D01*
G03X362933Y214206I-200J0D01*
G01X362908Y214260D01*
G02X362889Y214338I181J85D01*
G02X362891Y214372I200J5D01*
G02X362939Y214476I198J-28D01*
G01X362940Y214477D01*
G03X363321Y215476I-1122J1000D01*
G01Y215478D01*
G03X361819Y216980I-1502J0D01*
G03X361414Y216925I-2J-1502D01*
G01X361368Y216912D01*
X361324Y216920D01*
G02X361241Y216957I38J196D01*
G01X360985Y217151D01*
G02X360968Y217165I119J161D01*
G02X360907Y217290I138J145D01*
G02X360906Y217310I199J20D01*
G01Y287496D01*
G02X360907Y287515I200J-1D01*
G02X360962Y287635I199J-19D01*
G01X362205Y288877D01*
G03X362588Y289801I-923J924D01*
G01Y298724D01*
G02X362592Y298762I200J-2D01*
G02X362645Y298864I196J-37D01*
G01X368846Y305065D01*
G02X368948Y305118I139J-143D01*
G02X368986Y305122I40J-196D01*
G01X410983D01*
G03X411274Y305155I4J1266D01*
G03X411368Y305181I-290J1233D01*
G03X411372Y305182I-46J194D01*
G03X411379Y305185I-495J1164D01*
G03X411400Y305191I-337J1221D01*
G03X411411Y305195I-63J190D01*
G01X411419Y305199D01*
X411426Y305201D01*
G03X411843Y305457I-442J1187D01*
G01X411844Y305458D01*
X411856Y305469D01*
G03X411878Y305491I-885J907D01*
G01X414418Y308031D01*
G02X414440Y308050I141J-141D01*
G02X414560Y308090I120J-160D01*
G01X414735D01*
G03X415657Y308472I-1J1306D01*
G01X417964Y310779D01*
G02X418066Y310832I139J-143D01*
G02X418104Y310836I40J-196D01*
G01X440617D01*
G03X440759Y310895I0J200D01*
G01X441628Y311764D01*
G02X441678Y311800I140J-142D01*
G02X441769Y311822I91J-178D01*
G01X447351D01*
G02X447531Y311709I0J-200D01*
G01X447536Y311697D01*
G02X447547Y311579I-185J-77D01*
G01X447542Y311553D01*
X447515Y311503D01*
X429901Y293889D01*
G03X429518Y292965I923J-924D01*
G01Y280003D01*
G02X429496Y279912I-200J0D01*
G02X429460Y279862I-178J90D01*
G01X411967Y262369D01*
G03X411584Y261445I923J-924D01*
G01Y254782D01*
G02X411446Y254592I-200J0D01*
G01X411354Y254562D01*
G02X411292Y254552I-62J190D01*
G01X411143Y254618D01*
X411140Y254621D01*
G03X411094Y254670I-975J-869D01*
G01X408605Y257159D01*
G03X407681Y257542I-924J-923D01*
G01X395472D01*
G02X395381Y257564I0J200D01*
G02X395331Y257600I90J178D01*
G01X393567Y259364D01*
G03X392645Y259746I-923J-924D01*
G01X389987D01*
G03X389065Y259364I1J-1306D01*
G01X387487Y257786D01*
G02X387417Y257740I-143J141D01*
G01X387406Y257737D01*
G03X386350Y256303I446J-1434D01*
G03X386358Y256146I1502J-2D01*
G01X386362Y256105D01*
X386349Y256064D01*
G02X386308Y255992I-191J61D01*
G01X386110Y255771D01*
G02X386041Y255721I-149J133D01*
G02X385983Y255705I-82J183D01*
G02X385960Y255704I-20J199D01*
G01X383917D01*
G02X383881Y255707I-1J200D01*
G02X383776Y255762I36J197D01*
G01X379735Y259804D01*
G03X378813Y260186I-923J-924D01*
G01X365865D01*
G02X365773Y260209I1J200D01*
G01X365772D01*
G03X365073Y260382I-700J-1329D01*
G03Y257378I0J-1502D01*
G03X365772Y257551I-1J1502D01*
G01X365773D01*
G02X365865Y257574I93J-177D01*
G01X378187D01*
G02X378223Y257571I1J-200D01*
G02X378328Y257516I-36J-197D01*
G01X382369Y253474D01*
G03X383291Y253092I923J924D01*
G01X406334D01*
G02X406425Y253070I0J-200D01*
G02X406475Y253034I-90J-178D01*
G01X407030Y252479D01*
G02X407066Y252429I-142J-140D01*
G02X407088Y252338I-178J-91D01*
G01Y214269D01*
G02X407079Y214209I-200J-1D01*
G02X407006Y214108I-191J61D01*
G01X406746Y213918D01*
G02X406659Y213881I-120J160D01*
G01X406612Y213874D01*
X406588Y213882D01*
G03X406119Y213957I-469J-1427D01*
G01X406118D01*
G03Y210953I0J-1502D01*
G01X406119D01*
G03X406588Y211028I0J1502D01*
G01X406612Y211036D01*
X406659Y211029D01*
G02X406746Y210992I-33J-197D01*
G01X407006Y210802D01*
G02X407088Y210641I-118J-161D01*
G01Y210604D01*
G03X407470Y209682I1306J1D01*
G01X409212Y207940D01*
G03X410134Y207558I923J924D01*
G01X413866D01*
G02X413958Y207535I-1J-200D01*
G01X413959D01*
G03X414658Y207362I700J1329D01*
G03X416160Y208864I0J1502D01*
G03X415105Y210298I-1502J0D01*
G01X415104D01*
X415093Y210301D01*
G02X415023Y210347I73J187D01*
G01X414608Y210762D01*
X413763Y211606D01*
G02X413707Y211726I143J140D01*
G02X413706Y211746I199J20D01*
G01Y226798D01*
G02X413763Y226937I200J-1D01*
G01X415654Y228828D01*
G03X416036Y229750I-924J923D01*
G01Y260119D01*
G02X416045Y260179I200J1D01*
G02X416094Y260260I191J-60D01*
G01X433345Y277510D01*
G03X433728Y278434I-923J924D01*
G01Y291490D01*
G02X433732Y291532I200J2D01*
G02X433785Y291630I196J-42D01*
G01X450778Y308624D01*
G02X450859Y308673I141J-142D01*
G02X450919Y308682I59J-191D01*
G01X463042D01*
G03X463964Y309064I-1J1306D01*
G01X489253Y334353D01*
G03X489636Y335277I-923J924D01*
G01Y363961D01*
G02X489665Y363992I160J-120D01*
G03X489667Y363994I-140J142D01*
G02X489692Y364012I129J-153D01*
G01X489825Y364085D01*
X489827D01*
X489951Y364151D01*
X489962Y364157D01*
G02X490034Y364175I84J-182D01*
G01X490157D01*
G02X490246Y364154I0J-200D01*
G01X490258Y364148D01*
X490268Y364142D01*
X490285Y364132D01*
X490292Y364128D01*
G03X490857Y363934I761J1295D01*
G03X491048Y363921I197J1489D01*
G01X491053D01*
G03Y366925I0J1502D01*
G01X491052D01*
G03X490246Y366690I0J-1501D01*
G01X490244Y366689D01*
X490226Y366678D01*
X490192Y366663D01*
X490150Y366650D01*
G02X490088Y366643I-53J193D01*
G01X490087D01*
G02X490030Y366654I9J200D01*
G01X490011Y366661D01*
G02X490007Y366663I87J180D01*
G01X489688Y366837D01*
G02X489636Y366885I107J168D01*
G01Y372020D01*
G02X489655Y372042I160J-119D01*
G01X489674Y372061D01*
G02X489702Y372084I140J-142D01*
G01X489876Y372190D01*
X489877Y372191D01*
X489968Y372246D01*
G02X490061Y372269I93J-177D01*
G01X490119D01*
G02X490208Y372248I0J-200D01*
G01X490210Y372247D01*
G03X490884Y372087I675J1342D01*
G01X490900D01*
G03X492377Y373413I-15J1502D01*
G01X492381Y373447D01*
G03X492383Y373470I-1496J142D01*
G03X492388Y373589I-1498J123D01*
G03X491068Y375081I-1503J0D01*
G01X491004Y375087D01*
G03X490888Y375092I-123J-1498D01*
G01X490861D01*
G03X490202Y374928I24J-1503D01*
G01X490195Y374924D01*
X490180Y374917D01*
X490130Y374904D01*
G02X490110Y374900I-49J194D01*
G02X489978Y374926I-30J198D01*
G01X489977Y374927D01*
X489686Y375103D01*
G02X489636Y375150I110J167D01*
G01Y381001D01*
G02X489655Y381023I160J-119D01*
G01X489674Y381042D01*
G02X489702Y381065I140J-142D01*
G01X489876Y381171D01*
X489877Y381172D01*
X489968Y381227D01*
G02X490061Y381250I93J-177D01*
G01X490119D01*
G02X490208Y381229I0J-200D01*
G01X490210Y381228D01*
G03X490884Y381068I675J1342D01*
G01X490900D01*
G03X492377Y382394I-15J1502D01*
G01X492381Y382428D01*
G03X492383Y382451I-1496J142D01*
G03X492388Y382570I-1498J123D01*
G03X491068Y384062I-1503J0D01*
G01X491004Y384068D01*
G03X490888Y384073I-123J-1498D01*
G01X490861D01*
G03X490202Y383909I24J-1503D01*
G01X490195Y383905D01*
X490180Y383898D01*
X490130Y383885D01*
G02X490110Y383881I-49J194D01*
G02X489978Y383907I-30J198D01*
G01X489977Y383908D01*
X489686Y384084D01*
G02X489636Y384131I110J167D01*
G01Y390314D01*
G02X489698Y390368I160J-121D01*
G01X489798Y390413D01*
G02X489800Y390415I133J-131D01*
G01X490059Y390528D01*
G02X490166Y390539I73J-186D01*
G01X490193Y390534D01*
X490244Y390510D01*
X490267Y390488D01*
G03X491289Y390087I1022J1102D01*
G03Y393091I0J1502D01*
G01X491231D01*
G03X490287Y392709I58J-1502D01*
G01X490266Y392690D01*
X490209Y392662D01*
G02X490177Y392650I-86J180D01*
G02X490087Y392645I-56J192D01*
G02X490042Y392658I33J197D01*
G01X489830Y392750D01*
X489716Y392800D01*
X489687Y392813D01*
X489664Y392823D01*
X489661Y392824D01*
X489652Y392837D01*
X489644Y392865D01*
G02X489636Y392921I192J56D01*
G01Y404092D01*
G03X489253Y405016I-1306J0D01*
G01X489088Y405181D01*
G02X489086Y405209I198J28D01*
G01Y411179D01*
G02X489181Y411341I200J-9D01*
G02X489218Y411358I102J-172D01*
G01X489297Y411387D01*
X489299D01*
X489588Y411488D01*
G02X489616Y411494I56J-193D01*
G01X489631Y411495D01*
G02X489699Y411487I11J-200D01*
G01X489729Y411478D01*
X489780Y411444D01*
X489800Y411418D01*
G03X490984Y410840I1184J924D01*
G01X491007D01*
G03X492487Y412342I-22J1502D01*
G03X491161Y413834I-1502J0D01*
G01X491107Y413840D01*
G03X491023Y413844I-113J-1499D01*
G01X491019D01*
G03X490987Y413845I-63J-1501D01*
G01X490983D01*
G03X489825Y413298I2J-1503D01*
G01X489811Y413282D01*
X489788Y413263D01*
G02X489757Y413244I-120J161D01*
G01X489744Y413238D01*
X489689Y413212D01*
G02X489562Y413205I-74J186D01*
G01X489398Y413262D01*
X489396D01*
X489235Y413319D01*
X489192Y413334D01*
X489144Y413382D01*
G02X489100Y413449I142J141D01*
G01X489086Y413483D01*
Y416942D01*
G02X489149Y417087I200J-1D01*
G01X489170Y417105D01*
G03X489930Y418241I-732J1312D01*
G01X489936Y418294D01*
G03X489941Y418416I-1498J122D01*
G01Y418417D01*
G03X489210Y419706I-1502J0D01*
G02X489208Y419708I136J138D01*
G01X489172Y419730D01*
G02X489151Y419746I110J167D01*
G01X489132Y419764D01*
X489111Y419799D01*
G02X489087Y419877I175J97D01*
G01Y419879D01*
G02X489086Y419895I199J20D01*
G01Y423989D01*
G02X489149Y424134I200J-1D01*
G01X489170Y424152D01*
G03X489930Y425288I-732J1312D01*
G01X489936Y425341D01*
G03X489941Y425463I-1498J122D01*
G01Y425464D01*
G03X489210Y426753I-1502J0D01*
G02X489208Y426755I136J138D01*
G01X489172Y426777D01*
G02X489151Y426793I110J167D01*
G01X489132Y426811D01*
X489111Y426846D01*
G02X489087Y426924I175J97D01*
G01Y426926D01*
G02X489086Y426942I199J20D01*
G01Y429515D01*
G02X489090Y429552I200J-3D01*
G01Y429554D01*
G02X489143Y429655I196J-39D01*
G01X489344Y429856D01*
G02X489399Y429894I139J-143D01*
G01X489446Y429914D01*
X489470Y429915D01*
G03X490947Y431071I15J1502D01*
G01X490949Y431080D01*
G03X490987Y431415I-1463J336D01*
G01Y431417D01*
G03X489547Y432918I-1502J0D01*
G03X489506Y432919I-57J-1501D01*
G01X489482D01*
X489431Y432932D01*
X489404Y432939D01*
X489382Y432951D01*
G02X489377Y432954I100J173D01*
G02X489337Y432985I102J172D01*
G01X489144Y433178D01*
G02X489108Y433228I142J140D01*
G02X489086Y433319I178J91D01*
G01Y438001D01*
G02X489090Y438038I200J-3D01*
G01Y438040D01*
G02X489143Y438141I196J-39D01*
G01X489344Y438342D01*
G02X489399Y438380I139J-143D01*
G01X489446Y438400D01*
X489470Y438401D01*
G03X490947Y439557I15J1502D01*
G01X490949Y439566D01*
G03X490987Y439901I-1463J336D01*
G01Y439903D01*
G03X489547Y441404I-1502J0D01*
G03X489506Y441405I-57J-1501D01*
G01X489482D01*
X489431Y441418D01*
X489404Y441425D01*
X489382Y441437D01*
G02X489377Y441440I100J173D01*
G02X489337Y441471I102J172D01*
G01X489144Y441664D01*
G02X489108Y441714I142J140D01*
G02X489086Y441805I178J91D01*
G01Y460382D01*
G02X489090Y460419I200J-3D01*
G01Y460421D01*
G02X489143Y460522I196J-39D01*
G01X490590Y461969D01*
G02X490696Y462023I140J-143D01*
G01X490698D01*
G02X490730Y462026I35J-197D01*
G01X494950D01*
G02X495086Y461972I-1J-200D01*
G01X495135Y461925D01*
X495160Y461901D01*
X495163Y461898D01*
G02X495206Y461833I-142J-141D01*
G01X495235Y461765D01*
X495238Y461738D01*
G03X498220I1491J181D01*
G01X498223Y461765D01*
X498244Y461815D01*
X498258Y461848D01*
G02X498289Y461893I179J-90D01*
G01X498370Y461969D01*
X498376Y461975D01*
G02X498508Y462026I133J-149D01*
G01X502838D01*
G02X502875Y462022I-3J-200D01*
G01X502877D01*
G02X502978Y461969I-39J-196D01*
G01X502987Y461960D01*
X503187Y461736D01*
G02X503228Y461665I-149J-133D01*
G01X503241Y461625D01*
X503236Y461582D01*
G03X503227Y461419I1493J-164D01*
G03X506231I1502J0D01*
G03X506222Y461582I-1502J-1D01*
G01X506218Y461626D01*
X506230Y461664D01*
G02X506265Y461727I189J-64D01*
G01X506468Y461958D01*
X506474Y461963D01*
X506480Y461969D01*
G02X506581Y462022I140J-143D01*
G01X506583D01*
G02X506620Y462026I40J-196D01*
G01X511613D01*
G02X511804Y461886I0J-200D01*
G01X511816Y461848D01*
X511818Y461827D01*
G03X511845Y461670I1492J176D01*
G03X511929Y461412I1465J334D01*
G01X511937Y461394D01*
X511946Y461353D01*
Y461266D01*
G02X511938Y461239I-195J43D01*
G01X511927Y461211D01*
X511853Y461086D01*
Y461084D01*
X511757Y460924D01*
G02X511696Y460863I-169J108D01*
G01X511657Y460839D01*
X511609Y460834D01*
G03X511340Y460783I144J-1495D01*
G01X511338D01*
G03X511301Y460772I410J-1446D01*
G03X511296Y460770I555J-1396D01*
G03X511288Y460768I360J-1457D01*
G03X511284Y460766I86J-178D01*
G03X510818Y460515I468J-1427D01*
G01X510817Y460514D01*
X510789Y460493D01*
X510755Y460481D01*
G02X510693Y460471I-62J190D01*
G01X510608D01*
G03X510525Y460453I0J-200D01*
G01X510471Y460428D01*
G02X510393Y460409I-85J181D01*
G02X510359Y460411I-5J200D01*
G02X510255Y460459I28J198D01*
G01X510254Y460460D01*
G03X509255Y460841I-1000J-1122D01*
G01X509253D01*
G03X507751Y459339I0J-1502D01*
G01Y459337D01*
G03X508078Y458403I1501J1D01*
G01X508098Y458377D01*
X508113Y458333D01*
G02X508121Y458280I-192J-56D01*
G01Y458194D01*
G03X508129Y458138I200J0D01*
G01X508132Y458124D01*
Y457878D01*
X508110Y457814D01*
X508096Y457797D01*
G03X507998Y457665I1155J-960D01*
G03X507837Y457342I1254J-827D01*
G03X507836Y457339I186J-64D01*
G01X507835Y457335D01*
X507831Y457324D01*
G03X507751Y456840I1422J-484D01*
G01Y456839D01*
G03X508077Y455905I1502J0D01*
G01X508078Y455904D01*
X508088Y455892D01*
G02X508121Y455786I-167J-110D01*
G01Y455694D01*
G03X508139Y455611I200J0D01*
G01X508164Y455557D01*
G02X508183Y455479I-181J-85D01*
G02X508181Y455445I-200J-5D01*
G02X508133Y455341I-198J28D01*
G01X508132Y455340D01*
G03X507751Y454341I1122J-1000D01*
G01Y454339D01*
G03X509253Y452837I1502J0D01*
G01X509255D01*
G03X510189Y453164I-1J1501D01*
G01X510215Y453184D01*
X510259Y453199D01*
G02X510312Y453207I56J-192D01*
G01X510398D01*
G03X510481Y453225I0J200D01*
G01X510535Y453250D01*
G02X510613Y453269I85J-181D01*
G02X510647Y453267I5J-200D01*
G02X510751Y453219I-28J-198D01*
G01X510752Y453218D01*
G03X511751Y452837I1000J1122D01*
G01X511753D01*
G03X513255Y454339I0J1502D01*
G03X512929Y455273I-1502J0D01*
G01X512928Y455274D01*
X512918Y455286D01*
G02X512885Y455392I167J110D01*
G01Y455484D01*
G03X512877Y455540I-200J0D01*
G01X512874Y455554D01*
Y455800D01*
X512896Y455864D01*
X512910Y455881D01*
G03X513008Y456013I-1155J960D01*
G03X513169Y456336I-1254J827D01*
G03X513170Y456339I-186J64D01*
G01X513175Y456354D01*
G03X513253Y456759I-1422J484D01*
G03X513255Y456836I-1499J77D01*
G01Y456839D01*
G03X513254Y456902I-1502J8D01*
G01X513253Y456919D01*
G03X512929Y457773I-1500J-81D01*
G01X512928Y457774D01*
X512918Y457786D01*
G02X512885Y457892I167J110D01*
G01Y457984D01*
G03X512867Y458067I-200J0D01*
G01X512842Y458121D01*
G02X512823Y458199I181J85D01*
G02X512825Y458233I200J5D01*
G02X512873Y458337I198J-28D01*
G01X512874Y458338D01*
G03X513255Y459338I-1122J1000D01*
G01Y459342D01*
G03X513134Y459931I-1502J-2D01*
G01X513126Y459949D01*
X513117Y459990D01*
Y459991D01*
G02X513124Y460101I195J43D01*
G01X513136Y460132D01*
X513210Y460257D01*
Y460259D01*
X513305Y460419D01*
G02X513308Y460423I161J-118D01*
G01Y460424D01*
G02X513373Y460484I165J-114D01*
G01X513408Y460504D01*
X513454Y460509D01*
G03X514795Y461776I-144J1495D01*
G01Y461777D01*
X514800Y461810D01*
X514816Y461841D01*
G02X514858Y461896I178J-92D01*
G01X514919Y461953D01*
X514920D01*
X514948Y461979D01*
G02X515076Y462026I129J-153D01*
G01X521054D01*
G02X521254Y461826I0J-200D01*
G01Y461818D01*
G03X522756Y460316I1502J0D01*
G03X524246Y461626I0J1502D01*
G01X524253Y461678D01*
X524347Y461803D01*
G02X524416Y461859I157J-123D01*
G01X524428Y461864D01*
X524436Y461868D01*
X524441Y461870D01*
G02X524536Y461883I74J-186D01*
G01X524585Y461877D01*
X524642Y461839D01*
G02X524714Y461680I-128J-154D01*
G01Y461651D01*
G03X525041Y460716I1501J0D01*
G01X525061Y460690D01*
X525076Y460646D01*
G02X525084Y460593I-192J-56D01*
G01Y460507D01*
G03X525092Y460451I200J0D01*
G01X525095Y460437D01*
Y460191D01*
X525073Y460127D01*
X525059Y460110D01*
G03X524961Y459978I1155J-960D01*
G01X524937Y459942D01*
X524925Y459921D01*
G03X524800Y459655I1290J-769D01*
G03X524799Y459652I186J-64D01*
G01X524798Y459648D01*
X524794Y459637D01*
G03X524714Y459153I1422J-484D01*
G01Y459152D01*
G03X525040Y458218I1502J0D01*
G01X525041Y458217D01*
X525051Y458205D01*
G02X525084Y458099I-167J-110D01*
G01Y458007D01*
G03X525102Y457924I200J0D01*
G01X525127Y457870D01*
G02X525146Y457792I-181J-85D01*
G02X525144Y457758I-200J-5D01*
G02X525096Y457654I-198J28D01*
G01X525095Y457653D01*
G03X524714Y456654I1122J-1000D01*
G01Y456652D01*
G03X526216Y455150I1502J0D01*
G01X526218D01*
G03X527152Y455477I-1J1501D01*
G01X527178Y455497D01*
X527222Y455512D01*
G02X527275Y455520I56J-192D01*
G01X527361D01*
G03X527444Y455538I0J200D01*
G01X527498Y455563D01*
G02X527576Y455582I85J-181D01*
G02X527610Y455580I5J-200D01*
G02X527714Y455532I-28J-198D01*
G01X527715Y455531D01*
G03X528714Y455150I1000J1122D01*
G01X528716D01*
G03X530218Y456652I0J1502D01*
G03X529892Y457586I-1502J0D01*
G01X529891Y457587D01*
X529881Y457599D01*
G02X529848Y457705I167J110D01*
G01Y457797D01*
G03X529840Y457853I-200J0D01*
G01X529837Y457867D01*
Y458113D01*
X529859Y458177D01*
X529873Y458194D01*
G03X529971Y458326I-1155J960D01*
G01X529995Y458362D01*
X530007Y458383D01*
G03X530132Y458649I-1290J769D01*
G03X530133Y458652I-186J64D01*
G01X530134Y458656D01*
X530136Y458661D01*
X530138Y458667D01*
G03X530212Y459011I-1422J486D01*
G01Y459013D01*
G03X530216Y459070I-1496J134D01*
G01Y459073D01*
G03X530217Y459088I-1497J107D01*
G01X530220Y459154D01*
X530217Y459203D01*
G03X529892Y460086I-1501J-51D01*
G01X529891Y460087D01*
X529881Y460099D01*
G02X529848Y460205I167J110D01*
G01Y460297D01*
G03X529830Y460380I-200J0D01*
G01X529805Y460434D01*
G02X529786Y460512I181J85D01*
G02X529788Y460546I200J5D01*
G02X529836Y460650I198J-28D01*
G01X529837Y460651D01*
G03X530089Y461043I-1122J999D01*
G03X530207Y461468I-1373J610D01*
G01Y461473D01*
X530209Y461487D01*
G03X530210Y461496I-1492J170D01*
G01Y461497D01*
G03X530211Y461506I-1491J170D01*
G01Y461508D01*
X530212Y461512D01*
X530215Y461537D01*
G03X530218Y461611I-1499J98D01*
G01Y461613D01*
X530219Y461632D01*
X530229Y461679D01*
G02X530284Y461778I195J-44D01*
G01X530335Y461828D01*
X530463Y461954D01*
G03X530465Y461956I-140J142D01*
G01X530478Y461969D01*
G02X530579Y462022I140J-143D01*
G01X530581D01*
G02X530618Y462026I40J-196D01*
G01X543121D01*
G02X543153Y462023I-3J-200D01*
G01X543155D01*
G02X543261Y461969I-34J-197D01*
G01X547005Y458225D01*
G02X547058Y458123I-143J-139D01*
G02X547062Y458085I-196J-40D01*
G01Y438592D01*
G02X547040Y438501I-200J0D01*
G02X547004Y438451I-178J90D01*
G01X543534Y434981D01*
G03X543152Y434059I924J-923D01*
G01Y393971D01*
G02X543068Y393808I-200J0D01*
G01X542831Y393649D01*
X542787Y393619D01*
G02X542695Y393586I-111J166D01*
G01X542647Y393581D01*
X542646D01*
X542601Y393600D01*
G03X542034Y393711I-567J-1393D01*
G03X540532Y392209I0J-1502D01*
G03X541858Y390717I1502J0D01*
G01X541912Y390711D01*
G03X542034Y390706I123J1498D01*
G03X542601Y390817I0J1504D01*
G01X542646Y390836D01*
X542647D01*
X542695Y390831D01*
G02X542787Y390798I-19J-199D01*
G01X542831Y390768D01*
X543068Y390609D01*
G02X543152Y390446I-116J-163D01*
G01Y387811D01*
G02X543148Y387773I-200J2D01*
G02X543078Y387655I-197J37D01*
G02X543046Y387634I-125J156D01*
G01X542957Y387587D01*
X542735Y387468D01*
G02X542630Y387445I-94J177D01*
G01X542578Y387448D01*
X542532Y387478D01*
X542531Y387479D01*
G03X541706Y387725I-824J-1256D01*
G03X541645Y387724I-6J-1502D01*
G01X541643D01*
G03X540204Y386223I63J-1501D01*
G03X541706Y384721I1502J0D01*
G01X541708D01*
G03X542531Y384967I-1J1502D01*
G01X542532Y384968D01*
X542533Y384969D01*
G02X542631Y385001I109J-168D01*
G01X542686Y385004D01*
X542957Y384859D01*
X543046Y384812D01*
G02X543078Y384791I-93J-177D01*
G02X543148Y384673I-127J-155D01*
G02X543152Y384635I-196J-40D01*
G01Y354026D01*
G02X543137Y353949I-200J-1D01*
G02X543094Y353885I-184J78D01*
G01X486434Y297226D01*
G03X486052Y296304I924J-923D01*
G01Y275583D01*
G02X486044Y275528I-200J1D01*
G02X485994Y275442I-192J54D01*
G01X479677Y269125D01*
X473360Y262809D01*
G02X473218Y262750I-142J141D01*
G01X463384D01*
G03X462488Y262379I0J-1267D01*
G01X461883Y261774D01*
X461863Y261762D01*
G03X461631Y261578I691J-1109D01*
G03X461627Y261574I922J-926D01*
G01X451155Y251102D01*
G03X450772Y250178I923J-924D01*
G01Y240343D01*
G02X450750Y240252I-200J0D01*
G02X450714Y240202I-178J90D01*
G01X422636Y212124D01*
G03X422254Y211202I924J-923D01*
G01Y166424D01*
G02X422243Y166359I-200J0D01*
G02X422196Y166283I-189J65D01*
G01X398363Y142451D01*
G03X397980Y141527I923J-924D01*
G01Y114900D01*
G03X398363Y113976I1306J0D01*
G01X400228Y112111D01*
G02X400230Y112086I-198J-28D01*
G02X400227Y112054I-200J3D01*
G01X400053Y111880D01*
G02X400003Y111844I-140J142D01*
G02X399912Y111822I-91J178D01*
G01X388524D01*
G03X387628Y111451I0J-1267D01*
G01X385645Y109467D01*
G02X385600Y109434I-140J143D01*
G02X385505Y109410I-95J176D01*
G01X384768D01*
G02X384606Y109512I13J200D01*
G01X384449Y109848D01*
G02X384447Y109986I187J72D01*
G01Y109987D01*
X384474Y110065D01*
X384496Y110093D01*
X384497Y110094D01*
G03X384894Y111222I-1406J1129D01*
G01Y114623D01*
G03X381288I-1803J0D01*
G01Y111223D01*
G03X381401Y110595I1803J0D01*
G01X381403Y110590D01*
X381408Y110576D01*
G03X381415Y110557I191J60D01*
G01X381418Y110550D01*
G03X382022Y109771I1673J673D01*
G01X382041Y109757D01*
X382055Y109741D01*
G02X382082Y109700I-152J-130D01*
G01X382103Y109658D01*
Y109610D01*
G02X381903Y109410I-200J0D01*
G01X381612D01*
G03X381555Y109412I-73J-1266D01*
G01X381553D01*
G03X381033Y109300I1J-1268D01*
G01X381023Y109295D01*
X380979Y109281D01*
X380969Y109279D01*
G03X380314Y108924I269J-1279D01*
G01X376086Y104696D01*
G02X376050Y104703I58J396D01*
G02X375859Y104810I93J389D01*
G02X375857Y104812I140J142D01*
G02X375744Y105090I287J279D01*
G01Y107649D01*
G03X372140I-1802J0D01*
G01Y105252D01*
X372139Y104249D01*
G03X373352Y102545I1803J0D01*
G01X373353D01*
X373355Y102544D01*
G02X373437Y102489I-67J-188D01*
G01X373454Y102470D01*
X373465Y102449D01*
G02X373483Y102400I-177J-93D01*
G01X373504Y102305D01*
Y102303D01*
X373516Y102253D01*
G02X373478Y102090I-196J-40D01*
G01X373474Y102085D01*
G02X373462Y102072I-153J129D01*
G01X372716Y101326D01*
G02X372666Y101290I-140J142D01*
G02X372575Y101268I-91J178D01*
G01X363700D01*
X363677Y101280D01*
X363655Y101291D01*
G03X362957Y101463I-698J-1330D01*
G03X361455Y99961I0J-1502D01*
G03X362580Y98507I1502J0D01*
G01X362607Y98500D01*
X362633Y98485D01*
G02X362673Y98454I-102J-172D01*
G01X362705Y98422D01*
G02X362761Y98252I-142J-141D01*
G01X361376Y96867D01*
G03X360733Y95623I1631J-1631D01*
G01X360716Y95526D01*
G02X360642Y95481I-139J144D01*
G01X360606Y95469D01*
X360336Y95385D01*
X360298Y95373D01*
G02X360212Y95367I-57J192D01*
G01X359419Y96160D01*
G03X358497Y96542I-923J-924D01*
G01X353817D01*
X353802Y96550D01*
G03X353074Y96738I-728J-1316D01*
G03X351572Y95236I0J-1502D01*
G03X353066Y93734I1502J0D01*
G01X353077D01*
G03X353802Y93922I-3J1502D01*
G01X353817Y93930D01*
X357871D01*
X357884D01*
G02X358011Y93873I-13J-200D01*
G01X358325Y93558D01*
X358479Y93404D01*
G02X358477Y93335I-198J-29D01*
G01X358457Y93270D01*
Y93268D01*
X358366Y92978D01*
G02X358321Y92902I-190J61D01*
G01X358309Y92900D01*
X358224Y92885D01*
G03X356481Y91437I412J-2270D01*
G01X356446Y91346D01*
X356431Y91333D01*
X356056Y91254D01*
X356036Y91250D01*
X356005Y91243D01*
X355988Y91248D01*
X354955Y92281D01*
G03X353325Y92956I-1630J-1631D01*
G01X353324D01*
G03X351018Y90650I0J-2306D01*
G01Y90649D01*
G03X351693Y89019I2306J0D01*
G01X353633Y87079D01*
G03X355263Y86404I1630J1631D01*
G01X370350D01*
G02X370356Y86395I-163J-115D01*
G01X370360Y86389D01*
X370480Y86191D01*
Y86189D01*
X370541Y86087D01*
G02X370560Y86040I-174J-98D01*
G02X370566Y85994I-194J-49D01*
G01X370567Y85948D01*
X370545Y85901D01*
X370543Y85897D01*
G03X370369Y85197I1328J-702D01*
G01Y85180D01*
G03X370775Y84166I1502J13D01*
G01X370802Y84138D01*
X370816Y84103D01*
G02X370826Y84067I-187J-71D01*
G02X370829Y84032I-197J-35D01*
G01Y83755D01*
G02X370819Y83691I-200J-1D01*
G02X370816Y83684I-185J75D01*
G01X370803Y83650D01*
X370775Y83620D01*
G03Y81566I1096J-1027D01*
G01X370803Y81536D01*
X370816Y81502D01*
G02X370819Y81495I-182J-82D01*
G02X370829Y81431I-190J-63D01*
G01Y81155D01*
G02X370819Y81091I-200J-1D01*
G02X370816Y81084I-185J75D01*
G01X370803Y81050D01*
X370775Y81020D01*
G03Y78966I1096J-1027D01*
G01X370803Y78936D01*
X370816Y78902D01*
G02X370819Y78895I-182J-82D01*
G02X370829Y78831I-190J-63D01*
G01Y78555D01*
G02X370819Y78491I-200J-1D01*
G02X370816Y78484I-185J75D01*
G01X370803Y78450D01*
X370775Y78420D01*
G03Y76366I1096J-1027D01*
G01X370803Y76336D01*
X370816Y76302D01*
G02X370819Y76295I-182J-82D01*
G02X370829Y76231I-190J-63D01*
G01Y75955D01*
G02X370819Y75891I-200J-1D01*
G02X370816Y75884I-185J75D01*
G01X370803Y75850D01*
X370775Y75820D01*
G03X370369Y74793I1096J-1027D01*
G03X373373I1502J0D01*
G03X372967Y75820I-1502J0D01*
G01X372939Y75850D01*
X372926Y75884D01*
G02X372923Y75891I182J82D01*
G02X372913Y75955I190J63D01*
G01Y76231D01*
G02X372923Y76295I200J1D01*
G02X372926Y76302I185J-75D01*
G01X372939Y76336D01*
X372967Y76366D01*
G03Y78420I-1096J1027D01*
G01X372939Y78450D01*
X372926Y78484D01*
G02X372923Y78491I182J82D01*
G02X372913Y78555I190J63D01*
G01Y78831D01*
G02X372923Y78895I200J1D01*
G02X372926Y78902I185J-75D01*
G01X372939Y78936D01*
X372967Y78966D01*
G03Y81020I-1096J1027D01*
G01X372939Y81050D01*
X372926Y81084D01*
G02X372923Y81091I182J82D01*
G02X372913Y81155I190J63D01*
G01Y81431D01*
G02X372923Y81495I200J1D01*
G02X372926Y81502I185J-75D01*
G01X372939Y81536D01*
X372967Y81566D01*
G03Y83620I-1096J1027D01*
G01X372939Y83650D01*
X372926Y83684D01*
G02X372923Y83691I182J82D01*
G02X372913Y83755I190J63D01*
G01Y84031D01*
G02X372923Y84095I200J1D01*
G02X372926Y84102I185J-75D01*
G01X372939Y84136D01*
X372967Y84166D01*
G03X373373Y85193I-1096J1027D01*
G01Y85202D01*
G03X373199Y85897I-1502J-7D01*
G01X373193Y85908D01*
G02X373176Y85993I183J81D01*
G01X373177Y86046D01*
X373262Y86189D01*
Y86191D01*
X373382Y86388D01*
G02X373393Y86404I170J-105D01*
G01X390758D01*
G02X390872Y86369I1J-200D01*
G02X390888Y86356I-118J-162D01*
G01X392239Y85005D01*
G02X392241Y84976I-198J-28D01*
G01Y84913D01*
X392229Y84867D01*
X392212Y84834D01*
G03X392042Y84143I1332J-694D01*
G01Y84110D01*
G03X393544Y82638I1502J30D01*
G01X393558D01*
G03X393593Y82639I-25J1502D01*
G01X393614Y82640D01*
X393659Y82631D01*
G02X393755Y82585I-35J-197D01*
G01X393964Y82384D01*
G02X393986Y82359I-139J-144D01*
G01Y45945D01*
G03X394023Y45535I2306J1D01*
G01X394026Y45517D01*
Y45195D01*
G03X394689Y43594I2266J1D01*
G01X397333Y40950D01*
G03X398936Y40286I1603J1603D01*
G01X401794D01*
G03X402140Y40313I-3J2267D01*
G01X402144D01*
G03X403470Y40969I-306J2287D01*
G01X404168Y41668D01*
X406317Y43817D01*
G03X406992Y45447I-1631J1630D01*
G01Y45448D01*
G03X404686Y47754I-2306J0D01*
G01X404685D01*
G03X403055Y47079I0J-2306D01*
G01X402867Y46891D01*
G02X402857Y46889I-44J195D01*
G01X402529Y46898D01*
G02X402507Y46901I16J199D01*
G01X402452Y46964D01*
G03X402345Y47079I-1741J-1513D01*
G01X400896Y48528D01*
G02X400860Y48578I142J140D01*
G02X400838Y48669I178J91D01*
G01Y79845D01*
X400845Y79858D01*
X400886Y79886D01*
G03X400890Y79889I-113J154D01*
G01X400911Y79906D01*
X401033Y79958D01*
X401052Y79962D01*
G02X401120Y79964I40J-196D01*
G01X407046Y74038D01*
G02X407059Y74022I-149J-134D01*
G02X407094Y73908I-165J-113D01*
G01Y49492D01*
G03X407769Y47862I2306J0D01*
G01X409601Y46030D01*
G02X409654Y45928I-143J-139D01*
G02X409658Y45890I-196J-40D01*
G01Y39210D01*
G02X409615Y39168I-160J120D01*
G01X409482Y39072D01*
X409349Y38977D01*
X409338Y38969D01*
G02X409171Y38950I-104J171D01*
G01X409139Y38961D01*
G03X408683Y39032I-456J-1431D01*
G01X408680D01*
G03Y36028I0J-1502D01*
G01X408683D01*
G03X409137Y36098I1J1502D01*
G01X409141Y36100D01*
X409186Y36113D01*
G02X409254Y36118I48J-194D01*
G01X409263Y36117D01*
G02X409268Y36116I-37J-196D01*
G01X409283Y36113D01*
G02X409345Y36086I-48J-194D01*
G01X409481Y35988D01*
X409483D01*
X409625Y35887D01*
G02X409658Y35852I-128J-154D01*
G01Y29665D01*
G03X410334Y28034I2307J1D01*
G01X411603Y26766D01*
X412514Y25855D01*
G03X414145Y25180I1630J1631D01*
G01X414193Y25179D01*
G03X416452Y27486I-49J2307D01*
G01Y27492D01*
G03X416272Y28379I-2307J-6D01*
G03X415776Y29118I-2127J-892D01*
G01X414900Y29993D01*
G02X414857Y30058I142J141D01*
G01X414842Y30094D01*
Y30127D01*
X414844Y30156D01*
X414883Y30431D01*
G02X414899Y30486I198J-28D01*
G01X414980Y30529D01*
G03X416058Y31743I-1075J2041D01*
G01X416079Y31798D01*
X416081Y31800D01*
G02X416125Y31835I145J-137D01*
G01X416343Y31943D01*
G02X416345Y31944I90J-178D01*
G02X416487Y31956I87J-180D01*
G01X416490Y31955D01*
G03X416900Y31898I410J1445D01*
G03Y34902I0J1502D01*
G01X416898D01*
G03X416581Y34868I1J-1502D01*
G01X416537Y34859D01*
X416493Y34869D01*
G02X416413Y34908I45J195D01*
G01X416336Y34970D01*
X416173Y35101D01*
G02X416136Y35140I125J156D01*
G01Y48671D01*
G03X415461Y50301I-2306J0D01*
G01X414491Y51271D01*
G02X414439Y51361I141J142D01*
G01X414031Y51769D01*
G02X413972Y51911I141J142D01*
G01Y75920D01*
G03X413296Y77551I-2307J-1D01*
G01X412900Y77947D01*
Y77948D01*
X406746Y84103D01*
G02X406744Y84130I198J28D01*
G01Y101993D01*
G02X406748Y102030I200J-3D01*
G01Y102032D01*
G02X406801Y102133I196J-39D01*
G01X406861Y102193D01*
X406903Y102208D01*
G03X407243Y102383I-512J1412D01*
G03X407827Y103174I-850J1238D01*
G01Y103176D01*
G02X407876Y103256I190J-62D01*
G01X413130Y108510D01*
G03X413134Y108514I-922J926D01*
G03X413318Y108746I-925J923D01*
G01X413330Y108766D01*
X414115Y109551D01*
G03X414486Y110447I-896J896D01*
G01Y123480D01*
G03X414115Y124376I-1267J0D01*
G01X413344Y125147D01*
G02X413322Y125173I141J142D01*
G03X413261Y125264I-1115J-681D01*
G03X413132Y125415I-1055J-771D01*
G01X408074Y130472D01*
G02X408020Y130574I142J141D01*
G02X408016Y130613I196J40D01*
G01Y138086D01*
G02X408027Y138151I200J0D01*
G02X408074Y138227I189J-65D01*
G01X431724Y161876D01*
G03X432106Y162798I-924J923D01*
G01Y207576D01*
G02X432113Y207628I200J0D01*
G02X432164Y207717I193J-52D01*
G01X436399Y211952D01*
X443145Y218697D01*
G02X443353Y218743I141J-142D01*
G01X443362Y218739D01*
G02X443454Y218664I-75J-185D01*
G01X443469Y218641D01*
X443486Y218586D01*
Y142402D01*
G03X443868Y141480I1306J1D01*
G01X444465Y140883D01*
G02X444496Y140843I-141J-142D01*
G01X444506Y140826D01*
X444514Y140802D01*
G03X445949Y139745I1435J446D01*
G03X447451Y141247I0J1502D01*
G03X446395Y142682I-1503J0D01*
G01X446372Y142689D01*
X446330Y142714D01*
X446285Y142759D01*
X446154Y142889D01*
G02X446098Y143018I144J139D01*
G01Y216271D01*
G02X446116Y216292I160J-119D01*
G01X473508Y243684D01*
G02X473660Y243742I141J-142D01*
G01X473826Y243733D01*
X473828D01*
X473970Y243723D01*
G02X474102Y243653I-21J-199D01*
G01X474123Y243628D01*
X474136Y243612D01*
X474163Y243581D01*
G03X475293Y243069I1130J991D01*
G03X476795Y244552I0J1502D01*
G01Y244573D01*
G03X476689Y245127I-1502J0D01*
G01X476682Y245144D01*
X476673Y245188D01*
G02X476701Y245330I197J35D01*
G01X476702Y245331D01*
X476703Y245333D01*
X476895Y245621D01*
X476908Y245633D01*
X476910Y245635D01*
G02X476932Y245654I141J-141D01*
G01X482053D01*
G02X482091Y245650I-2J-200D01*
G02X482193Y245597I-37J-196D01*
G01X483643Y244147D01*
G02Y244087I-198J-30D01*
G01X483639Y244062D01*
X483552Y243836D01*
Y243834D01*
X483510Y243725D01*
X483506Y243716D01*
X483481Y243665D01*
G02X483453Y243633I-164J115D01*
G01X483327Y243579D01*
X483294Y243576D01*
G03X481910Y242078I119J-1498D01*
G03X484914I1502J0D01*
G01Y242080D01*
G03X484891Y242344I-1502J2D01*
G01X484882Y242395D01*
X484897Y242440D01*
G02X484946Y242520I190J-62D01*
G01X485001Y242575D01*
X485214Y242787D01*
X485230Y242792D01*
X485326Y242772D01*
G03X485585Y242746I259J1281D01*
G01X490745D01*
G03X491095Y242794I-1J1307D01*
G01X491097D01*
G02X491131Y242801I57J-192D01*
G03X492191Y243395I-142J1496D01*
G03X492425Y243852I-1201J903D01*
G01X492432Y243875D01*
X492457Y243917D01*
X499286Y250746D01*
G02X499483Y250796I141J-142D01*
G01X499504Y250787D01*
G02X499594Y250714I-76J-185D01*
G01X499609Y250692D01*
X499626Y250635D01*
Y169111D01*
G02X499604Y169020I-200J0D01*
G02X499568Y168970I-178J90D01*
G01X485321Y154723D01*
G03X484938Y153799I923J-924D01*
G01Y144678D01*
G02X484930Y144623I-200J1D01*
G01X484909Y144548D01*
X484896Y144526D01*
G03X484758Y144212I1310J-763D01*
G01X484755Y144201D01*
G03X484752Y144191I1451J-441D01*
G02X484751Y144189I-176J87D01*
G01X484715Y144128D01*
G02X484684Y144088I-172J102D01*
G01X478854Y138258D01*
G03X478472Y137336I924J-923D01*
G01Y127603D01*
G02X478443Y127572I-160J120D01*
G01X478360Y127504D01*
X478318Y127470D01*
X478266Y127427D01*
X478264D01*
X478195Y127371D01*
X478194Y127370D01*
X478161Y127344D01*
X478069Y127364D01*
G03X477592Y127414I-478J-2257D01*
G03X475286Y125109I0J-2306D01*
G01Y121236D01*
G02X475275Y121171I-200J0D01*
G01X475264Y121139D01*
X475258Y121132D01*
X475169Y121079D01*
X474971Y120960D01*
X474949Y120947D01*
G02X474858Y120920I-101J172D01*
G01X474809Y120918D01*
X474760Y120929D01*
X474737Y120940D01*
G03X474638Y120986I-684J-1344D01*
G01X474623Y120992D01*
X474575Y121022D01*
G03X474060Y121113I-518J-1428D01*
G01X474058D01*
G03X472539Y119594I0J-1519D01*
G03X473095Y118421I1515J0D01*
G01X473097Y118419D01*
X473119Y118400D01*
X473135Y118387D01*
X473149Y118371D01*
G02X473172Y118336I-155J-127D01*
G01X473198Y118280D01*
G02X473212Y118207I-186J-74D01*
G01Y117983D01*
G02X473194Y117900I-200J0D01*
G01X473181Y117873D01*
Y117871D01*
X473154Y117817D01*
G02X473121Y117772I-176J95D01*
G01X473102Y117753D01*
X473095Y117747D01*
G03X472556Y116594I964J-1153D01*
G03X474058Y115092I1502J0D01*
G01Y115091D01*
G03X474868Y115328I0J1503D01*
G01X474869Y115329D01*
G02X474952Y115359I108J-169D01*
G01X474993Y115364D01*
X475318Y115261D01*
X475329Y115257D01*
G02X475405Y115214I-58J-191D01*
G01X475437Y115184D01*
X475454Y115142D01*
G03X475961Y114376I2138J865D01*
G01X485561Y104776D01*
G02X485614Y104674I-143J-139D01*
G02X485618Y104636I-196J-40D01*
G01Y95111D01*
G03X490232I2307J0D01*
G01Y105213D01*
G02X490273Y105254I160J-119D01*
G01X491433D01*
X491443D01*
G02X491524Y105232I-11J-200D01*
G03X491617Y105182I773J1327D01*
G01X491640Y105171D01*
X491642Y105170D01*
X491677Y105140D01*
X491692Y105119D01*
G02X491646Y104840I-163J-116D01*
G01X491623Y104824D01*
X491599Y104815D01*
G03X490633Y103411I537J-1404D01*
G03X492135Y101909I1502J0D01*
G03X493627Y103235I0J1502D01*
G01X493637Y103320D01*
G03X493638Y103340I-199J20D01*
G01Y103411D01*
G03X493097Y104566I-1503J0D01*
G01X493095Y104567D01*
X493090Y104571D01*
X493088Y104572D01*
G03X493053Y104601I-976J-1142D01*
G01X493036Y104615D01*
X493011Y104645D01*
X492997Y104663D01*
G02X492958Y104764I160J120D01*
G01X492957Y104785D01*
X492962Y104897D01*
Y104899D01*
X492973Y105081D01*
X492984Y105129D01*
X493008Y105173D01*
G02X493068Y105236I172J-103D01*
G01X493072Y105239D01*
X493078Y105242D01*
G03X493829Y106561I-783J1319D01*
G03X492294Y108096I-1535J0D01*
G01X492293D01*
G03X491531Y107894I0J-1537D01*
G01X491508Y107881D01*
X491484Y107875D01*
G02X491433Y107868I-52J193D01*
G01X490942D01*
G02X490801Y107926I0J200D01*
G01X481103Y117622D01*
G02X481084Y117644I141J141D01*
G01Y136710D01*
G02X481086Y136740I200J2D01*
G02X481141Y136850I198J-30D01*
G01X484766Y140474D01*
X486532Y142240D01*
G02X486572Y142271I142J-141D01*
G01X486633Y142307D01*
G02X486635Y142308I89J-175D01*
G03X486645Y142311I-431J1454D01*
G01X486656Y142314D01*
G03X487722Y143762I-450J1448D01*
G01Y143763D01*
G03X487581Y144402I-1516J0D01*
G01X487572Y144421D01*
X487557Y144485D01*
G02X487552Y144530I195J44D01*
G01Y153175D01*
G02X487556Y153213I200J-2D01*
G02X487609Y153315I196J-37D01*
G01X501857Y167563D01*
G03X501986Y167714I-926J922D01*
G03X502047Y167805I-1054J772D01*
G02X502069Y167831I163J-116D01*
G01X507939Y173701D01*
X507943Y173704D01*
G03X508286Y174274I-877J916D01*
G01X508288Y174285D01*
X508291Y174296D01*
G03X508334Y174618I-1225J327D01*
G01Y294947D01*
G02X508336Y294975I200J0D01*
G01X515300Y301939D01*
G02X515402Y301992I139J-143D01*
G02X515440Y301996I40J-196D01*
G01X518155D01*
G03X519079Y302379I0J1306D01*
G01X520826Y304126D01*
G03X521208Y305048I-924J923D01*
G01Y307765D01*
G02X521215Y307816I200J-1D01*
G02X521266Y307906I193J-50D01*
G01X531247Y317886D01*
X531754Y318393D01*
X531774Y318396D01*
X552991D01*
G02X553023Y318393I-3J-200D01*
G01X553025D01*
G02X553131Y318339I-34J-197D01*
G01X557875Y313595D01*
G02X557928Y313494I-143J-140D01*
G01Y313492D01*
G02X557932Y313455I-196J-40D01*
G01Y267769D01*
G02X557929Y267737I-200J3D01*
G01Y267736D01*
X557928Y267731D01*
X557921Y267692D01*
G02X557909Y267654I-196J41D01*
G01X557903Y267639D01*
X557878Y267612D01*
G02X557848Y267586I-145J138D01*
G02X557822Y267571I-113J165D01*
G01X557769Y267544D01*
G03X557725Y267514I90J-179D01*
G01X557641Y267436D01*
G02X557543Y267392I-128J154D01*
G02X557494Y267391I-29J198D01*
G01X557490D01*
X557481Y267392D01*
G03X557323Y267399I-145J-1495D01*
G03X556400Y267073I11J-1502D01*
G01X556399Y267072D01*
X556387Y267062D01*
G02X556281Y267029I-110J167D01*
G01X556189D01*
G03X556106Y267011I0J-200D01*
G01X556052Y266986D01*
G02X555974Y266967I-85J181D01*
G02X555940Y266969I-5J200D01*
G02X555836Y267017I28J198D01*
G01X555835Y267018D01*
G03X554836Y267399I-1000J-1122D01*
G01X554834D01*
G03Y264395I0J-1502D01*
G01X554836D01*
G03X555770Y264722I-1J1501D01*
G01X555796Y264742D01*
X555840Y264757D01*
G02X555893Y264765I56J-192D01*
G01X555972D01*
G03X556063Y264787I0J200D01*
G01X556064Y264788D01*
G03X556068Y264790I-87J180D01*
G01X556073Y264792D01*
X556112Y264811D01*
G02X556295Y264797I78J-184D01*
G01X556351Y264761D01*
X556364Y264750D01*
X556370Y264745D01*
X556372Y264743D01*
X556384Y264733D01*
X556404Y264713D01*
G02X556449Y264644I-141J-141D01*
G02X556462Y264582I-187J-72D01*
G01X556472Y264394D01*
Y264392D01*
X556478Y264293D01*
X556480Y264245D01*
X556465Y264205D01*
G02X556419Y264135I-187J72D01*
G01X554226Y261942D01*
G02X554176Y261906I-140J142D01*
G02X554085Y261884I-91J178D01*
G01X542168D01*
G03X541744Y261813I-6J-1267D01*
G01X541743Y261812D01*
X541740Y261811D01*
X541733Y261808D01*
X541730Y261807D01*
X541721Y261803D01*
G03X541650Y261774I443J-1186D01*
G01X541274Y261512D01*
G03X541247Y261489I116J-163D01*
G01X539322Y259563D01*
X539307Y259554D01*
X539301Y259550D01*
G03X539071Y259369I688J-1111D01*
G03X539067Y259365I922J-926D01*
G01X537472Y257770D01*
X537430Y257745D01*
X537407Y257738D01*
G03X536356Y256174I446J-1435D01*
G01X536357Y256166D01*
Y256163D01*
X536362Y256114D01*
X536351Y256069D01*
G02X536311Y255996I-191J57D01*
G01X536137Y255800D01*
X536105Y255764D01*
G02X536019Y255714I-140J142D01*
G01X536017Y255713D01*
X535986Y255704D01*
X533919D01*
G02X533863Y255712I0J200D01*
G02X533845Y255718I54J193D01*
G01X533809Y255733D01*
X529766Y259776D01*
G03X529713Y259826I-895J-896D01*
G01X529709Y259830D01*
G03X528812Y260186I-897J-952D01*
G01X515817D01*
X515802Y260194D01*
G03X515074Y260382I-728J-1316D01*
G03Y257378I0J-1502D01*
G03X515802Y257566I0J1504D01*
G01X515817Y257574D01*
X528188D01*
G02X528224Y257571I1J-200D01*
G02X528329Y257516I-36J-197D01*
G01X532147Y253697D01*
X532371Y253473D01*
G03X532719Y253225I922J926D01*
G01X532749Y253210D01*
X535027Y250931D01*
X535030Y250927D01*
G03X535600Y250584I916J877D01*
G01X535611Y250582D01*
X535622Y250579D01*
G03X535944Y250536I327J1225D01*
G01X544361D01*
X544368D01*
G02X544539Y250427I-7J-200D01*
G01X544542Y250420D01*
G02X544546Y250411I-181J-86D01*
G01X544676Y250092D01*
G02X544690Y250014I-186J-74D01*
G02X544674Y249939I-200J3D01*
G01Y249938D01*
X544660Y249904D01*
X544635Y249848D01*
X544609Y249821D01*
X544608Y249820D01*
G03X544175Y248765I1069J-1055D01*
G03X545677Y247263I1502J0D01*
G01X545679D01*
G03X546613Y247590I-1J1501D01*
G01X546639Y247610D01*
X546683Y247625D01*
G02X546736Y247633I56J-192D01*
G01X546822D01*
G03X546878Y247641I0J200D01*
G01X546892Y247644D01*
X547104D01*
G02X547229Y247600I0J-200D01*
G01X547230Y247599D01*
G03X547233Y247597I835J1249D01*
G03X547251Y247583I931J1178D01*
G02X547261Y247575I-120J-160D01*
G03X547264Y247572I1062J1059D01*
G03X547351Y247510I915J1192D01*
G01X547355Y247508D01*
X547386Y247487D01*
X547400Y247479D01*
G03X547674Y247349I777J1285D01*
G03X547677Y247348I64J186D01*
G01X547692Y247343D01*
G03X548097Y247265I484J1422D01*
G03X548174Y247263I77J1499D01*
G01X548177D01*
G03X548240Y247264I8J1502D01*
G01X548257Y247265D01*
G03X549111Y247589I-81J1500D01*
G01X549112Y247590D01*
X549124Y247600D01*
G02X549230Y247633I110J-167D01*
G01X549322D01*
G03X549405Y247651I0J200D01*
G01X549459Y247676D01*
G02X549537Y247695I85J-181D01*
G02X549571Y247693I5J-200D01*
G02X549675Y247645I-28J-198D01*
G01X549676Y247644D01*
G03X550675Y247263I1000J1122D01*
G01X550677D01*
G03X552179Y248765I0J1502D01*
G03X551746Y249820I-1502J0D01*
G01X551745Y249821D01*
X551721Y249846D01*
X551694Y249904D01*
G02X551690Y249914I184J79D01*
G01X551674Y249954D01*
G02X551675Y250077I191J60D01*
G01X551738Y250236D01*
X551746Y250256D01*
Y250258D01*
X551812Y250418D01*
G02X551815Y250425I185J-75D01*
G02X551982Y250536I179J-89D01*
G01X556698D01*
G02X556812Y250482I-24J-198D01*
G01X557077Y250217D01*
G02X557130Y250115I-143J-139D01*
G02X557134Y250077I-196J-40D01*
G01Y229061D01*
G02X557112Y228970I-200J0D01*
G02X557076Y228920I-178J90D01*
G01X555808Y227652D01*
G03X555523Y227215I896J-896D01*
G01X555519Y227204D01*
G02X555496Y227167I-180J86D01*
G03X555495Y227165I176J-89D01*
G03X555234Y226392I1046J-784D01*
G01Y222748D01*
G02X555154Y222685I-160J120D01*
G01X554790Y222552D01*
G02X554670Y222546I-70J187D01*
G01X554641Y222554D01*
X554589Y222587D01*
X554569Y222611D01*
G03X553420Y223144I-1149J-972D01*
G03Y220140I0J-1502D01*
G03X554543Y220644I0J1503D01*
G01X554544Y220645D01*
X554570Y220674D01*
X554632Y220715D01*
G02X554789Y220733I99J-174D01*
G01X555012Y220652D01*
X555143Y220604D01*
G02X555234Y220536I-69J-188D01*
G01Y216982D01*
G03X555617Y216058I1306J0D01*
G01X563192Y208483D01*
X563217Y208441D01*
X563224Y208418D01*
G03X566094I1435J446D01*
G01X566101Y208441D01*
X566126Y208483D01*
X568727Y211084D01*
G03X569110Y212008I-923J924D01*
G01Y216192D01*
G02X569165Y216329I200J-1D01*
G01X569174Y216338D01*
X569396Y216539D01*
G02X569425Y216561I135J-148D01*
G02X569530Y216591I105J-170D01*
G01X569549D01*
X569558Y216590D01*
G03X569704Y216583I145J1495D01*
G03X569706I1J1502D01*
G01X569734D01*
G03X570787Y217040I-26J1502D01*
G01X570815Y217069D01*
X570930Y217119D01*
G02X570998Y217133I74J-186D01*
G01X571216D01*
X571265Y217123D01*
X571288Y217119D01*
X571401Y217069D01*
X571428Y217041D01*
G03X572508Y216583I1080J1044D01*
G03Y219587I0J1502D01*
G03X571429Y219130I0J-1502D01*
G01X571401Y219101D01*
X571286Y219051D01*
G02X571218Y219037I-74J186D01*
G01X571025D01*
G02X570985Y219041I0J200D01*
G01X570942Y219050D01*
X570920Y219054D01*
X570815Y219101D01*
X570788Y219130D01*
G03X569819Y219583I-1079J-1045D01*
G01X569782Y219586D01*
X569748Y219602D01*
G02X569701Y219633I86J181D01*
G01X569598Y219737D01*
G02X569548Y219870I150J132D01*
G01Y234818D01*
G03X569489Y234960I-200J0D01*
G01X569168Y235281D01*
G02X569132Y235331I142J140D01*
G02X569110Y235422I178J91D01*
G01Y243241D01*
G03X568727Y244165I-1306J0D01*
G01X566535Y246357D01*
G02X566536Y246415I198J26D01*
G01X566617Y246711D01*
X566634Y246772D01*
G02X566699Y246873I193J-53D01*
G02X566779Y246913I127J-154D01*
G01X566780D01*
G03X567918Y248371I-365J1458D01*
G03X566416Y249873I-1502J0D01*
G01X566413D01*
G03X566008Y249817I1J-1502D01*
G01X565992Y249812D01*
X565958Y249808D01*
G02X565818Y249847I-20J199D01*
G01X565594Y250014D01*
X565561Y250039D01*
G02X565524Y250077I124J157D01*
G01Y309636D01*
G02X565724Y309836I200J0D01*
G01X569938D01*
G02X569970Y309833I-3J-200D01*
G01X569972D01*
G02X570078Y309779I-34J-197D01*
G01X596950Y282906D01*
G02X596973Y282878I-142J-140D01*
G02X596994Y282839I-164J-114D01*
G01Y249870D01*
G02X596992Y249842I-200J0D01*
G02X596937Y249730I-198J28D01*
G01X594266Y247060D01*
X592952Y245746D01*
X592910Y245733D01*
G03X592882Y245724I446J-1434D01*
G03X592605Y245601I468J-1427D01*
G03X592491Y245529I744J-1305D01*
G01X592473Y245517D01*
G02X592260Y245524I-101J173D01*
G01Y245525D01*
G02X592175Y245652I111J166D01*
G01X592171Y245686D01*
G02X592175Y245751I199J20D01*
G01X592181Y245777D01*
X592206Y245823D01*
X592224Y245842D01*
G03X592633Y246872I-1093J1030D01*
G01Y246910D01*
X592632Y246939D01*
G03X591131Y248376I-1501J-65D01*
G03Y245372I0J-1502D01*
G01X591134D01*
G03X591483Y245413I0J1502D01*
G01X591488Y245415D01*
X591513Y245419D01*
X591541Y245421D01*
G02X591688Y245363I6J-200D01*
G01X591699Y245352D01*
X591756Y245288D01*
X591758Y245285D01*
X591915Y245102D01*
G02X591964Y244972I-151J-131D01*
G01Y244917D01*
X591950Y244843D01*
X591944Y244827D01*
G03X591848Y244299I1407J-529D01*
G01Y244297D01*
G03X591849Y244249I1503J7D01*
G01X591851Y244223D01*
Y244219D01*
G03X592255Y243270I1500J78D01*
G03X593292Y242796I1096J1027D01*
G03X593338Y242795I56J1501D01*
G01X593357D01*
G03X594057Y242967I2J1503D01*
G02X594150Y242990I93J-177D01*
G01X594731D01*
G02X594769Y242986I-2J-200D01*
G02X594871Y242933I-37J-196D01*
G01X596964Y240840D01*
G02X596966Y240811I-198J-28D01*
G01Y231763D01*
G02X596958Y231717I-200J11D01*
G02X596867Y231603I-191J59D01*
G01X596790Y231558D01*
X596612Y231454D01*
G02X596587Y231442I-99J174D01*
G02X596529Y231428I-75J185D01*
G01X596527D01*
G02X596512Y231427I-21J199D01*
G01X596399D01*
X596359Y231436D01*
X596334Y231450D01*
G03X595641Y231619I-693J-1334D01*
G01X595634D01*
G03Y228615I0J-1502D01*
G01X595637D01*
G03X596370Y228806I0J1503D01*
G01X596371Y228807D01*
X596382Y228813D01*
G02X596471Y228833I87J-180D01*
G01X596523Y228832D01*
X596872Y228628D01*
G02X596941Y228556I-105J-170D01*
G02X596966Y228458I-175J-97D01*
G01Y215997D01*
G02X596947Y215917I-200J5D01*
G01X596925Y215908D01*
X596843Y215874D01*
G02X596625Y215916I-78J184D01*
G01X583515Y229027D01*
X583490Y229069D01*
X583483Y229092D01*
G03X582048Y230148I-1435J-447D01*
G03X580546Y228646I0J-1502D01*
G01X580545D01*
G03X581602Y227211I1503J0D01*
G01X581603D01*
G02X581685Y227161I-60J-191D01*
G01X595634Y213212D01*
G02X595636Y213183I-198J-28D01*
G01Y181731D01*
G02X595626Y181669I-200J0D01*
G02X595622Y181657I-192J57D01*
G01X595608Y181623D01*
X595580Y181594D01*
X595576Y181589D01*
X595570Y181582D01*
X572682Y158694D01*
G02X572661Y158676I-140J142D01*
G01X561286D01*
X561271Y158684D01*
G03X560543Y158872I-728J-1316D01*
G03X559041Y157370I0J-1502D01*
G03X560535Y155868I1502J0D01*
G01X560546D01*
G03X561271Y156056I-3J1502D01*
G01X561286Y156064D01*
X571451D01*
G02X571636Y155940I0J-200D01*
G01X571681Y155831D01*
X571676Y155806D01*
X571034Y155165D01*
X558429Y142561D01*
G02X558420Y142554I-127J154D01*
G01X554483D01*
G02X554448Y142586I117J163D01*
G01X554320Y142763D01*
X554255Y142854D01*
G02X554222Y142960I167J110D01*
G01Y143039D01*
X554231Y143069D01*
G03X554300Y143518I-1433J450D01*
G03X552798Y145020I-1502J0D01*
G03X551296Y143529I0J-1502D01*
G01Y143515D01*
G03X551365Y143066I1502J1D01*
G01X551368Y143056D01*
X551374Y143037D01*
X551380Y142986D01*
G02X551349Y142864I-199J-14D01*
G01X551274Y142759D01*
X551152Y142590D01*
G02X551115Y142554I-157J124D01*
G01X549057D01*
X549034Y142566D01*
X549021Y142572D01*
G03X548314Y142749I-708J-1327D01*
G01X548311D01*
G03Y139745I0J-1502D01*
G01X548314D01*
G03X549021Y139922I-1J1504D01*
G01X549034Y139928D01*
X549057Y139940D01*
X557776D01*
G02X557951Y139835I-1J-200D01*
G01X557994Y139732D01*
Y139720D01*
X557980Y139686D01*
G02X557937Y139620I-186J74D01*
G01X550290Y131974D01*
G03X550006Y131538I897J-895D01*
G01X549972Y131451D01*
G03X549962Y131416I187J-72D01*
G01X549956Y131381D01*
X549955Y131375D01*
G03X549920Y131081I1231J-296D01*
G01Y130698D01*
X549915Y130675D01*
G03X549880Y130375I1271J-300D01*
G01Y114162D01*
G03X549927Y113812I1306J-3D01*
G01X549951Y113726D01*
G02X549923Y113676I-187J72D01*
G02X549921Y113673I-167J109D01*
G01X549804Y113523D01*
X549787Y113501D01*
X549729Y113428D01*
G02X549671Y113378I-157J123D01*
G02X549639Y113363I-101J173D01*
G01X549603Y113350D01*
X541267D01*
G03X540371Y112979I0J-1267D01*
G01X538224Y110832D01*
G03X538217Y110825I920J-927D01*
G01X537789Y110397D01*
X536755Y109362D01*
G02X536643Y109308I-139J144D01*
G02X536616Y109306I-28J198D01*
G01X534688D01*
G02X534507Y109423I1J200D01*
G01X534460Y109532D01*
X534360Y109765D01*
G02X534344Y109845I184J78D01*
G01X534398Y109979D01*
X534422Y110006D01*
G03X534895Y111223I-1329J1217D01*
G01X534894Y113128D01*
Y114623D01*
G03X531290I-1802J0D01*
G01Y113128D01*
X531289Y111223D01*
G03X531762Y110006I1802J0D01*
G01X531786Y109979D01*
X531840Y109845D01*
G02X531824Y109765I-200J-2D01*
G01X531724Y109532D01*
X531677Y109423D01*
G02X531496Y109306I-182J83D01*
G01X531237D01*
G03X530315Y108924I1J-1306D01*
G01X526176Y104784D01*
G02X526105Y104738I-142J141D01*
G02X525938Y104750I-70J187D01*
G02X525922Y104759I90J179D01*
G02X525746Y105091I224J332D01*
G01Y107649D01*
G03X522140I-1803J0D01*
G01Y104249D01*
G03X523334Y102551I1804J0D01*
G01X523375Y102536D01*
X523435Y102478D01*
X523448Y102463D01*
G02X523485Y102394I-155J-127D01*
G01X523496Y102345D01*
Y102343D01*
X523518Y102248D01*
G02X523487Y102101I-197J-35D01*
G01X523479Y102090D01*
G02X523463Y102072I-157J124D01*
G01X522717Y101326D01*
G02X522667Y101290I-140J142D01*
G02X522576Y101268I-91J178D01*
G01X513701D01*
X513678Y101280D01*
X513656Y101291D01*
G03X512958Y101463I-698J-1330D01*
G03X511456Y99961I0J-1502D01*
G03X512581Y98507I1502J0D01*
G01X512608Y98500D01*
X512634Y98485D01*
G02X512674Y98454I-102J-172D01*
G01X512706Y98422D01*
G02X512762Y98252I-142J-141D01*
G01X511377Y96867D01*
G03X510734Y95624I1631J-1631D01*
G01X510718Y95527D01*
G02X510645Y95482I-139J144D01*
G01X510381Y95398D01*
X510379D01*
X510331Y95383D01*
G02X510297Y95376I-57J191D01*
G02X510271Y95374I-28J198D01*
G01X510249D01*
X510213Y95389D01*
G02X510148Y95432I76J185D01*
G01X509420Y96160D01*
G03X508498Y96542I-923J-924D01*
G01X503818D01*
X503803Y96550D01*
G03X503075Y96738I-728J-1316D01*
G03X501573Y95236I0J-1502D01*
G03X503067Y93734I1502J0D01*
G01X503078D01*
G03X503803Y93922I-3J1502D01*
G01X503818Y93930D01*
X507872D01*
X507885D01*
G02X508012Y93873I-13J-200D01*
G01X508326Y93558D01*
X508480Y93404D01*
G02X508478Y93335I-198J-29D01*
G01X508458Y93270D01*
Y93268D01*
X508367Y92978D01*
G02X508322Y92902I-190J61D01*
G01X508310Y92900D01*
X508225Y92885D01*
G03X506482Y91437I412J-2270D01*
G01X506447Y91346D01*
X506432Y91333D01*
X506057Y91254D01*
X506037Y91250D01*
X506006Y91243D01*
X505989Y91248D01*
X504956Y92281D01*
G03X503325Y92956I-1630J-1631D01*
G01X503277Y92957D01*
G03X501018Y90650I49J-2307D01*
G01Y90644D01*
G03X501198Y89757I2307J6D01*
G03X501694Y89018I2127J892D01*
G01X502823Y87890D01*
X503634Y87079D01*
G03X505264Y86404I1630J1631D01*
G01X520351D01*
G02X520357Y86395I-163J-115D01*
G01X520361Y86389D01*
X520481Y86191D01*
Y86189D01*
X520542Y86087D01*
G02X520561Y86040I-174J-98D01*
G02X520567Y85994I-194J-49D01*
G01X520568Y85948D01*
X520546Y85901D01*
X520544Y85897D01*
G03X520370Y85197I1328J-702D01*
G01Y85180D01*
G03X520776Y84166I1502J13D01*
G01X520803Y84138D01*
X520817Y84103D01*
G02X520827Y84067I-187J-71D01*
G02X520830Y84032I-197J-35D01*
G01Y83755D01*
G02X520820Y83691I-200J-1D01*
G02X520817Y83684I-185J75D01*
G01X520804Y83650D01*
X520776Y83620D01*
G03Y81566I1096J-1027D01*
G01X520804Y81536D01*
X520817Y81502D01*
G02X520820Y81495I-182J-82D01*
G02X520830Y81431I-190J-63D01*
G01Y81155D01*
G02X520820Y81091I-200J-1D01*
G02X520817Y81084I-185J75D01*
G01X520804Y81050D01*
X520776Y81020D01*
G03Y78966I1096J-1027D01*
G01X520804Y78936D01*
X520817Y78902D01*
G02X520820Y78895I-182J-82D01*
G02X520830Y78831I-190J-63D01*
G01Y78555D01*
G02X520820Y78491I-200J-1D01*
G02X520817Y78484I-185J75D01*
G01X520804Y78450D01*
X520776Y78420D01*
G03Y76366I1096J-1027D01*
G01X520804Y76336D01*
X520817Y76302D01*
G02X520820Y76295I-182J-82D01*
G02X520830Y76231I-190J-63D01*
G01Y75955D01*
G02X520820Y75891I-200J-1D01*
G02X520817Y75884I-185J75D01*
G01X520804Y75850D01*
X520776Y75820D01*
G03X520370Y74793I1096J-1027D01*
G03X523374I1502J0D01*
G03X522968Y75820I-1502J0D01*
G01X522940Y75850D01*
X522927Y75884D01*
G02X522924Y75891I182J82D01*
G02X522914Y75955I190J63D01*
G01Y76231D01*
G02X522924Y76295I200J1D01*
G02X522927Y76302I185J-75D01*
G01X522940Y76336D01*
X522968Y76366D01*
G03Y78420I-1096J1027D01*
G01X522940Y78450D01*
X522927Y78484D01*
G02X522924Y78491I182J82D01*
G02X522914Y78555I190J63D01*
G01Y78831D01*
G02X522924Y78895I200J1D01*
G02X522927Y78902I185J-75D01*
G01X522940Y78936D01*
X522968Y78966D01*
G03Y81020I-1096J1027D01*
G01X522940Y81050D01*
X522927Y81084D01*
G02X522924Y81091I182J82D01*
G02X522914Y81155I190J63D01*
G01Y81431D01*
G02X522924Y81495I200J1D01*
G02X522927Y81502I185J-75D01*
G01X522940Y81536D01*
X522968Y81566D01*
G03Y83620I-1096J1027D01*
G01X522940Y83650D01*
X522927Y83684D01*
G02X522924Y83691I182J82D01*
G02X522914Y83755I190J63D01*
G01Y84031D01*
G02X522924Y84095I200J1D01*
G02X522927Y84102I185J-75D01*
G01X522940Y84136D01*
X522968Y84166D01*
G03X523374Y85193I-1096J1027D01*
G01Y85202D01*
G03X523200Y85897I-1502J-7D01*
G01X523194Y85908D01*
G02X523177Y85993I183J81D01*
G01X523178Y86046D01*
X523263Y86189D01*
Y86191D01*
X523383Y86388D01*
G02X523394Y86404I170J-105D01*
G01X540759D01*
G02X540873Y86369I1J-200D01*
G02X540889Y86356I-118J-162D01*
G01X542240Y85005D01*
G02X542242Y84976I-198J-28D01*
G01Y84913D01*
X542230Y84867D01*
X542213Y84834D01*
G03X542043Y84143I1332J-694D01*
G01Y84110D01*
G03X543545Y82638I1502J30D01*
G01X543546D01*
G03X543609Y82639I8J1502D01*
G01X543651Y82641D01*
X543687Y82627D01*
G02X543750Y82589I-70J-187D01*
G01X543804Y82538D01*
G02X543806Y82536I-140J-142D01*
G01X543971Y82377D01*
G02X543986Y82359I-146J-137D01*
G01Y76586D01*
G03X544777Y74848I2307J1D01*
G01X544842Y74792D01*
X544844Y74769D01*
X544846Y74691D01*
X544851Y74497D01*
Y74490D01*
X544853Y74436D01*
X544723Y74307D01*
X544662Y74247D01*
G03X544162Y73498I1632J-1631D01*
G03X543986Y72622I2131J-884D01*
G01Y72615D01*
G03X546293Y70308I2307J0D01*
G01X546330D01*
G03X547176Y70484I-39J2307D01*
G03X547925Y70984I-882J2132D01*
G01X549227Y72287D01*
X550163Y73223D01*
G03X550838Y74853I-1631J1630D01*
G01Y84546D01*
G02X550893Y84596I160J-120D01*
G01X550916Y84610D01*
X551260Y84754D01*
G02X551368Y84767I77J-184D01*
G01X553689Y82446D01*
G02Y82387I-198J-30D01*
G01Y82384D01*
X553668Y82254D01*
X553637Y82059D01*
G02X553532Y81922I-196J41D01*
G01X553505Y81908D01*
G03X552709Y80581I708J-1327D01*
G03X554211Y79079I1502J0D01*
G03X555713Y80572I0J1502D01*
G01Y80582D01*
G03X555637Y81054I-1502J0D01*
G01X555631Y81072D01*
X555626Y81108D01*
Y81109D01*
X555620Y81146D01*
X555629Y81184D01*
G02X555661Y81254I194J-47D01*
G01X555791Y81436D01*
G02X555889Y81508I162J-118D01*
G02X555952Y81518I62J-190D01*
G01X562035D01*
G03X563710Y82239I-1J2308D01*
G01X563714Y82243D01*
X565886Y84414D01*
G03X566562Y86045I-1631J1632D01*
G01Y86102D01*
X566561Y86125D01*
G03X564255Y88352I-2305J-79D01*
G03X562624Y87677I-1J-2306D01*
G01X562393Y87446D01*
G02X562370Y87444I-29J198D01*
G01X562321D01*
G02X562191Y87492I0J200D01*
G01X562185Y87497D01*
G03X560701Y88038I-1484J-1765D01*
G01X560083D01*
G02X560049Y88068I114J164D01*
G01X559971Y88164D01*
X559841Y88325D01*
G02X559831Y88341I165J114D01*
G02X559816Y88377I176J95D01*
G01X559800Y88439D01*
X559810Y88484D01*
G03X559843Y88791I-1469J313D01*
G03Y88793I-1502J1D01*
G01Y88816D01*
G03X558517Y90293I-1502J-15D01*
G01X558461Y90299D01*
G03X558330Y90304I-123J-1498D01*
G01X558322D01*
G03X557410Y89980I20J-1502D01*
G03X557344Y89925I928J-1181D01*
G01X557338Y89920D01*
X557331Y89914D01*
X557299Y89893D01*
G02X557121Y89878I-104J170D01*
G01X557027Y89919D01*
X557025D01*
X556785Y90026D01*
G02X556777Y90030I85J181D01*
G01X556723Y90057D01*
X556704Y90088D01*
Y102018D01*
G02X556715Y102083I200J0D01*
G01X556725Y102112D01*
X556743Y102136D01*
X556845Y102167D01*
G03X557500Y102576I-452J1453D01*
G03X557862Y103218I-1105J1046D01*
G01X557871Y103250D01*
X563470Y108849D01*
G03X563852Y109771I-924J923D01*
G01Y114702D01*
G02X563853Y114725I200J3D01*
G02X563869Y114783I199J-24D01*
G02X563919Y114852I183J-80D01*
G01X564141Y115050D01*
G02X564212Y115091I133J-149D01*
G01X564252Y115104D01*
X564294Y115100D01*
G03X564451Y115092I155J1494D01*
G03X565953Y116594I0J1502D01*
G03X565940Y116794I-1502J3D01*
G03X565407Y117753I-1489J-200D01*
G01X565390Y117766D01*
X565363Y117800D01*
X565317Y117895D01*
G02X565297Y117982I180J87D01*
G01Y118206D01*
G02X565317Y118293I200J0D01*
G01X565363Y118388D01*
X565390Y118422D01*
X565407Y118435D01*
G03X565953Y119594I-957J1159D01*
G03X564451Y121096I-1502J0D01*
G03X564294Y121088I-2J-1502D01*
G01X564252Y121084D01*
X564212Y121097D01*
G02X564141Y121138I62J190D01*
G01X563919Y121336D01*
G02X563869Y121405I133J149D01*
G02X563853Y121463I183J82D01*
G02X563852Y121486I199J20D01*
G01Y122490D01*
Y122491D01*
G02X563906Y122627I200J-1D01*
G02X563937Y122654I146J-137D01*
G01X564203Y122841D01*
G02X564291Y122875I114J-164D01*
G01X564340Y122882D01*
X564355Y122877D01*
G03X564882Y122781I528J1406D01*
G01X564885D01*
G03Y125785I0J1502D01*
G01X564882D01*
G03X564355Y125689I1J-1502D01*
G01X564340Y125684D01*
X564291Y125691D01*
G02X564203Y125725I26J198D01*
G01X563937Y125912D01*
G02X563906Y125939I115J164D01*
G02X563852Y126075I146J137D01*
G01Y130866D01*
G02X563861Y130926I200J1D01*
G02X563910Y131007I191J-60D01*
G01X572034Y139130D01*
X580707Y147803D01*
G02X580859Y147861I141J-142D01*
G01X581156Y147845D01*
G02X581236Y147824I-10J-200D01*
G01X581273Y147805D01*
X581300Y147771D01*
G03X582467Y147215I1167J947D01*
G01X582468D01*
G03X583960Y148541I0J1502D01*
G01X583966Y148598D01*
G03X583971Y148717I-1498J123D01*
G03X583414Y149885I-1503J0D01*
G01X583397Y149898D01*
X583370Y149932D01*
X583361Y149949D01*
G02X583340Y150029I179J90D01*
G01X583324Y150326D01*
G02X583382Y150478I200J11D01*
G01X586960Y154056D01*
G02X587157Y154106I141J-142D01*
G01X587178Y154097D01*
G02X587268Y154024I-76J-185D01*
G01X587283Y154002D01*
X587300Y153945D01*
Y144624D01*
G02X587278Y144534I-200J1D01*
G01X587269Y144517D01*
G03X587161Y144289I1299J-755D01*
G01X587156Y144275D01*
X587145Y144243D01*
X587144Y144241D01*
X587141Y144231D01*
X587140Y144228D01*
G03X587137Y144219I1423J-479D01*
G02X587135Y144213I-191J60D01*
G03X587132Y144205I1404J-531D01*
G01X587128Y144193D01*
G02X587123Y144181I-187J71D01*
G02X587084Y144126I-180J87D01*
G01X581216Y138258D01*
G03X580834Y137336I924J-923D01*
G01Y127603D01*
G02X580805Y127572I-160J120D01*
G01X580722Y127504D01*
X580680Y127470D01*
X580628Y127427D01*
X580626D01*
X580557Y127371D01*
X580556Y127370D01*
X580523Y127344D01*
X580431Y127364D01*
G03X579954Y127414I-478J-2257D01*
G03X577648Y125109I0J-2306D01*
G01Y121236D01*
G02X577637Y121171I-200J0D01*
G01X577626Y121139D01*
X577620Y121132D01*
X577531Y121079D01*
X577333Y120960D01*
X577311Y120947D01*
G02X577220Y120920I-101J172D01*
G01X577171Y120918D01*
X577122Y120929D01*
X577099Y120940D01*
G03X577000Y120986I-684J-1344D01*
G01X576985Y120992D01*
X576937Y121022D01*
G03X576422Y121113I-518J-1428D01*
G01X576420D01*
G03X574901Y119594I0J-1519D01*
G03X575457Y118421I1515J0D01*
G01X575459Y118419D01*
X575481Y118400D01*
X575497Y118387D01*
X575511Y118371D01*
G02X575534Y118336I-155J-127D01*
G01X575560Y118280D01*
G02X575574Y118207I-186J-74D01*
G01Y117983D01*
G02X575556Y117900I-200J0D01*
G01X575543Y117873D01*
Y117871D01*
X575516Y117817D01*
G02X575483Y117772I-176J95D01*
G01X575464Y117753D01*
X575457Y117747D01*
G03X574918Y116594I964J-1153D01*
G03X576420Y115092I1502J0D01*
G03X577495Y115545I0J1502D01*
G01X577503Y115553D01*
G02X577546Y115583I135J-148D01*
G01X577669Y115638D01*
X577715Y115635D01*
X577716D01*
X577816Y115630D01*
G02X577848Y115626I-9J-200D01*
G02X577978Y115533I-42J-196D01*
G01Y115532D01*
G03X577986Y115520I1922J1273D01*
G01X577990Y115513D01*
G03X578323Y115092I1963J1211D01*
G01X587923Y105492D01*
G02X587976Y105390I-143J-139D01*
G02X587980Y105352I-196J-40D01*
G01Y95111D01*
G03X592594I2307J0D01*
G01Y105214D01*
G02X592634Y105254I160J-120D01*
G01X593795D01*
X593805D01*
G02X593886Y105232I-11J-200D01*
G03X593979Y105182I773J1327D01*
G01X594002Y105171D01*
X594004Y105170D01*
X594039Y105140D01*
X594054Y105119D01*
G02X594008Y104840I-163J-116D01*
G01X593985Y104824D01*
X593961Y104815D01*
G03X592995Y103411I537J-1404D01*
G03X595999I1502J0D01*
G03X595420Y104596I-1502J0D01*
G01X595402Y104610D01*
X595365Y104655D01*
G02X595335Y104704I154J128D01*
G01Y104706D01*
G02X595319Y104793I184J79D01*
G01X595324Y104897D01*
Y104899D01*
X595335Y105081D01*
X595346Y105129D01*
X595370Y105173D01*
G02X595430Y105236I172J-103D01*
G01X595434Y105239D01*
X595440Y105242D01*
G03X596191Y106561I-783J1319D01*
G03X594656Y108096I-1535J0D01*
G01X594655D01*
G03X593893Y107894I0J-1537D01*
G01X593870Y107881D01*
X593846Y107875D01*
G02X593795Y107868I-52J193D01*
G01X593304D01*
G02X593163Y107926I0J200D01*
G01X587048Y114039D01*
X583465Y117623D01*
G02X583446Y117645I141J141D01*
G01Y136710D01*
G02X583448Y136740I200J2D01*
G02X583503Y136850I198J-30D01*
G01X587165Y140511D01*
X588967Y142313D01*
X588993Y142321D01*
G03X590070Y143749I-425J1441D01*
G01Y143776D01*
G03X590042Y144055I-1503J-10D01*
G01X590036Y144084D01*
G03X589947Y144359I-1467J-323D01*
G01Y144361D01*
G03X589932Y144393I-1368J-622D01*
G01X589914Y144433D01*
Y153311D01*
G02X589932Y153332I160J-119D01*
G01X609081Y172481D01*
G02X609085Y172485I143J-139D01*
G03X609160Y172562I-870J922D01*
G03X609480Y173403I-946J841D01*
G01Y174497D01*
G02X609484Y174535I200J-2D01*
G02X609537Y174637I196J-37D01*
G01X609694Y174794D01*
G03X610076Y175716I-924J923D01*
G01Y298079D01*
G03X609694Y299001I-1306J-1D01*
G01X592866Y315828D01*
G02X592817Y315909I142J141D01*
G02X592808Y315969I191J59D01*
G01Y338450D01*
G03X592504Y339287I-1306J-1D01*
G02X592500Y339326I196J40D01*
G01Y341918D01*
G03X592441Y342060I-200J0D01*
G01X569986Y364515D01*
G02X569950Y364565I142J140D01*
G02X569928Y364656I178J91D01*
G01Y373147D01*
G03X569913Y373223I-200J0D01*
G01X569884Y373292D01*
G02X569871Y373346I186J73D01*
G02X569870Y373366I199J20D01*
G01Y376550D01*
X569872Y376588D01*
X569885Y376618D01*
G02X569921Y376674I184J-79D01*
G01X570005Y376766D01*
G02X570049Y376801I145J-137D01*
G01X570088Y376822D01*
X570121Y376826D01*
X570123D01*
X570130Y376827D01*
G03X570361Y376876I-195J1489D01*
G03X570534Y376938I-419J1442D01*
G03X571440Y378265I-595J1379D01*
G01Y378279D01*
G03X570143Y379805I-1501J38D01*
G01X570137Y379806D01*
X570123Y379808D01*
X570085Y379820D01*
X570083Y379821D01*
G02X570034Y379844I60J191D01*
G02X570004Y379868I110J168D01*
G01X569956Y379921D01*
X569924Y379956D01*
G02X569885Y380019I148J135D01*
G01X569870Y380057D01*
Y426950D01*
G02X569874Y426987I200J-3D01*
G01Y426989D01*
G02X569927Y427090I196J-39D01*
G01X576014Y433177D01*
G02X576120Y433231I140J-143D01*
G01X576122D01*
G02X576154Y433234I35J-197D01*
G01X588859D01*
G02X588940Y433216I-2J-200D01*
G01X589298Y432850D01*
G03X589976Y432296I2808J2745D01*
G03X590628Y431957I2129J3299D01*
G01X593496Y430790D01*
G02X593597Y430699I-75J-185D01*
G01X593606Y430680D01*
X593656Y430573D01*
G02X593664Y430425I-181J-84D01*
G01X593660Y430410D01*
X593659Y430408D01*
G03X593656Y430399I1705J-573D01*
G01Y430395D01*
X593654Y430389D01*
G03X593648Y430371I1706J-579D01*
G01X593647Y430367D01*
G03X593635Y430323I184J-74D01*
G01Y430322D01*
G03X593631Y430309I1719J-536D01*
G01Y430308D01*
X593627Y430293D01*
Y430291D01*
X593626Y430289D01*
Y430288D01*
X593620Y430264D01*
G03X593614Y430237I1756J-404D01*
G01Y430236D01*
G03X593610Y430220I1746J-445D01*
G01Y430217D01*
X593606Y430198D01*
G03X593592Y430113I1771J-335D01*
G03X593578Y429976I1785J-252D01*
G03X593574Y429860I1798J-120D01*
G01Y426460D01*
G03X597180I1803J0D01*
G01Y428426D01*
G02X597293Y428599I200J-7D01*
G01X597400D01*
G02X597432Y428596I-3J-200D01*
G01X597434D01*
G02X597540Y428542I-34J-197D01*
G01X598006Y428076D01*
G03X598596Y427591I2754J2749D01*
G01X604076Y423929D01*
X604108Y423907D01*
X604129Y423877D01*
G02X604161Y423806I-163J-116D01*
G01X604168Y423775D01*
Y423773D01*
X604189Y423687D01*
Y423639D01*
X604183Y423615D01*
X604181Y423606D01*
X604168Y423557D01*
X604159Y423539D01*
G03X603976Y422748I1620J-791D01*
G01Y419347D01*
G03X607582I1803J0D01*
G01Y421220D01*
G02X607685Y421388I200J-7D01*
G01X607880D01*
G02X607893Y421380I-98J-174D01*
G01X608078Y421257D01*
X608342Y421082D01*
X608350Y421077D01*
X631062Y402985D01*
G03X631429Y402726I2424J3045D01*
G03X631549Y402654I2062J3300D01*
G03X631750Y402547I1928J3380D01*
G01X631866Y402489D01*
X631901Y402468D01*
X640624Y393745D01*
G03X640766Y393686I142J141D01*
G01X649466D01*
G02X649555Y393665I0J-200D01*
G01X651221Y392832D01*
X658783Y389052D01*
X658800Y389033D01*
X658881Y388920D01*
X658889Y388877D01*
G03X660365Y387651I1477J276D01*
G01X660367D01*
G03X660501Y387658I-11J1502D01*
G01X660543Y387662D01*
G03X661495Y388162I-177J1494D01*
G02X661562Y388212I150J-132D01*
G01X661566Y388214D01*
X666468D01*
X666497Y388202D01*
X666524Y388174D01*
X666545Y388153D01*
G03X667663Y387651I1122J1003D01*
G03X667941Y387676I5J1502D01*
G01X667965Y387678D01*
G03X668260Y387508I2106J3314D01*
G03X670065Y387068I1806J3487D01*
G01X670067D01*
G03X670212Y387071I-9J3927D01*
G01X670214D01*
G03X670271Y387074I-178J3922D01*
G01X670281D01*
X670353Y387078D01*
G02X670389Y387049I-107J-169D01*
G01X673929Y383509D01*
G02X673983Y383403I-143J-140D01*
G01Y383401D01*
G02X673986Y383369I-197J-35D01*
G01Y354245D01*
G02X673982Y354206I-200J1D01*
G01Y354205D01*
X673970Y354146D01*
X673956Y354115D01*
X673928Y354084D01*
X673926Y354082D01*
G03X673920Y354075I148J-133D01*
G01X673913Y354066D01*
X668840Y348993D01*
G02X668790Y348957I-140J142D01*
G02X668699Y348935I-91J178D01*
G01X666554D01*
G03X666354Y348735I0J-200D01*
G01Y318596D01*
G03X666554Y318396I200J0D01*
G01X667478D01*
G02X667638Y318316I0J-200D01*
G01Y266211D01*
G02X667616Y266120I-200J0D01*
G02X667580Y266070I-178J90D01*
G01X660601Y259091D01*
G02X660551Y259055I-140J142D01*
G02X660460Y259033I-91J178D01*
G01X646898D01*
G02X646807Y259055I0J200D01*
G02X646757Y259091I90J178D01*
G01X646484Y259364D01*
G03X645562Y259746I-923J-924D01*
G01X642350D01*
G03X641428Y259364I1J-1306D01*
G01X639834Y257770D01*
X639792Y257745D01*
X639769Y257738D01*
G03X638718Y256174I446J-1435D01*
G01X638719Y256166D01*
Y256163D01*
X638724Y256114D01*
X638713Y256069D01*
G02X638673Y255996I-191J57D01*
G01X638499Y255800D01*
X638467Y255764D01*
G02X638381Y255714I-140J142D01*
G01X638379Y255713D01*
X638348Y255704D01*
X636281D01*
G02X636225Y255712I0J200D01*
G02X636207Y255718I54J193D01*
G01X636171Y255733D01*
X632128Y259776D01*
G03X632075Y259826I-895J-896D01*
G01X632071Y259830D01*
G03X631174Y260186I-897J-952D01*
G01X618179D01*
X618164Y260194D01*
G03X617436Y260382I-728J-1316D01*
G03Y257378I0J-1502D01*
G03X618164Y257566I0J1504D01*
G01X618179Y257574D01*
X630550D01*
G02X630586Y257571I1J-200D01*
G02X630691Y257516I-36J-197D01*
G01X634509Y253697D01*
X634733Y253473D01*
G03X635081Y253225I922J926D01*
G01X635111Y253210D01*
X635781Y252540D01*
G03X635923Y252481I142J141D01*
G01X657086D01*
G02X657118Y252478I-3J-200D01*
G01X657120D01*
G02X657226Y252424I-34J-197D01*
G01X659133Y250517D01*
G02X659186Y250416I-143J-140D01*
G01Y250414D01*
G02X659190Y250377I-196J-40D01*
G01Y228753D01*
G02X659182Y228697I-200J0D01*
G02X659176Y228679I-193J54D01*
G01X659161Y228643D01*
X658170Y227652D01*
G03X657885Y227215I896J-896D01*
G01X657881Y227204D01*
G02X657858Y227167I-180J86D01*
G03X657857Y227165I176J-89D01*
G03X657596Y226392I1046J-784D01*
G01Y222748D01*
G02X657516Y222685I-160J120D01*
G01X657152Y222552D01*
G02X657032Y222546I-70J187D01*
G01X657003Y222554D01*
X656951Y222587D01*
X656931Y222611D01*
G03X655782Y223144I-1149J-972D01*
G03Y220140I0J-1502D01*
G03X656905Y220644I0J1503D01*
G01X656906Y220645D01*
G03X656911Y220651I-1152J965D01*
G01X656913Y220653D01*
X656932Y220674D01*
X656994Y220715D01*
G02X657151Y220733I99J-174D01*
G01X657374Y220652D01*
X657505Y220604D01*
G02X657596Y220536I-69J-188D01*
G01Y216982D01*
G03X657979Y216058I1306J0D01*
G01X665554Y208483D01*
X665579Y208441D01*
X665586Y208418D01*
G03X668456I1435J446D01*
G01X668463Y208441D01*
X668488Y208483D01*
X670411Y210406D01*
G03X670596Y210639I-924J924D01*
G01X670608Y210659D01*
X671101Y211152D01*
G03X671472Y212048I-896J896D01*
G01Y214382D01*
G03X671272Y214582I-200J0D01*
G01X670059D01*
G02X669968Y214604I0J200D01*
G02X669918Y214640I90J178D01*
G01X668782Y215776D01*
G03X667860Y216158I-923J-924D01*
G01X666557D01*
G02X666550Y216163I113J165D01*
G01X666539Y216172D01*
X666248Y216463D01*
G02X666245Y216467I157J121D01*
G02X666190Y216590I145J138D01*
G01Y222211D01*
G02X666194Y222249I200J-2D01*
G02X666247Y222351I196J-37D01*
G01X667464Y223568D01*
G03X667846Y224490I-924J923D01*
G01Y246715D01*
G02X667893Y246760I160J-120D01*
G01X667938Y246791D01*
X667998Y246833D01*
X668000D01*
X668175Y246952D01*
G02X668255Y246980I105J-170D01*
G01X668302Y246986D01*
X668312Y246983D01*
X668334Y246974D01*
X668349Y246968D01*
G03X668885Y246869I536J1403D01*
G01X668923D01*
G03X670388Y248371I-37J1502D01*
G03X668886Y249873I-1502J0D01*
G01X668885D01*
G03X668349Y249774I0J-1502D01*
G01X668334Y249768D01*
X668312Y249759D01*
X668302Y249756D01*
X668255Y249762D01*
G02X668175Y249790I25J198D01*
G01X668000Y249909D01*
X667998D01*
X667938Y249951D01*
X667893Y249982D01*
G02X667846Y250027I113J165D01*
G01Y258600D01*
G02X667848Y258628I200J0D01*
G02X667903Y258740I198J-28D01*
G01X671908Y262744D01*
G03X672290Y263666I-924J923D01*
G01Y318316D01*
G02X672450Y318396I160J-120D01*
G01X688078D01*
G02X688121Y318391I-1J-200D01*
G01X688164Y318382D01*
X694349Y312197D01*
G02X694402Y312095I-143J-139D01*
G02X694406Y312057I-196J-40D01*
G01Y248568D01*
X694404Y248563D01*
X694181Y248396D01*
X694179D01*
X694097Y248335D01*
G02X693940Y248308I-110J167D01*
G01X693930Y248311D01*
G03X693493Y248376I-437J-1436D01*
G03X691991Y246874I0J-1502D01*
G03X693486Y245372I1502J0D01*
G01X693495D01*
G03X693591Y245375I1J1502D01*
G01X693594D01*
X693601Y245376D01*
X693607D01*
G03X693729Y245390I-110J1498D01*
G03X694116Y245507I-237J1484D01*
G01X694117Y245508D01*
X694118D01*
G03X694123Y245510I-555J1396D01*
G01X694163Y245529D01*
X694205D01*
G02X694312Y245498I0J-200D01*
G01X694313Y245497D01*
G02X694406Y245328I-107J-169D01*
G01Y245096D01*
G02X694383Y245003I-200J0D01*
G03X694211Y244321I1331J-698D01*
G01Y244284D01*
G03X695700Y242795I1502J13D01*
G01X695736D01*
G03X696419Y242967I-15J1503D01*
G02X696512Y242990I93J-177D01*
G01X697093D01*
G02X697233Y242933I0J-200D01*
G01X697862Y242304D01*
X699135Y241032D01*
G02X699194Y240896I-141J-142D01*
G01Y231632D01*
X699179Y231605D01*
G02X699106Y231531I-174J99D01*
G01X698975Y231454D01*
G02X698950Y231442I-99J174D01*
G01X698948D01*
G02X698891Y231428I-76J185D01*
G01X698889D01*
G02X698874Y231427I-21J199D01*
G01X698761D01*
X698721Y231436D01*
X698696Y231450D01*
G03X698003Y231619I-693J-1334D01*
G01X697996D01*
G03Y228615I0J-1502D01*
G01X697999D01*
G03X698732Y228806I0J1503D01*
G01X698733Y228807D01*
X698744Y228813D01*
G02X698833Y228833I87J-180D01*
G01X698886Y228832D01*
X698944Y228798D01*
G03X698946Y228797I90J178D01*
G01X699094Y228710D01*
G02X699137Y228677I-99J-174D01*
G02X699189Y228582I-143J-140D01*
G02X699194Y228537I-195J-44D01*
G01Y216193D01*
G02X699081Y216013I-200J0D01*
G01X699069Y216008D01*
G02X698951Y215997I-77J185D01*
G01X698925Y216002D01*
X698875Y216029D01*
X685877Y229027D01*
X685852Y229069D01*
X685845Y229092D01*
G03X684410Y230148I-1435J-447D01*
G03X682908Y228646I0J-1502D01*
G01X682907D01*
G03X683964Y227211I1503J0D01*
G01X683965D01*
G02X684047Y227161I-60J-191D01*
G01X697726Y213483D01*
G02X697776Y213398I-142J-141D01*
G02X697784Y213342I-192J-56D01*
G01Y181517D01*
G02X697762Y181426I-200J0D01*
G02X697726Y181376I-178J90D01*
G01X675044Y158694D01*
G02X675023Y158676I-140J142D01*
G01X663648D01*
X663633Y158684D01*
G03X662905Y158872I-728J-1316D01*
G03X661403Y157370I0J-1502D01*
G03X662897Y155868I1502J0D01*
G01X662908D01*
G03X663633Y156056I-3J1502D01*
G01X663648Y156064D01*
X673813D01*
G02X673998Y155940I0J-200D01*
G01X674043Y155831D01*
X674038Y155806D01*
X673396Y155165D01*
X660791Y142561D01*
G02X660782Y142554I-127J154D01*
G01X656845D01*
G02X656810Y142586I117J163D01*
G01X656682Y142763D01*
X656617Y142854D01*
G02X656584Y142960I167J110D01*
G01Y143039D01*
X656593Y143069D01*
G03X656662Y143518I-1433J450D01*
G03X655160Y145020I-1502J0D01*
G03X653658Y143529I0J-1502D01*
G01Y143515D01*
G03X653727Y143066I1502J1D01*
G01X653730Y143056D01*
X653736Y143037D01*
X653742Y142986D01*
G02X653711Y142864I-199J-14D01*
G01X653636Y142759D01*
X653514Y142590D01*
G02X653477Y142554I-157J124D01*
G01X651419D01*
X651396Y142566D01*
X651383Y142572D01*
G03X650676Y142749I-708J-1327D01*
G01X650673D01*
G03Y139745I0J-1502D01*
G01X650676D01*
G03X651383Y139922I-1J1504D01*
G01X651396Y139928D01*
X651419Y139940D01*
X660138D01*
G02X660313Y139835I-1J-200D01*
G01X660356Y139732D01*
Y139720D01*
X660342Y139686D01*
G02X660301Y139622I-186J74D01*
G01X659492Y138814D01*
X652191Y131513D01*
G03X651820Y130617I896J-896D01*
G01Y130372D01*
G03X651819Y130355I1304J-85D01*
G01Y130353D01*
G03X651818Y130314I1305J-53D01*
G01Y113550D01*
G02X651618Y113350I-200J0D01*
G01X642311D01*
G03X641415Y112979I0J-1267D01*
G01X637802Y109365D01*
G02X637695Y109309I-142J141D01*
G02X637660Y109306I-35J197D01*
G01X637050D01*
G02X636869Y109423I1J200D01*
G01X636822Y109532D01*
X636722Y109765D01*
G02X636706Y109845I184J78D01*
G01X636760Y109979D01*
X636784Y110006D01*
G03X637257Y111223I-1329J1217D01*
G01X637256Y113128D01*
Y114623D01*
G03X633652I-1802J0D01*
G01Y113128D01*
X633651Y111223D01*
G03X634124Y110006I1802J0D01*
G01X634148Y109979D01*
X634202Y109845D01*
G02X634186Y109765I-200J-2D01*
G01X634086Y109532D01*
X634039Y109423D01*
G02X633858Y109306I-182J83D01*
G01X633599D01*
G03X632677Y108924I1J-1306D01*
G01X628538Y104784D01*
G02X628467Y104738I-142J141D01*
G02X628300Y104750I-70J187D01*
G02X628284Y104759I90J179D01*
G02X628108Y105091I224J332D01*
G01Y107649D01*
G03X624502I-1803J0D01*
G01Y104249D01*
G03X625696Y102551I1804J0D01*
G01X625737Y102536D01*
X625797Y102478D01*
X625810Y102463D01*
G02X625847Y102394I-155J-127D01*
G01X625858Y102345D01*
Y102343D01*
X625880Y102248D01*
G02X625849Y102101I-197J-35D01*
G01X625841Y102090D01*
G02X625825Y102072I-157J124D01*
G01X625079Y101326D01*
G02X625029Y101290I-140J142D01*
G02X624938Y101268I-91J178D01*
G01X616063D01*
X616040Y101280D01*
X616018Y101291D01*
G03X615320Y101463I-698J-1330D01*
G03X613818Y99961I0J-1502D01*
G03X614943Y98507I1502J0D01*
G01X614970Y98500D01*
X614997Y98484D01*
G02X615036Y98454I-101J-172D01*
G01X615068Y98422D01*
G02X615124Y98252I-142J-141D01*
G01X613739Y96867D01*
G03X613096Y95624I1631J-1631D01*
G01X613080Y95527D01*
G02X613007Y95482I-139J144D01*
G01X612743Y95398D01*
X612741D01*
X612693Y95383D01*
G02X612659Y95376I-57J192D01*
G02X612633Y95374I-28J198D01*
G01X612611D01*
X612575Y95389D01*
G02X612510Y95432I76J185D01*
G01X611782Y96160D01*
G03X610860Y96542I-923J-924D01*
G01X606180D01*
X606165Y96550D01*
G03X605437Y96738I-728J-1316D01*
G03X603935Y95236I0J-1502D01*
G03X605429Y93734I1502J0D01*
G01X605440D01*
G03X606165Y93922I-3J1502D01*
G01X606180Y93930D01*
X610234D01*
G02X610325Y93908I0J-200D01*
G02X610375Y93872I-90J-178D01*
G01X610843Y93404D01*
G02X610835Y93312I-198J-29D01*
G01X610799Y93203D01*
Y93201D01*
X610715Y92928D01*
X610686Y92902D01*
X610589Y92885D01*
G03X608844Y91437I410J-2270D01*
G01X608811Y91351D01*
G02X608742Y91322I-111J166D01*
G01X608548Y91281D01*
X608546D01*
X608405Y91251D01*
G02X608349Y91252I-24J199D01*
G01X607319Y92282D01*
G03X605687Y92958I-1632J-1632D01*
G03X603379Y90650I0J-2308D01*
G03X604055Y89018I2308J0D01*
G01X605995Y87078D01*
G03X607627Y86402I1632J1632D01*
G03X607711Y86404I-13J2308D01*
G01X622713D01*
G02X622719Y86395I-163J-115D01*
G01X622723Y86389D01*
X622843Y86191D01*
Y86189D01*
X622904Y86087D01*
G02X622923Y86040I-174J-98D01*
G02X622929Y85994I-194J-49D01*
G01X622930Y85948D01*
X622908Y85901D01*
X622906Y85897D01*
G03X622732Y85197I1328J-702D01*
G01Y85180D01*
G03X623138Y84166I1502J13D01*
G01X623165Y84138D01*
X623179Y84103D01*
G02X623189Y84067I-187J-71D01*
G02X623192Y84032I-197J-35D01*
G01Y83755D01*
G02X623182Y83691I-200J-1D01*
G02X623179Y83684I-185J75D01*
G01X623166Y83650D01*
X623138Y83620D01*
G03Y81566I1096J-1027D01*
G01X623166Y81536D01*
X623179Y81502D01*
G02X623182Y81495I-182J-82D01*
G02X623192Y81431I-190J-63D01*
G01Y81155D01*
G02X623182Y81091I-200J-1D01*
G02X623179Y81084I-185J75D01*
G01X623166Y81050D01*
X623138Y81020D01*
G03Y78966I1096J-1027D01*
G01X623166Y78936D01*
X623179Y78902D01*
G02X623182Y78895I-182J-82D01*
G02X623192Y78831I-190J-63D01*
G01Y78555D01*
G02X623182Y78491I-200J-1D01*
G02X623179Y78484I-185J75D01*
G01X623166Y78450D01*
X623138Y78420D01*
G03Y76366I1096J-1027D01*
G01X623166Y76336D01*
X623179Y76302D01*
G02X623182Y76295I-182J-82D01*
G02X623192Y76231I-190J-63D01*
G01Y75955D01*
G02X623182Y75891I-200J-1D01*
G02X623179Y75884I-185J75D01*
G01X623166Y75850D01*
X623138Y75820D01*
G03X622732Y74793I1096J-1027D01*
G03X625736I1502J0D01*
G03X625330Y75820I-1502J0D01*
G01X625302Y75850D01*
X625289Y75884D01*
G02X625286Y75891I182J82D01*
G02X625276Y75955I190J63D01*
G01Y76231D01*
G02X625286Y76295I200J1D01*
G02X625289Y76302I185J-75D01*
G01X625302Y76336D01*
X625330Y76366D01*
G03Y78420I-1096J1027D01*
G01X625302Y78450D01*
X625289Y78484D01*
G02X625286Y78491I182J82D01*
G02X625276Y78555I190J63D01*
G01Y78831D01*
G02X625286Y78895I200J1D01*
G02X625289Y78902I185J-75D01*
G01X625302Y78936D01*
X625330Y78966D01*
G03Y81020I-1096J1027D01*
G01X625302Y81050D01*
X625289Y81084D01*
G02X625286Y81091I182J82D01*
G02X625276Y81155I190J63D01*
G01Y81431D01*
G02X625286Y81495I200J1D01*
G02X625289Y81502I185J-75D01*
G01X625302Y81536D01*
X625330Y81566D01*
G03Y83620I-1096J1027D01*
G01X625302Y83650D01*
X625289Y83684D01*
G02X625286Y83691I182J82D01*
G02X625276Y83755I190J63D01*
G01Y84032D01*
G02X625279Y84067I200J0D01*
G02X625289Y84103I197J-35D01*
G01X625303Y84138D01*
X625332Y84168D01*
G03X625736Y85179I-1098J1025D01*
G01Y85195D01*
G03X625562Y85897I-1502J0D01*
G01X625556Y85908D01*
G02X625539Y85993I183J81D01*
G01X625540Y86046D01*
X625625Y86189D01*
Y86191D01*
X625745Y86388D01*
G02X625756Y86404I170J-105D01*
G01X643121D01*
G02X643235Y86369I1J-200D01*
G02X643251Y86356I-118J-162D01*
G01X644602Y85005D01*
G02X644604Y84976I-198J-28D01*
G01Y84913D01*
X644592Y84867D01*
X644575Y84834D01*
G03X644405Y84143I1332J-694D01*
G01Y84110D01*
G03X645907Y82638I1502J30D01*
G01X645908D01*
G03X645971Y82639I8J1502D01*
G01X646013Y82641D01*
X646049Y82627D01*
G02X646112Y82589I-70J-187D01*
G01X646166Y82538D01*
G02X646168Y82536I-140J-142D01*
G01X646333Y82377D01*
G02X646348Y82359I-146J-137D01*
G01Y76586D01*
G03X647139Y74848I2307J1D01*
G01X647204Y74792D01*
X647206Y74769D01*
X647208Y74691D01*
X647213Y74497D01*
Y74490D01*
X647215Y74436D01*
X647085Y74307D01*
X647024Y74247D01*
G03X646524Y73498I1632J-1631D01*
G03X646348Y72622I2131J-884D01*
G01Y72615D01*
G03X648655Y70308I2307J0D01*
G01X648692D01*
G03X649538Y70484I-39J2307D01*
G03X650287Y70984I-882J2132D01*
G01X651589Y72287D01*
X652525Y73223D01*
G03X653200Y74853I-1631J1630D01*
G01Y84546D01*
G02X653255Y84596I160J-120D01*
G01X653278Y84610D01*
X653622Y84754D01*
G02X653731Y84767I77J-184D01*
G01X656051Y82447D01*
G02Y82387I-198J-30D01*
G01Y82384D01*
X656030Y82254D01*
X655999Y82059D01*
G02X655894Y81922I-196J41D01*
G01X655867Y81908D01*
G03X655071Y80581I708J-1327D01*
G03X656573Y79079I1502J0D01*
G03X658075Y80556I0J1502D01*
G01Y80559D01*
X658076Y80575D01*
X658111Y80650D01*
X658237Y80761D01*
G02X658371Y80810I131J-151D01*
G01X658392Y80809D01*
X658397Y80808D01*
G03X658419Y80806I220J2295D01*
G01X658425D01*
G03X658660Y80794I235J2294D01*
G01X663672D01*
G03X665302Y81469I0J2306D01*
G01X666533Y82700D01*
X668248Y84414D01*
G03X668924Y86045I-1631J1632D01*
G01Y86102D01*
X668923Y86125D01*
G03X666617Y88352I-2305J-79D01*
G03X664986Y87677I-1J-2306D01*
G01X664755Y87446D01*
G02X664732Y87444I-29J198D01*
G01X664683D01*
G02X664553Y87492I0J200D01*
G01X664547Y87497D01*
G03X663063Y88038I-1484J-1765D01*
G01X662445D01*
G02X662411Y88068I114J164D01*
G01X662333Y88164D01*
X662203Y88325D01*
G02X662193Y88341I165J114D01*
G02X662178Y88377I176J95D01*
G01X662162Y88439D01*
X662172Y88484D01*
G03X662205Y88791I-1469J313D01*
G03Y88793I-1502J1D01*
G01Y88816D01*
G03X660879Y90293I-1502J-15D01*
G01X660823Y90299D01*
G03X660692Y90304I-123J-1498D01*
G01X660684D01*
G03X659772Y89980I20J-1502D01*
G03X659706Y89925I928J-1181D01*
G01X659700Y89920D01*
X659693Y89914D01*
X659661Y89893D01*
G02X659483Y89878I-104J170D01*
G01X659389Y89919D01*
X659387D01*
X659147Y90026D01*
G02X659139Y90030I85J181D01*
G01X659085Y90057D01*
X659066Y90088D01*
Y102018D01*
G02X659077Y102083I200J0D01*
G01X659087Y102112D01*
X659105Y102136D01*
X659207Y102167D01*
G03X659862Y102576I-452J1453D01*
G03X660224Y103218I-1105J1046D01*
G01X660233Y103250D01*
X664624Y107641D01*
G03X665006Y108563I-924J923D01*
G01Y115314D01*
G02X665134Y115500I200J-1D01*
G01X665483Y115635D01*
G02X665601Y115643I72J-187D01*
G01X665630Y115636D01*
X665681Y115606D01*
X665702Y115583D01*
G03X666813Y115092I1111J1011D01*
G03X668315Y116594I0J1502D01*
G03X667769Y117753I-1503J0D01*
G01X667752Y117766D01*
X667725Y117800D01*
X667679Y117895D01*
G02X667659Y117982I180J87D01*
G01Y118206D01*
G02X667679Y118293I200J0D01*
G01X667725Y118388D01*
X667752Y118422D01*
X667769Y118435D01*
G03X668315Y119594I-957J1159D01*
G03X666813Y121096I-1502J0D01*
G01X666811D01*
G03X665702Y120606I1J-1502D01*
G02X665599Y120545I-149J134D01*
G01X665571Y120538D01*
X665512Y120542D01*
X665134Y120688D01*
G02X665006Y120874I72J187D01*
G01Y130014D01*
G02X665028Y130105I200J0D01*
G02X665064Y130155I178J-90D01*
G01X682921Y148012D01*
G02X683087Y148069I141J-141D01*
G01X683399Y148032D01*
G02X683484Y148001I-24J-199D01*
G01X683499Y147991D01*
X683532Y147959D01*
X683546Y147937D01*
G03X684830Y147215I1284J781D01*
G03X686332Y148717I0J1502D01*
G03X685610Y150001I-1503J0D01*
G01X685588Y150015D01*
X685570Y150034D01*
G02X685545Y150064I140J142D01*
G01X685534Y150083D01*
X685518Y150125D01*
X685478Y150460D01*
G02X685533Y150624I198J25D01*
G01X688072Y153162D01*
X689322Y154412D01*
G02X689519Y154462I141J-142D01*
G01X689540Y154453D01*
G02X689630Y154380I-76J-185D01*
G01X689645Y154358D01*
X689662Y154301D01*
Y144624D01*
G02X689640Y144534I-200J1D01*
G01X689631Y144517D01*
G03X689523Y144289I1299J-755D01*
G01X689518Y144275D01*
X689507Y144243D01*
X689506Y144241D01*
X689503Y144231D01*
X689502Y144228D01*
G03X689499Y144219I1423J-479D01*
G02X689497Y144213I-191J60D01*
G03X689494Y144205I1404J-531D01*
G01X689490Y144193D01*
G02X689485Y144181I-187J71D01*
G02X689446Y144126I-180J87D01*
G01X683578Y138258D01*
G03X683196Y137336I924J-923D01*
G01Y127603D01*
G02X683161Y127567I-160J120D01*
G01X683130Y127541D01*
X683044Y127471D01*
X682918Y127368D01*
X682887Y127344D01*
X682795Y127363D01*
X682794D01*
G03X682529Y127404I-485J-2255D01*
G03X682316Y127414I-215J-2297D01*
G01X682132D01*
Y127407D01*
G03X680010Y125109I184J-2299D01*
G01Y121166D01*
G02X679999Y121153I-158J123D01*
G01X679983Y121135D01*
X679678Y120946D01*
G02X679484Y120941I-102J172D01*
G01X679474Y120946D01*
X679441Y120962D01*
X679410Y120976D01*
G03X678782Y121113I-630J-1382D01*
G03X677263Y119594I0J-1519D01*
G03X677819Y118421I1515J0D01*
G01X677821Y118419D01*
X677843Y118400D01*
X677859Y118387D01*
X677873Y118371D01*
G02X677896Y118336I-155J-127D01*
G01X677922Y118280D01*
G02X677936Y118207I-186J-74D01*
G01Y117983D01*
G02X677918Y117900I-200J0D01*
G01X677905Y117873D01*
Y117871D01*
X677878Y117817D01*
G02X677845Y117772I-176J95D01*
G01X677826Y117753D01*
X677819Y117747D01*
G03X677280Y116594I964J-1153D01*
G03X678782Y115092I1502J0D01*
G01X678783D01*
G03X679639Y115360I0J1502D01*
G01X679640Y115361D01*
G02X679720Y115394I115J-164D01*
G01X679760Y115401D01*
X680108Y115308D01*
G02X680219Y115221I-60J-191D01*
G01X680228Y115202D01*
G03X680685Y114552I2087J982D01*
G01X690285Y104952D01*
G02X690338Y104850I-143J-139D01*
G02X690342Y104812I-196J-40D01*
G01Y95111D01*
G03X694956I2307J0D01*
G01Y105213D01*
G02X694997Y105254I160J-119D01*
G01X696157D01*
X696167D01*
G02X696248Y105232I-11J-200D01*
G03X696341Y105182I773J1327D01*
G01X696364Y105171D01*
X696366Y105170D01*
X696401Y105140D01*
X696416Y105119D01*
G02X696370Y104840I-163J-116D01*
G01X696347Y104824D01*
X696323Y104815D01*
G03X695357Y103411I537J-1404D01*
G03X698361I1502J0D01*
G03X697782Y104596I-1502J0D01*
G01X697764Y104610D01*
X697727Y104655D01*
G02X697697Y104704I154J128D01*
G01Y104706D01*
G02X697681Y104793I184J79D01*
G01X697686Y104897D01*
Y104899D01*
X697697Y105081D01*
X697708Y105129D01*
X697732Y105173D01*
G02X697792Y105236I172J-103D01*
G01X697796Y105239D01*
X697802Y105242D01*
G03X698553Y106561I-783J1319D01*
G03X697018Y108096I-1535J0D01*
G01X697017D01*
G03X696255Y107894I0J-1537D01*
G01X696232Y107881D01*
X696208Y107875D01*
G02X696157Y107868I-52J193D01*
G01X695666D01*
G02X695525Y107926I0J200D01*
G01X689410Y114039D01*
X685827Y117623D01*
G02X685808Y117645I141J141D01*
G01Y136710D01*
G02X685810Y136740I200J2D01*
G02X685865Y136850I198J-30D01*
G01X689527Y140511D01*
X691329Y142313D01*
X691355Y142321D01*
G03X692432Y143749I-425J1441D01*
G01Y143776D01*
G03X692404Y144055I-1503J-10D01*
G01X692398Y144084D01*
G03X692309Y144359I-1467J-323D01*
G01Y144361D01*
G03X692294Y144393I-1368J-622D01*
G01X692276Y144433D01*
Y153311D01*
G02X692294Y153332I160J-119D01*
G01X711443Y172481D01*
G02X711447Y172485I143J-139D01*
G03X711522Y172562I-870J922D01*
G03X711842Y173403I-946J841D01*
G01Y175250D01*
X711845Y175267D01*
G03X711866Y175502I-1285J233D01*
G01Y292729D01*
G02X711872Y292778I200J0D01*
G02X711924Y292870I194J-49D01*
G01X721167Y302112D01*
G03X721550Y303036I-923J924D01*
G01Y316890D01*
G03X721167Y317814I-1306J0D01*
G01X720920Y318060D01*
G02X720883Y318273I147J135D01*
G01X720926Y318376D01*
G02X721005Y318396I88J-180D01*
G01X741978D01*
G02X742115Y318341I-1J-200D01*
G01X762196Y298260D01*
G02X762232Y298210I-142J-140D01*
G02X762254Y298119I-178J-91D01*
G01Y279768D01*
X762253Y270040D01*
G03X762614Y269139I1307J1D01*
G02X762656Y269025I-158J-123D01*
G01Y267870D01*
G02X762648Y267814I-200J0D01*
G02X762642Y267796I-193J54D01*
G01X762627Y267760D01*
X762547Y267680D01*
X762546Y267679D01*
G03X762494Y267592I140J-143D01*
G01X762491Y267577D01*
Y267576D01*
G03X762489Y267567I194J-48D01*
G01X762488Y267563D01*
Y267558D01*
G02X762337Y267390I-198J26D01*
G03X762058Y267416I-280J-1493D01*
G03X761836Y267400I-2J-1519D01*
G01X761718Y267415D01*
X761612Y267354D01*
G02X761575Y267337I-101J172D01*
G03X761054Y267037I482J-1440D01*
G02X760999Y267029I-56J192D01*
G01X760932D01*
G03X760821Y266995I1J-200D01*
G01X760787Y266974D01*
X760734Y266968D01*
G02X760657Y266978I-13J200D01*
G01X760567Y267010D01*
X760539Y267034D01*
G03X759558Y267399I-981J-1136D01*
G03Y264395I0J-1502D01*
G01X759561D01*
G03X760453Y264690I-2J1502D01*
G03X760502Y264728I-896J1206D01*
G02X760504Y264730I140J-138D01*
G01X760523Y264741D01*
G02X760617Y264765I95J-176D01*
G01X760684D01*
G03X760795Y264799I-1J200D01*
G01X760829Y264820D01*
X760882Y264826D01*
G02X760955Y264818I15J-200D01*
G01X760972Y264812D01*
G02X761036Y264772I-72J-186D01*
G03X762058Y264378I1021J1126D01*
G03X762156Y264381I3J1519D01*
G02X762223Y264338I-72J-186D01*
G01X762427Y264138D01*
G02X762487Y263995I-140J-143D01*
G01Y260068D01*
G02X762479Y260012I-200J0D01*
G02X762473Y259994I-193J54D01*
G01X762458Y259958D01*
X759644Y257144D01*
G02X759623Y257126I-140J142D01*
G01X750612D01*
G02X750585Y257128I1J200D01*
G02X750471Y257184I27J198D01*
G01X748292Y259364D01*
G03X747370Y259746I-923J-924D01*
G01X744712D01*
G03X743790Y259364I1J-1306D01*
G01X742214Y257788D01*
G02X742132Y257738I-142J141D01*
G01X742131D01*
G03X741075Y256325I446J-1435D01*
G01Y256285D01*
G03X741155Y255818I1502J17D01*
G01Y255817D01*
G02X741164Y255723I-189J-66D01*
G01X741157Y255678D01*
X740932Y255364D01*
G02X740897Y255330I-156J125D01*
G01X739019D01*
G02X738928Y255352I0J200D01*
G02X738878Y255388I90J178D01*
G01X734490Y259776D01*
G03X734437Y259826I-895J-896D01*
G01X734433Y259830D01*
G03X733536Y260186I-897J-952D01*
G01X720543D01*
X720526Y260195D01*
G03X719800Y260382I-726J-1317D01*
G01X719798D01*
G03Y257378I0J-1502D01*
G01X719799D01*
G03X720530Y257568I-1J1504D01*
G01X720541Y257574D01*
X732912D01*
G02X732949Y257571I2J-200D01*
G02X733053Y257516I-37J-197D01*
G01X737469Y253099D01*
G03X737470Y253098I924J923D01*
G03X737818Y252850I922J926D01*
G01X737848Y252835D01*
X739751Y250931D01*
X739754Y250927D01*
G03X740324Y250584I916J877D01*
G01X740335Y250582D01*
X740346Y250579D01*
G03X740668Y250536I327J1225D01*
G01X749088D01*
G02X749194Y250503I-4J-200D01*
G01X749221Y250484D01*
G02X749239Y250468I-124J-157D01*
G02X749290Y250379I-142J-141D01*
G01X749304Y250328D01*
X749321Y250287D01*
X749339Y250240D01*
G03X749376Y250180I186J74D01*
G01X749380Y250175D01*
G02X749425Y250077I-152J-129D01*
G01X749429Y250050D01*
X749426Y250023D01*
G02X749410Y249967I-198J26D01*
G01X749376Y249891D01*
Y249889D01*
X749358Y249848D01*
X749332Y249821D01*
G03X749331Y249820I1062J-1063D01*
G03X749329Y249818I140J-142D01*
G03X748899Y248773I1072J-1052D01*
G01Y248741D01*
G03X750345Y247264I1502J24D01*
G01X750346D01*
G03X750401Y247263I55J1501D01*
G01X750403D01*
G03X751337Y247590I-1J1501D01*
G01X751363Y247610D01*
X751407Y247625D01*
G02X751460Y247633I56J-192D01*
G01X751546D01*
G03X751602Y247641I0J200D01*
G01X751616Y247644D01*
X751828D01*
G02X751953Y247600I0J-200D01*
G01X751954Y247599D01*
G03X751957Y247597I835J1249D01*
G03X751975Y247583I931J1178D01*
G02X751985Y247575I-120J-160D01*
G03X751988Y247572I1062J1059D01*
G03X752075Y247510I915J1192D01*
G01X752079Y247508D01*
X752110Y247487D01*
X752124Y247479D01*
G03X752398Y247349I777J1285D01*
G03X752401Y247348I64J186D01*
G01X752416Y247343D01*
G03X752821Y247265I484J1422D01*
G03X752898Y247263I77J1499D01*
G01X752901D01*
G03X752964Y247264I8J1502D01*
G01X752981Y247265D01*
G03X753835Y247589I-81J1500D01*
G01X753836Y247590D01*
X753848Y247600D01*
G02X753954Y247633I110J-167D01*
G01X754046D01*
G03X754129Y247651I0J200D01*
G01X754183Y247676D01*
G02X754261Y247695I85J-181D01*
G02X754295Y247693I5J-200D01*
G02X754399Y247645I-28J-198D01*
G01X754400Y247644D01*
G03X755399Y247263I1000J1122D01*
G01X755401D01*
G03X756903Y248765I0J1502D01*
G03X756470Y249820I-1502J0D01*
G01X756469Y249821D01*
X756445Y249846D01*
X756429Y249880D01*
X756414Y249912D01*
G02X756406Y249936I185J75D01*
G01X756394Y249992D01*
G02X756401Y250089I198J34D01*
G01X756476Y250273D01*
Y250275D01*
X756537Y250421D01*
G02X756564Y250464I182J-84D01*
G02X756718Y250536I154J-128D01*
G01X760216D01*
G02X760376Y250456I0J-200D01*
G01Y227463D01*
X760366Y227448D01*
G03X760277Y227286I1063J-689D01*
G03X760247Y227215I1151J-528D01*
G02X760220Y227167I-186J73D01*
G03X759958Y226382I1045J-785D01*
G01Y222748D01*
G02X759878Y222685I-160J120D01*
G01X759514Y222552D01*
G02X759394Y222546I-70J187D01*
G01X759365Y222554D01*
X759313Y222587D01*
X759293Y222611D01*
G03X758144Y223144I-1149J-972D01*
G03Y220140I0J-1502D01*
G03X759267Y220644I0J1503D01*
G01X759268Y220645D01*
G03X759273Y220651I-1152J965D01*
G01X759275Y220653D01*
X759294Y220674D01*
X759356Y220715D01*
G02X759513Y220733I99J-174D01*
G01X759736Y220652D01*
X759867Y220604D01*
G02X759958Y220536I-69J-188D01*
G01Y216982D01*
G03X760341Y216058I1306J0D01*
G01X767916Y208483D01*
X767941Y208441D01*
X767948Y208418D01*
G03X770818I1435J446D01*
G01X770825Y208441D01*
X770850Y208483D01*
X773451Y211084D01*
G03X773834Y212008I-923J924D01*
G01Y216192D01*
G02X773889Y216329I200J-1D01*
G01X773898Y216338D01*
X774120Y216539D01*
G02X774149Y216561I135J-148D01*
G02X774254Y216591I105J-170D01*
G01X774273D01*
X774282Y216590D01*
G03X774428Y216583I145J1495D01*
G03X774430I1J1502D01*
G01X774458D01*
G03X775511Y217040I-26J1502D01*
G01X775539Y217069D01*
X775654Y217119D01*
G02X775722Y217133I74J-186D01*
G01X775940D01*
X775989Y217123D01*
X776012Y217119D01*
X776125Y217069D01*
X776152Y217041D01*
G03X777232Y216583I1080J1044D01*
G03Y219587I0J1502D01*
G03X776153Y219130I0J-1502D01*
G01X776125Y219101D01*
X776010Y219051D01*
G02X775942Y219037I-74J186D01*
G01X775749D01*
G02X775709Y219041I0J200D01*
G01X775666Y219050D01*
X775644Y219054D01*
X775539Y219101D01*
X775512Y219130D01*
G03X774543Y219583I-1079J-1045D01*
G01X774535D01*
G02X774412Y219644I22J199D01*
G01X774385Y219672D01*
X774383Y219674D01*
X774329Y219729D01*
G02X774272Y219869I143J140D01*
G01Y222883D01*
G03X774213Y223025I-200J0D01*
G01X769304Y227934D01*
G02X769268Y227984I142J140D01*
G02X769246Y228075I178J91D01*
G01Y247194D01*
Y247197D01*
G02X769359Y247374I200J-3D01*
G02X769381Y247383I87J-180D01*
G01X769559Y247445D01*
X769747Y247510D01*
G02X769949Y247455I56J-192D01*
G02X769960Y247442I-147J-136D01*
G03X771140Y246869I1180J929D01*
G03Y249873I0J1502D01*
G03X769960Y249300I0J-1502D01*
G02X769949Y249287I-158J123D01*
G02X769747Y249232I-146J137D01*
G01X769559Y249297D01*
X769381Y249359D01*
G02X769359Y249368I65J189D01*
G02X769246Y249545I87J180D01*
G01Y263554D01*
G02X769286Y263674I200J0D01*
G02X769305Y263696I160J-119D01*
G01X769969Y264360D01*
G02X770070Y264413I140J-143D01*
G01X770072D01*
G02X770109Y264417I40J-196D01*
G01X786442D01*
G02X786470Y264415I0J-200D01*
G01X796711Y254174D01*
G02X796764Y254072I-143J-139D01*
G02X796768Y254034I-196J-40D01*
G01Y248568D01*
X796766Y248563D01*
X796543Y248396D01*
X796541D01*
X796459Y248335D01*
G02X796302Y248308I-110J167D01*
G01X796292Y248311D01*
G03X795855Y248376I-437J-1436D01*
G03X794353Y246874I0J-1502D01*
G03X795848Y245372I1502J0D01*
G01X795857D01*
G03X795953Y245375I1J1502D01*
G01X795956D01*
X795963Y245376D01*
X795969D01*
G03X796091Y245390I-110J1498D01*
G03X796478Y245507I-237J1484D01*
G01X796479Y245508D01*
X796480D01*
G03X796485Y245510I-555J1396D01*
G01X796525Y245529D01*
X796567D01*
G02X796674Y245498I0J-200D01*
G01X796675Y245497D01*
G02X796768Y245328I-107J-169D01*
G01Y245096D01*
G02X796745Y245003I-200J0D01*
G03X796573Y244321I1331J-698D01*
G01Y244284D01*
G03X798075Y242795I1502J13D01*
G01X798082D01*
G03X798785Y242972I-5J1504D01*
G01X798798Y242978D01*
X798821Y242990D01*
X800833D01*
G02X800871Y242986I-2J-200D01*
G02X800973Y242933I-37J-196D01*
G01X801688Y242218D01*
G02X801690Y242190I-198J-28D01*
G01Y231775D01*
G02X801689Y231754I-200J-1D01*
G02X801601Y231609I-199J22D01*
G01X801471Y231533D01*
X801296Y231431D01*
G02X801158Y231412I-95J176D01*
G01X801095Y231427D01*
X801073Y231439D01*
G03X800360Y231619I-713J-1322D01*
G01X800358D01*
G03Y228615I0J-1502D01*
G01X800361D01*
G03X801094Y228806I0J1503D01*
G01X801095Y228807D01*
X801106Y228813D01*
G02X801195Y228833I87J-180D01*
G01X801247Y228832D01*
X801596Y228628D01*
G02X801665Y228556I-105J-170D01*
G02X801690Y228458I-175J-97D01*
G01Y215997D01*
G02X801671Y215917I-200J5D01*
G01X801649Y215908D01*
X801567Y215874D01*
G02X801349Y215916I-78J184D01*
G01X788239Y229027D01*
X788214Y229069D01*
X788207Y229092D01*
G03X786772Y230148I-1435J-447D01*
G03X785270Y228646I0J-1502D01*
G01X785269D01*
G03X786326Y227211I1503J0D01*
G01X786327D01*
G02X786409Y227161I-60J-191D01*
G01X800358Y213212D01*
G02X800360Y213185I-198J-28D01*
G01Y181731D01*
G02X800350Y181669I-200J0D01*
G02X800346Y181657I-192J57D01*
G01X800332Y181623D01*
X800304Y181594D01*
X800300Y181589D01*
X800294Y181582D01*
X777406Y158694D01*
G02X777385Y158676I-140J142D01*
G01X766012D01*
X765995Y158685D01*
G03X765269Y158872I-726J-1317D01*
G01X765267D01*
G03Y155868I0J-1502D01*
G01X765268D01*
G03X765999Y156058I-1J1504D01*
G01X766010Y156064D01*
X776175D01*
G02X776360Y155940I0J-200D01*
G01X776405Y155831D01*
X776400Y155806D01*
X775758Y155165D01*
X763153Y142561D01*
G02X763144Y142554I-127J154D01*
G01X759207D01*
G02X759172Y142586I117J163D01*
G01X759044Y142763D01*
X758979Y142854D01*
G02X758946Y142960I167J110D01*
G01Y143039D01*
X758955Y143069D01*
G03X759024Y143518I-1433J450D01*
G03X757522Y145020I-1502J0D01*
G03X756020Y143529I0J-1502D01*
G01Y143515D01*
G03X756089Y143066I1502J1D01*
G01X756092Y143056D01*
X756098Y143037D01*
X756104Y142986D01*
G02X756073Y142864I-199J-14D01*
G01X755998Y142759D01*
X755876Y142590D01*
G02X755839Y142554I-157J124D01*
G01X753781D01*
X753758Y142566D01*
X753745Y142572D01*
G03X753038Y142749I-708J-1327D01*
G01X753035D01*
G03Y139745I0J-1502D01*
G01X753038D01*
G03X753745Y139922I-1J1504D01*
G01X753758Y139928D01*
X753781Y139940D01*
X762417D01*
G02X762592Y139835I-1J-200D01*
G01X762600Y139815D01*
G02X762612Y139699I-184J-78D01*
G01X762607Y139673D01*
X762579Y139621D01*
X755283Y132325D01*
G03X754900Y131401I923J-924D01*
G01Y113994D01*
G03X754914Y113807I1307J4D01*
G01X754920Y113764D01*
X754908Y113723D01*
G02X754867Y113648I-192J56D01*
G01X754664Y113413D01*
G02X754526Y113350I-146J137D01*
G01X744777D01*
G03X743881Y112979I0J-1267D01*
G01X740268Y109365D01*
G02X740161Y109309I-142J141D01*
G02X740126Y109306I-35J197D01*
G01X739412D01*
G02X739231Y109423I1J200D01*
G01X739184Y109532D01*
X739084Y109765D01*
G02X739068Y109845I184J78D01*
G01X739122Y109979D01*
X739146Y110006D01*
G03X739619Y111223I-1329J1217D01*
G01X739618Y113128D01*
Y114623D01*
G03X736014I-1802J0D01*
G01Y113128D01*
X736013Y111223D01*
G03X736486Y110006I1802J0D01*
G01X736510Y109979D01*
X736564Y109845D01*
G02X736548Y109765I-200J-2D01*
G01X736448Y109532D01*
X736401Y109423D01*
G02X736220Y109306I-182J83D01*
G01X735961D01*
G03X735039Y108924I1J-1306D01*
G01X730900Y104784D01*
G02X730829Y104738I-142J141D01*
G02X730662Y104750I-70J187D01*
G02X730646Y104759I90J179D01*
G02X730470Y105091I224J332D01*
G01Y107649D01*
G03X726864I-1803J0D01*
G01Y104249D01*
G03X728058Y102551I1804J0D01*
G01X728099Y102536D01*
X728159Y102478D01*
X728172Y102463D01*
G02X728209Y102394I-155J-127D01*
G01X728220Y102345D01*
Y102343D01*
X728242Y102248D01*
G02X728211Y102101I-197J-35D01*
G01X728203Y102090D01*
G02X728187Y102072I-157J124D01*
G01X727441Y101326D01*
G02X727391Y101290I-140J142D01*
G02X727300Y101268I-91J178D01*
G01X718425D01*
X718402Y101280D01*
X718380Y101291D01*
G03X717682Y101463I-698J-1330D01*
G03X716180Y99961I0J-1502D01*
G03X717305Y98507I1502J0D01*
G01X717332Y98500D01*
X717359Y98484D01*
G02X717398Y98454I-101J-172D01*
G01X717430Y98422D01*
G02X717486Y98252I-142J-141D01*
G01X716101Y96867D01*
G03X715458Y95624I1631J-1631D01*
G01X715442Y95527D01*
G02X715369Y95482I-139J144D01*
G01X715105Y95398D01*
X715103D01*
X715055Y95383D01*
G02X715021Y95376I-57J192D01*
G02X714995Y95374I-28J198D01*
G01X714973D01*
X714937Y95389D01*
G02X714872Y95432I76J185D01*
G01X714144Y96160D01*
G03X713222Y96542I-923J-924D01*
G01X708544D01*
X708527Y96551D01*
G03X707801Y96738I-726J-1317D01*
G01X707799D01*
G03Y93734I0J-1502D01*
G01X707800D01*
G03X708531Y93924I-1J1504D01*
G01X708542Y93930D01*
X712596D01*
X712609D01*
G02X712736Y93873I-13J-200D01*
G01X713051Y93557D01*
X713205Y93403D01*
G02X713206Y93349I-198J-31D01*
G02X713198Y93314I-198J27D01*
G01X713161Y93203D01*
Y93201D01*
X713077Y92928D01*
X713048Y92902D01*
X712951Y92885D01*
G03X711206Y91437I410J-2270D01*
G01X711173Y91351D01*
G02X711104Y91322I-111J166D01*
G01X710910Y91281D01*
X710908D01*
X710767Y91251D01*
G02X710711Y91252I-24J199D01*
G01X709681Y92282D01*
G03X708049Y92958I-1632J-1632D01*
G03X705741Y90650I0J-2308D01*
G03X706417Y89018I2308J0D01*
G01X708357Y87078D01*
G03X709989Y86402I1632J1632D01*
G03X710073Y86404I-13J2308D01*
G01X725075D01*
G02X725081Y86395I-163J-115D01*
G01X725085Y86389D01*
X725205Y86191D01*
Y86189D01*
X725266Y86087D01*
G02X725285Y86040I-174J-98D01*
G02X725291Y85994I-194J-49D01*
G01X725292Y85948D01*
X725270Y85901D01*
X725268Y85897D01*
G03X725094Y85197I1328J-702D01*
G01Y85180D01*
G03X725500Y84166I1502J13D01*
G01X725527Y84138D01*
X725541Y84103D01*
G02X725551Y84067I-187J-71D01*
G02X725554Y84032I-197J-35D01*
G01Y83755D01*
G02X725544Y83691I-200J-1D01*
G02X725541Y83684I-185J75D01*
G01X725528Y83650D01*
X725500Y83620D01*
G03Y81566I1096J-1027D01*
G01X725528Y81536D01*
X725541Y81502D01*
G02X725544Y81495I-182J-82D01*
G02X725554Y81431I-190J-63D01*
G01Y81155D01*
G02X725544Y81091I-200J-1D01*
G02X725541Y81084I-185J75D01*
G01X725528Y81050D01*
X725500Y81020D01*
G03Y78966I1096J-1027D01*
G01X725528Y78936D01*
X725541Y78902D01*
G02X725544Y78895I-182J-82D01*
G02X725554Y78831I-190J-63D01*
G01Y78555D01*
G02X725544Y78491I-200J-1D01*
G02X725541Y78484I-185J75D01*
G01X725528Y78450D01*
X725500Y78420D01*
G03Y76366I1096J-1027D01*
G01X725528Y76336D01*
X725541Y76302D01*
G02X725544Y76295I-182J-82D01*
G02X725554Y76231I-190J-63D01*
G01Y75955D01*
G02X725544Y75891I-200J-1D01*
G02X725541Y75884I-185J75D01*
G01X725528Y75850D01*
X725500Y75820D01*
G03X725094Y74793I1096J-1027D01*
G03X728098I1502J0D01*
G03X727692Y75820I-1502J0D01*
G01X727664Y75850D01*
X727651Y75884D01*
G02X727648Y75891I182J82D01*
G02X727638Y75955I190J63D01*
G01Y76231D01*
G02X727648Y76295I200J1D01*
G02X727651Y76302I185J-75D01*
G01X727664Y76336D01*
X727692Y76366D01*
G03Y78420I-1096J1027D01*
G01X727664Y78450D01*
X727651Y78484D01*
G02X727648Y78491I182J82D01*
G02X727638Y78555I190J63D01*
G01Y78831D01*
G02X727648Y78895I200J1D01*
G02X727651Y78902I185J-75D01*
G01X727664Y78936D01*
X727692Y78966D01*
G03Y81020I-1096J1027D01*
G01X727664Y81050D01*
X727651Y81084D01*
G02X727648Y81091I182J82D01*
G02X727638Y81155I190J63D01*
G01Y81431D01*
G02X727648Y81495I200J1D01*
G02X727651Y81502I185J-75D01*
G01X727664Y81536D01*
X727692Y81566D01*
G03Y83620I-1096J1027D01*
G01X727664Y83650D01*
X727651Y83684D01*
G02X727648Y83691I182J82D01*
G02X727638Y83755I190J63D01*
G01Y84032D01*
G02X727641Y84067I200J0D01*
G02X727651Y84103I197J-35D01*
G01X727665Y84138D01*
X727694Y84168D01*
G03X728098Y85179I-1098J1025D01*
G01Y85195D01*
G03X727924Y85897I-1502J0D01*
G01X727918Y85908D01*
G02X727901Y85993I183J81D01*
G01X727902Y86046D01*
X727987Y86189D01*
Y86191D01*
X728107Y86388D01*
G02X728118Y86404I170J-105D01*
G01X745539D01*
G02X745560Y86403I1J-200D01*
G02X745681Y86345I-21J-199D01*
G01X746908Y85117D01*
G02X746966Y84976I-142J-141D01*
G01Y84913D01*
X746954Y84866D01*
X746943Y84845D01*
G03X746767Y84143I1326J-705D01*
G01Y84110D01*
G03X748269Y82638I1502J30D01*
G01X748270D01*
G03X748333Y82639I8J1502D01*
G01X748375Y82641D01*
X748411Y82627D01*
G02X748474Y82589I-70J-187D01*
G01X748528Y82538D01*
G02X748530Y82536I-140J-142D01*
G01X748695Y82377D01*
G02X748710Y82359I-146J-137D01*
G01Y76586D01*
G03X749501Y74848I2307J1D01*
G01X749566Y74792D01*
X749568Y74769D01*
X749570Y74691D01*
X749575Y74497D01*
Y74490D01*
X749577Y74436D01*
X749447Y74307D01*
X749386Y74247D01*
G03X748886Y73498I1632J-1631D01*
G03X748710Y72622I2131J-884D01*
G01Y72615D01*
G03X751017Y70308I2307J0D01*
G01X751054D01*
G03X751900Y70484I-39J2307D01*
G03X752649Y70984I-882J2132D01*
G01X753951Y72287D01*
X754887Y73223D01*
G03X755562Y74853I-1631J1630D01*
G01Y84546D01*
G02X755617Y84596I160J-120D01*
G01X755640Y84610D01*
X755984Y84754D01*
G02X756093Y84767I77J-184D01*
G01X758413Y82447D01*
G02Y82387I-198J-30D01*
G01Y82384D01*
X758392Y82254D01*
X758361Y82059D01*
G02X758256Y81922I-196J41D01*
G01X758229Y81908D01*
G03X757433Y80581I708J-1327D01*
G03X758935Y79079I1502J0D01*
G03X760437Y80572I0J1502D01*
G01Y80582D01*
G03X760361Y81054I-1502J0D01*
G01X760355Y81072D01*
X760350Y81108D01*
Y81109D01*
X760344Y81147D01*
X760356Y81194D01*
G02X760381Y81249I192J-54D01*
G01X760420Y81305D01*
G02X760422Y81307I140J-138D01*
G01X760497Y81411D01*
G02X760647Y81494I163J-117D01*
G01X766734D01*
G03X768364Y82169I0J2306D01*
G01X769956Y83761D01*
X770610Y84414D01*
G03X771286Y86045I-1631J1632D01*
G01Y86102D01*
X771285Y86125D01*
G03X768979Y88352I-2305J-79D01*
G03X767348Y87677I-1J-2306D01*
G01X767117Y87446D01*
G02X767094Y87444I-29J198D01*
G01X767045D01*
G02X766960Y87463I0J200D01*
G01X766916Y87491D01*
X766915Y87492D01*
X766909Y87497D01*
G03X765425Y88038I-1484J-1765D01*
G01X764807D01*
G02X764773Y88068I114J164D01*
G01X764695Y88164D01*
X764565Y88325D01*
G02X764555Y88341I165J114D01*
G02X764540Y88377I176J95D01*
G01X764524Y88439D01*
X764534Y88484D01*
G03X764567Y88791I-1469J313D01*
G03Y88793I-1502J1D01*
G01Y88816D01*
G03X763241Y90293I-1502J-15D01*
G01X763185Y90299D01*
G03X763054Y90304I-123J-1498D01*
G01X763046D01*
G03X762134Y89980I20J-1502D01*
G03X762068Y89925I928J-1181D01*
G01X762062Y89920D01*
X762055Y89914D01*
X762023Y89893D01*
G02X761845Y89878I-104J170D01*
G01X761751Y89919D01*
X761749D01*
X761509Y90026D01*
G02X761501Y90030I85J181D01*
G01X761447Y90057D01*
X761428Y90088D01*
Y102060D01*
X761436Y102075D01*
G02X761541Y102167I176J-95D01*
G01X761552Y102171D01*
X761569Y102176D01*
G03X762569Y103190I-451J1445D01*
G01X762574Y103206D01*
X762577Y103216D01*
X762588Y103235D01*
G02X762618Y103273I171J-104D01*
G01X767096Y107751D01*
G03X767478Y108673I-924J923D01*
G01Y115362D01*
G02X767516Y115400I159J-121D01*
G01X767533Y115413D01*
X767730Y115496D01*
X767732D01*
X767886Y115562D01*
G02X768022Y115564I71J-187D01*
G01X768117Y115524D01*
X768142Y115501D01*
X768144Y115499D01*
G03X769174Y115091I1030J1097D01*
G01X769175D01*
G03X770678Y116594I0J1503D01*
G03X770127Y117757I-1503J0D01*
G01X770115Y117769D01*
G02X770077Y117822I141J141D01*
G01X770051Y117875D01*
X770050Y117878D01*
X770040Y117898D01*
G02X770025Y117942I181J86D01*
G02X770021Y117981I196J40D01*
G01Y118205D01*
G02X770036Y118281I200J0D01*
G01X770052Y118316D01*
X770082Y118376D01*
G02X770093Y118394I176J-95D01*
G02X770110Y118414I161J-119D01*
G01X770131Y118435D01*
X770138Y118441D01*
G03X770677Y119594I-964J1153D01*
G03X769175Y121096I-1502J0D01*
G03X768112Y120655I0J-1502D01*
G02X767959Y120606I-132J150D01*
G01X767929Y120609D01*
X767732Y120692D01*
X767730D01*
X767555Y120766D01*
G02X767478Y120828I83J182D01*
G01Y130498D01*
G02X767500Y130589I200J0D01*
G02X767536Y130639I178J-90D01*
G01X785394Y148496D01*
G02X785526Y148543I129J-153D01*
G01X785529D01*
X785570Y148542D01*
X785643Y148508D01*
X785651Y148500D01*
X785685Y148462D01*
G02X785710Y148425I-152J-130D01*
G01X785723Y148400D01*
X785727Y148384D01*
X785729Y148374D01*
G03X787192Y147215I1463J344D01*
G03X788694Y148717I0J1502D01*
G03X787535Y150180I-1503J0D01*
G01X787534D01*
X787506Y150187D01*
X787465Y150208D01*
X787438Y150232D01*
X787437Y150233D01*
X787411Y150256D01*
X787409Y150258D01*
X787372Y150291D01*
G02X787369Y150294I140J143D01*
G01X787367Y150380D01*
Y150383D01*
G02X787425Y150527I200J3D01*
G01X790062Y153164D01*
G02X790164Y153217I139J-143D01*
G02X790202Y153221I40J-196D01*
G01X790899D01*
G02X790931Y153218I-3J-200D01*
G01X790933D01*
G02X791038Y153165I-34J-197D01*
G01X792017Y152185D01*
G02X792024Y152176I-154J-127D01*
G01Y144624D01*
G02X792002Y144534I-200J1D01*
G01X791993Y144517D01*
G03X791885Y144289I1299J-755D01*
G01X791880Y144275D01*
X791869Y144243D01*
X791868Y144241D01*
X791865Y144231D01*
X791864Y144228D01*
G03X791861Y144219I1423J-479D01*
G02X791859Y144213I-191J60D01*
G03X791856Y144205I1404J-531D01*
G01X791852Y144193D01*
G02X791847Y144181I-187J71D01*
G02X791808Y144126I-180J87D01*
G01X785940Y138258D01*
G03X785558Y137336I924J-923D01*
G01Y127603D01*
G02X785523Y127567I-160J120D01*
G01X785492Y127541D01*
X785406Y127471D01*
X785280Y127368D01*
X785249Y127344D01*
X785157Y127363D01*
X785156D01*
G03X784891Y127404I-485J-2255D01*
G03X784678Y127414I-215J-2297D01*
G01X784494D01*
Y127407D01*
G03X782372Y125109I184J-2299D01*
G01Y121166D01*
G02X782361Y121153I-158J123D01*
G01X782345Y121135D01*
X782040Y120946D01*
G02X781846Y120941I-102J172D01*
G01X781836Y120946D01*
X781803Y120962D01*
X781772Y120976D01*
G03X781144Y121113I-630J-1382D01*
G03X779625Y119594I0J-1519D01*
G03X780181Y118421I1515J0D01*
G01X780183Y118419D01*
X780205Y118400D01*
X780221Y118387D01*
X780235Y118371D01*
G02X780258Y118336I-155J-127D01*
G01X780284Y118280D01*
G02X780298Y118207I-186J-74D01*
G01Y117983D01*
G02X780280Y117900I-200J0D01*
G01X780267Y117873D01*
Y117871D01*
X780240Y117817D01*
G02X780207Y117772I-176J95D01*
G01X780188Y117753D01*
X780181Y117747D01*
G03X779642Y116594I964J-1153D01*
G03X781144Y115092I1502J0D01*
G01Y115091D01*
G03X782012Y115367I0J1503D01*
G02X782014Y115369I140J-138D01*
G01X782049Y115393D01*
X782089Y115401D01*
G02X782178Y115399I40J-196D01*
G01X782473Y115323D01*
G02X782596Y115231I-49J-194D01*
G01X782603Y115215D01*
G03X783047Y114592I2074J1009D01*
G01X792647Y104992D01*
G02X792700Y104890I-143J-139D01*
G02X792704Y104852I-196J-40D01*
G01Y95111D01*
G03X797318I2307J0D01*
G01Y105213D01*
G02X797359Y105254I160J-119D01*
G01X798519D01*
X798529D01*
G02X798610Y105232I-11J-200D01*
G03X798703Y105182I773J1327D01*
G01X798726Y105171D01*
X798728Y105170D01*
X798763Y105140D01*
X798778Y105119D01*
G02X798732Y104840I-163J-116D01*
G01X798709Y104824D01*
X798685Y104815D01*
G03X797719Y103411I537J-1404D01*
G03X800723I1502J0D01*
G03X800144Y104596I-1502J0D01*
G01X800126Y104610D01*
X800089Y104655D01*
G02X800059Y104704I154J128D01*
G01Y104706D01*
G02X800043Y104793I184J79D01*
G01X800048Y104897D01*
Y104899D01*
X800059Y105081D01*
X800070Y105129D01*
X800094Y105173D01*
G02X800154Y105236I172J-103D01*
G01X800158Y105239D01*
X800164Y105242D01*
G03X800915Y106561I-783J1319D01*
G03X799380Y108096I-1535J0D01*
G01X799379D01*
G03X798617Y107894I0J-1537D01*
G01X798594Y107881D01*
X798570Y107875D01*
G02X798519Y107868I-52J193D01*
G01X798028D01*
G02X797887Y107926I0J200D01*
G01X791772Y114039D01*
X788189Y117623D01*
G02X788170Y117645I141J141D01*
G01Y136710D01*
G02X788172Y136740I200J2D01*
G02X788227Y136850I198J-30D01*
G01X791889Y140511D01*
X793691Y142313D01*
X793717Y142321D01*
G03X794794Y143749I-425J1441D01*
G01Y143776D01*
G03X794766Y144055I-1503J-10D01*
G01X794760Y144084D01*
G03X794671Y144359I-1467J-323D01*
G01Y144361D01*
G03X794656Y144393I-1368J-622D01*
G01X794638Y144433D01*
Y155324D01*
G02X794645Y155333I161J-118D01*
G01X814145Y174834D01*
G03X814204Y174976I-141J142D01*
G01Y175277D01*
G02X814211Y175329I200J0D01*
G01X814214Y175338D01*
G02X814236Y175384I190J-63D01*
G01Y175385D01*
G03X814442Y176088I-1100J704D01*
G01Y303156D01*
G02X814464Y303247I200J0D01*
G02X814500Y303297I178J-90D01*
G01X815766Y304563D01*
G02X815810Y304565I31J-197D01*
G01X816112Y304543D01*
X816150Y304522D01*
X816152Y304521D01*
X816251Y304467D01*
X816277Y304435D01*
G03X817456Y303864I1179J932D01*
G03X818960Y305368I0J1504D01*
G03X818389Y306547I-1503J0D01*
G01X818356Y306573D01*
X818299Y306681D01*
G02X818279Y306754I179J88D01*
G01X818263Y306965D01*
X818261Y307000D01*
Y307001D01*
X818260Y307014D01*
Y307029D01*
G02X818263Y307060I200J-4D01*
G01X819739Y308535D01*
X820466Y309262D01*
X820512Y309256D01*
X820531Y309254D01*
X820607Y309231D01*
X820609D01*
X820877Y309156D01*
G02X820900Y309148I-54J-192D01*
G02X820968Y309102I-76J-185D01*
G01X820986Y309084D01*
X821011Y309040D01*
X821018Y309011D01*
Y309010D01*
G03X822477Y307866I1459J358D01*
G03X823979Y309368I0J1502D01*
G03X822860Y310821I-1503J0D01*
G01X822833Y310828D01*
X822780Y310858D01*
G02X822734Y310895I101J173D01*
G02X822687Y310978I145J137D01*
G01X822611Y311249D01*
Y311251D01*
X822594Y311311D01*
G02X822591Y311387I194J46D01*
G01X826895Y315691D01*
G03X827278Y316615I-923J924D01*
G01Y344357D01*
X827290Y344380D01*
X827301Y344402D01*
G03X827473Y345099I-1331J698D01*
G01Y345101D01*
G03X824469I-1502J0D01*
G01Y345099D01*
G03X824641Y344402I1503J1D01*
G01X824652Y344380D01*
X824664Y344357D01*
Y317239D01*
G02X824642Y317148I-200J0D01*
G02X824606Y317098I-178J90D01*
G01X814029Y306521D01*
G02X813916Y306465I-141J142D01*
G02X813460Y306860I-56J396D01*
G01Y307879D01*
G03X813069Y308794I-1267J-1D01*
G01X813065Y308797D01*
X812848Y309014D01*
X812836Y309034D01*
G03X812654Y309264I-1109J-691D01*
G03X812647Y309271I-927J-920D01*
G01X810950Y310968D01*
G02X810919Y311008I141J142D01*
G01X810908Y311027D01*
G03X810285Y311864I-1442J-423D01*
G02X810253Y311890I109J167D01*
G01X810238Y311905D01*
G02X810191Y311978I141J142D01*
G01X810178Y312015D01*
X810179Y312209D01*
X810180Y312386D01*
G02X810200Y312460I200J-14D01*
G01X810207Y312473D01*
G02X810238Y312513I172J-102D01*
G01X810275Y312550D01*
X810294Y312562D01*
G03X810991Y313830I-805J1268D01*
G03X807987I-1502J0D01*
G03X808670Y312571I1502J0D01*
G01X808685Y312561D01*
X808746Y312500D01*
G02X808753Y312488I-169J-107D01*
G02X808777Y312390I-176J-95D01*
G01X808775Y312221D01*
Y312219D01*
X808774Y312060D01*
G02X808752Y311971I-200J2D01*
G01X808738Y311942D01*
X808699Y311903D01*
G02X808665Y311876I-141J142D01*
G03X807963Y310604I801J-1272D01*
G03X809046Y309161I1503J0D01*
G01X809068Y309154D01*
X809494Y308728D01*
X810363Y307860D01*
G02X810419Y307740I-143J-140D01*
G02X810420Y307720I-199J-20D01*
G01Y307195D01*
G02X810340Y307035I-200J0D01*
G01X810084Y306843D01*
G02X809963Y306803I-120J160D01*
G01X809909Y306811D01*
X809908D01*
G03X809901Y306813I-416J-1443D01*
G01X809895Y306815D01*
G03X809499Y306870I-403J-1447D01*
G01X809489D01*
G03X809425Y306869I-9J-1502D01*
G01X809423D01*
G03X807988Y305368I68J-1501D01*
G03X809490Y303866I1502J0D01*
G01X809492D01*
G03X809823Y303903I0J1502D01*
G01X809845Y303908D01*
X809941D01*
G02X809979Y303894I-50J-194D01*
G01X809995Y303886D01*
G02X810012Y303875I-100J-173D01*
G01X810172Y303748D01*
X810174D01*
X810258Y303682D01*
G02X810307Y303627I-122J-158D01*
G01X810311Y303620D01*
Y303619D01*
X810316Y303611D01*
G02X810340Y303517I-176J-95D01*
G01Y266831D01*
G02X810332Y266775I-200J0D01*
G02X810326Y266757I-193J54D01*
G01X810311Y266721D01*
X808062Y264472D01*
G02X808012Y264436I-140J142D01*
G02X807921Y264414I-91J178D01*
G01X802267D01*
G02X802211Y264422I0J200D01*
G02X802193Y264428I54J193D01*
G01X802157Y264443D01*
X795474Y271126D01*
G02X795456Y271147I142J140D01*
G01Y289230D01*
G03X794781Y290860I-2306J0D01*
G01X790982Y294659D01*
G03X789352Y295334I-1630J-1631D01*
G01X786461D01*
G03Y290722I0J-2306D01*
G01X788313D01*
G02X788427Y290687I1J-200D01*
G02X788443Y290674I-118J-162D01*
G01X789242Y289875D01*
G02X789244Y289836I-198J-30D01*
G01X789220Y289630D01*
X789200Y289464D01*
X789197Y289459D01*
X789152Y289434D01*
G03X789150Y289432I135J-137D01*
G01X789113Y289411D01*
G03X787973Y287421I1167J-1990D01*
G01X787974Y281165D01*
Y273060D01*
G02X787850Y272875I-200J0D01*
G01X787837Y272869D01*
X787822Y272863D01*
X787763Y272857D01*
X787735Y272863D01*
G02X787634Y272917I40J196D01*
G01X771968Y288583D01*
G02X771932Y288633I142J140D01*
G02X771910Y288724I178J91D01*
G01Y300695D01*
G03X771907Y300820I-2267J8D01*
G01Y300821D01*
X771906Y300830D01*
Y301946D01*
G03X771231Y303576I-2306J0D01*
G01X746846Y327961D01*
G03X745216Y328636I-1630J-1631D01*
G01X744920D01*
G02X744863Y328644I-1J200D01*
G01X744837Y328652D01*
X744810Y328670D01*
G03X743560Y329046I-1250J-1891D01*
G01X727660D01*
G02X727519Y329104I0J200D01*
G01X702854Y353769D01*
G02X702841Y353785I149J134D01*
G02X702806Y353899I165J113D01*
G01Y460531D01*
G02X702828Y460622I200J0D01*
G02X702864Y460672I178J-90D01*
G01X706587Y464395D01*
G02X706601Y464407I137J-146D01*
G03X706603Y464409I-140J142D01*
G02X706624Y464424I127J-155D01*
G01X706643Y464435D01*
X706655Y464439D01*
X706668Y464443D01*
G03X706678Y464446I-427J1440D01*
G01X706690Y464450D01*
G03X707147Y464699I-479J1424D01*
G03X707467Y465048I-934J1177D01*
G01X707469Y465051D01*
X707482Y465070D01*
X707497Y465084D01*
G02X707529Y465109I138J-144D01*
G01X707582Y465141D01*
X707604Y465153D01*
X707628Y465165D01*
G02X707717Y465186I89J-179D01*
G01X717067D01*
G02X717126Y465177I0J-200D01*
G02X717129Y465176I-62J-190D01*
G02X717252Y465058I-64J-190D01*
G01X717256Y465047D01*
X717260Y465034D01*
X717262Y465028D01*
G03X717270Y465006I1416J502D01*
G01Y465004D01*
G03X718691Y463989I1421J487D01*
G01X718718Y463990D01*
X718719D01*
G03X718807Y463994I-24J1502D01*
G03X718966Y464015I-117J1498D01*
G01X718992Y464019D01*
G03X719790Y463632I2101J3317D01*
G03X722005Y463517I1303J3705D01*
G01X722031Y463524D01*
G03X723192Y464019I-940J3813D01*
G03X723255Y464008I290J1474D01*
G01X723257D01*
X723271Y464006D01*
G03X723315Y464000I225J1485D01*
G01X723370Y463994D01*
G03X723491Y463989I123J1498D01*
G03X724645Y464528I0J1505D01*
G01X724649Y464533D01*
X724652Y464535D01*
G02X724726Y464573I126J-155D01*
G03X725845Y464853I-384J3909D01*
G01X726635Y465179D01*
G02X726685Y465186I52J-193D01*
G01X729897D01*
G02X729992Y465162I0J-200D01*
G01X730011Y465152D01*
G03X730014Y465150I112J164D01*
G01X730017Y465148D01*
G03X730050Y465131I107J168D01*
G01X730062Y465126D01*
X730074Y465120D01*
G02X730117Y465087I-99J-174D01*
G01X730122Y465082D01*
X730134Y465069D01*
X730135Y465068D01*
X730138Y465064D01*
G03X731197Y464528I1153J963D01*
G02X731351Y464439I-13J-200D01*
G01X731446Y464296D01*
Y464294D01*
X731530Y464166D01*
G02X731558Y464041I-171J-104D01*
G01X731543Y463999D01*
G03X731451Y463482I1416J-519D01*
G01Y463479D01*
G03X734467I1508J0D01*
G01Y463480D01*
G03X734082Y464486I-1508J0D01*
G01X734071Y464498D01*
X734032Y464560D01*
X734018Y464597D01*
G02X734005Y464669I187J71D01*
G02X734021Y464745I200J-2D01*
G01X734059Y464835D01*
Y464837D01*
X734139Y465023D01*
X734143Y465032D01*
G02X734214Y465112I180J-88D01*
G01X734270Y465144D01*
X734295Y465159D01*
G02X734334Y465176I99J-174D01*
G02X734378Y465185I62J-190D01*
G01X734380D01*
G02X734396Y465186I20J-199D01*
G01X739983D01*
G02X740164Y465057I-6J-200D01*
G01X740168Y465045D01*
G03X740656Y464325I1434J447D01*
G03X741426Y464000I946J1167D01*
G01X741472Y463995D01*
G03X741602Y463989I134J1497D01*
G03X743037Y465045I0J1503D01*
G01X743038Y465050D01*
X743041Y465056D01*
X743044Y465064D01*
G02X743112Y465149I184J-78D01*
G01X743136Y465167D01*
X743167Y465177D01*
G02X743227Y465186I59J-191D01*
G01X747776D01*
G02X747906Y465138I0J-200D01*
G02X747962Y465059I-130J-152D01*
G01X747969Y465040D01*
X747971Y465035D01*
G03X749063Y464029I1431J457D01*
G03X749343Y463991I341J1463D01*
G01X749351D01*
G03X749364Y463990I122J1496D01*
G01X749404D01*
G03X749768Y464035I-1J1502D01*
G01X749792Y464041D01*
X749888D01*
X749928Y464026D01*
X749959Y464013D01*
X750013Y463970D01*
X750015Y463968D01*
X750219Y463806D01*
X750223Y463803D01*
X750224Y463802D01*
G02X750295Y463649I-129J-153D01*
G01Y463636D01*
X750294Y463626D01*
Y460217D01*
G03X753900I1803J0D01*
G01Y463617D01*
G03X752763Y465292I-1802J0D01*
G01X752725Y465307D01*
X752651Y465381D01*
X752650D01*
G02X752588Y465425I83J182D01*
G01X752584Y465430D01*
G02X752545Y465495I149J134D01*
G02X752540Y465511I188J68D01*
G01X752483Y465755D01*
X752482Y465761D01*
X752474Y465792D01*
G02X752526Y465983I194J50D01*
G01X802091Y515548D01*
G02X802210Y515630I283J-283D01*
G02X802292Y515648I83J-182D01*
G01X802491D01*
G02X802494Y515647I-125J-380D01*
G01Y514902D01*
G02X802488Y514852I-200J-1D01*
G02X802436Y514761I-194J50D01*
G01X792476Y504802D01*
G03X792094Y503880I924J-923D01*
G01Y472710D01*
G02X792082Y472640I-200J-2D01*
G02X792036Y472569I-187J71D01*
G01X760443Y440977D01*
G03X760060Y440053I923J-924D01*
G01Y420877D01*
G02X760038Y420786I-200J0D01*
G02X760002Y420736I-178J90D01*
G01X756064Y416798D01*
G02X756014Y416762I-140J142D01*
G02X755923Y416740I-91J178D01*
G01X744495D01*
G03X743571Y416357I0J-1306D01*
G01X733737Y406523D01*
G03X733354Y405599I923J-924D01*
G01Y394377D01*
X733342Y394354D01*
X733331Y394332D01*
G03X733159Y393635I1331J-698D01*
G01Y393633D01*
G03X736163I1502J0D01*
G01Y393635D01*
G03X735991Y394332I-1503J-1D01*
G01X735980Y394354D01*
X735968Y394377D01*
Y404975D01*
G02X735972Y405013I200J-2D01*
G02X736025Y405115I196J-37D01*
G01X744979Y414069D01*
G02X745081Y414122I139J-143D01*
G02X745119Y414126I40J-196D01*
G01X747997D01*
G02X748172Y414021I-1J-200D01*
G01X748180Y414001D01*
G02X748192Y413885I-184J-78D01*
G01X748187Y413859D01*
X748159Y413807D01*
X739460Y405108D01*
G03X739078Y404186I924J-923D01*
G01Y390610D01*
G02X739075Y390578I-200J3D01*
G02X739021Y390470I-197J31D01*
G01X733721Y385171D01*
X731130Y382580D01*
X731088Y382555D01*
X731065Y382548D01*
G03X730009Y381113I447J-1435D01*
G03X731511Y379611I1502J0D01*
G03X732946Y380667I0J1503D01*
G01X732953Y380690D01*
X732978Y380732D01*
X741308Y389062D01*
G03X741690Y389984I-924J923D01*
G01Y403342D01*
G02X741709Y403364I160J-119D01*
G01X750480Y412133D01*
G02X750489Y412140I127J-154D01*
G01X757008D01*
G03X757932Y412523I0J1306D01*
G01X764701Y419292D01*
G03X765084Y420216I-923J924D01*
G01Y438019D01*
G02X765088Y438057I200J-2D01*
G02X765141Y438159I196J-37D01*
G01X793973Y466991D01*
G02X794181Y467037I141J-142D01*
G01X794190Y467033D01*
G02X794282Y466958I-75J-185D01*
G01X794297Y466935D01*
X794314Y466880D01*
Y452292D01*
G02X794258Y452153I-200J0D01*
G01X794200Y452093D01*
G02X794142Y452051I-144J138D01*
G01X794049Y452007D01*
X794048D01*
G03X794023Y452005I107J-1498D01*
G01X794015Y452004D01*
G03Y449016I158J-1494D01*
G01X794023Y449015D01*
G03X794048Y449013I132J1496D01*
G01X794049D01*
X794142Y448969D01*
G02X794200Y448927I-86J-180D01*
G01X794258Y448867D01*
G02X794314Y448728I-144J-139D01*
G01Y421558D01*
G02X794306Y421503I-200J1D01*
G02X794256Y421417I-192J54D01*
G01X783852Y411013D01*
X781428Y408591D01*
G03X780752Y406960I1631J-1632D01*
G01Y341472D01*
G02X780694Y341331I-200J0D01*
G01X779950Y340587D01*
X774311Y334947D01*
G02X774202Y334892I-140J143D01*
G02X774171Y334890I-28J198D01*
G01X772162D01*
G03Y330278I0J-2306D01*
G01X775210D01*
G03X776840Y330953I0J2306D01*
G01X784690Y338802D01*
G03X785366Y340433I-1631J1632D01*
G01Y364700D01*
G02X785471Y364875I200J-1D01*
G01X785491Y364883D01*
G02X785607Y364895I78J-184D01*
G01X785633Y364890D01*
X785685Y364862D01*
X793978Y356569D01*
X794003Y356527D01*
X794010Y356504D01*
G03X795445Y355448I1435J447D01*
G03X796947Y356950I0J1502D01*
G01X796948D01*
G03X795891Y358385I-1503J0D01*
G01X795890D01*
G02X795808Y358435I60J191D01*
G01X787122Y367120D01*
G02X787070Y367213I142J141D01*
G02X787064Y367261I194J49D01*
G01Y405277D01*
G02X787068Y405315I200J-2D01*
G02X787121Y405417I196J-37D01*
G01X791735Y410030D01*
G02X791930Y410066I129J-153D01*
G02X791952Y410057I-65J-190D01*
G01X792291Y409891D01*
G02X792380Y409806I-87J-180D01*
G02X792402Y409687I-176J-94D01*
G01Y409686D01*
G03X792391Y409502I1491J-181D01*
G03X793893Y411004I1502J0D01*
G03X793709Y410993I-3J-1502D01*
G01X793708D01*
G02X793589Y411015I-25J198D01*
G02X793504Y411104I95J176D01*
G01X793338Y411443D01*
G02X793330Y411464I183J82D01*
G02X793365Y411660I188J68D01*
G01X799352Y417647D01*
G03X799356Y417651I-922J926D01*
G03X799540Y417883I-925J923D01*
G01X799552Y417903D01*
X800229Y418580D01*
G03X800600Y419476I-896J896D01*
G01Y446808D01*
G02X800710Y446986I200J-1D01*
G01X801027Y447145D01*
G02X801204Y447147I91J-179D01*
G01X801230Y447134D01*
X801245Y447123D01*
G03X802134Y446832I889J1213D01*
G01X802136D01*
G03Y449836I0J1502D01*
G03X801239Y449539I0J-1503D01*
G01X801231Y449533D01*
G02X801137Y449500I-111J166D01*
G01X801111Y449498D01*
X801084Y449503D01*
G02X801030Y449521I36J197D01*
G01X800891Y449591D01*
X800698Y449688D01*
G02X800688Y449694I98J174D01*
G02X800602Y449833I112J166D01*
G01Y449835D01*
G02X800600Y449860I198J28D01*
G01Y499370D01*
G02X800604Y499408I200J-2D01*
G02X800657Y499510I196J-37D01*
G01X810637Y509490D01*
G03X811020Y510414I-923J924D01*
G01Y518789D01*
G02X811024Y518827I200J-2D01*
G02X811077Y518929I196J-37D01*
G01X825146Y532998D01*
G02X825344Y533048I141J-142D01*
G01X825735Y532931D01*
X825809Y532850D01*
X825820Y532796D01*
G03X827291Y531598I1471J304D01*
G03X828793Y533100I0J1502D01*
G03X828705Y533606I-1502J-1D01*
G02X828709Y533750I188J67D01*
G01X828813Y533999D01*
G02X828911Y534103I185J-76D01*
G03X829774Y535462I-639J1359D01*
G03X829768Y535597I-1502J1D01*
G02X829769Y535641I199J17D01*
G03X829781Y535797I-1490J193D01*
G01Y535838D01*
G03X829524Y536677I-1502J-1D01*
G02X829509Y536703I165J113D01*
G01X829491Y536741D01*
X829482Y536768D01*
G03X829481Y536771I-190J-62D01*
G01X829465Y536818D01*
G02X829464Y536820I177J90D01*
G01Y536821D01*
G02X829475Y536972I190J62D01*
G01X829480Y536982D01*
X829491Y537080D01*
X829495Y537118D01*
X829560Y537241D01*
X829586Y537265D01*
G03X829893Y537656I-1012J1110D01*
G03X830008Y537926I-1318J721D01*
G01X830012Y537939D01*
G03X830075Y538309I-1438J435D01*
G01Y538316D01*
G03X830076Y538375I-1501J55D01*
G01Y538380D01*
G03X828575Y539877I-1502J-5D01*
G01X828542D01*
G03X827842Y539687I32J-1502D01*
G03X827753Y539633I734J-1310D01*
G03X827723Y539613I818J-1260D01*
G02X827684Y539592I-114J165D01*
G02X827522Y539598I-74J186D01*
G01X827420Y539647D01*
G02X827306Y539827I86J180D01*
G01Y540681D01*
G02X827328Y540772I200J0D01*
G02X827364Y540822I178J-90D01*
G01X828737Y542195D01*
G02X829019I141J-142D01*
G01X833368Y537846D01*
G02X833426Y537694I-142J-141D01*
G01X833410Y537396D01*
G02X833389Y537317I-199J11D01*
G01X833371Y537280D01*
X833336Y537252D01*
G03X832780Y536085I947J-1167D01*
G03X834282Y534583I1502J0D01*
G01Y534582D01*
G03X835450Y535139I0J1503D01*
G01X835451Y535140D01*
G02X835517Y535194I157J-124D01*
G01X835551Y535211D01*
X835891Y535229D01*
G02X836043Y535171I11J-200D01*
G01X851495Y519719D01*
G02X851548Y519617I-143J-139D01*
G02X851552Y519579I-196J-40D01*
G01Y472133D01*
G02X851530Y472042I-200J0D01*
G02X851494Y471992I-178J90D01*
G01X850334Y470832D01*
X850296Y470820D01*
G03X849230Y469382I437J-1438D01*
G03X850732Y467880I1502J0D01*
G01X850735D01*
G03X851194Y467952I-1J1502D01*
G01X851224Y467962D01*
X851299D01*
G02X851325Y467960I-2J-200D01*
G02X851408Y467930I-25J-198D01*
G01X851528Y467844D01*
X851668Y467744D01*
G02X851725Y467678I-119J-161D01*
G02X851743Y467631I-177J-95D01*
G02X851748Y467585I-195J-44D01*
G01Y467185D01*
G02X851685Y467039I-200J0D01*
G03X851683Y467038I84J-171D01*
G02X851665Y467023I-137J146D01*
G01X851411Y466839D01*
G02X851303Y466807I-109J168D01*
G01X851224D01*
X851208Y466812D01*
G03X851152Y466829I-464J-1428D01*
G03X850765Y466884I-403J-1447D01*
G01X850751D01*
G03X850745I-3J-1502D01*
G01X850743D01*
G03X849246Y465382I5J-1502D01*
G03X850748Y463880I1502J0D01*
G01X850753D01*
G03X850756I1J1503D01*
G03X851214Y463952I-2J1503D01*
G01X851230Y463957D01*
X851264Y463962D01*
G02X851403Y463932I30J-198D01*
G01X851582Y463801D01*
X851667Y463738D01*
G02X851678Y463729I-121J-159D01*
G01X851701Y463706D01*
G02X851733Y463654I-152J-130D01*
G01X851748Y463617D01*
Y459744D01*
G02X851738Y459682I-200J0D01*
G02X851734Y459670I-192J57D01*
G01X851720Y459636D01*
X851693Y459608D01*
G03X851684Y459597I150J-132D01*
G01X851677Y459588D01*
X834272Y442183D01*
G03X833977Y441719I896J-895D01*
G01Y441714D01*
X833952Y441648D01*
G03X833945Y441619I190J-61D01*
G02X833942Y441607I-195J42D01*
G01Y441606D01*
G03X833902Y441287I1226J-316D01*
G01Y415204D01*
Y415203D01*
G03X833916Y415008I1267J-7D01*
G03X833918Y414995I1253J186D01*
G03X833928Y414942I1249J208D01*
G01Y414940D01*
G03X833978Y414768I1239J267D01*
G01X833989Y414740D01*
G03X833991Y414735I1177J468D01*
G01X833992Y414733D01*
X834435Y413663D01*
G02X834446Y413610I-189J-67D01*
G01Y412919D01*
G03X834533Y412452I1307J2D01*
G01Y412450D01*
G03X834546Y412419I1211J490D01*
G01X838351Y403231D01*
X839972Y399316D01*
G02X839980Y399290I-187J-72D01*
G01X840251Y397925D01*
X840429Y397028D01*
X840930Y394501D01*
G02X840934Y394462I-196J-40D01*
G01Y325599D01*
X840925Y325582D01*
G03X840738Y324856I1317J-726D01*
G01Y324854D01*
G03X843742I1502J0D01*
G01Y324855D01*
G03X843552Y325586I-1504J-1D01*
G01X843546Y325597D01*
Y354988D01*
Y354995D01*
G02X843662Y355170I200J-7D01*
G02X843680Y355177I81J-183D01*
G01X844037Y355301D01*
G02X844158Y355305I67J-189D01*
G01X844188Y355296D01*
X844239Y355262D01*
X844259Y355237D01*
G03X845435Y354670I1176J936D01*
G01X845440D01*
G03X845584Y354676I10J1502D01*
G01X845593Y354677D01*
X845596D01*
G02X845731Y354640I18J-199D01*
G01X845963Y354434D01*
X845970Y354427D01*
G03X845972Y354425I142J140D01*
G01X845977Y354420D01*
G02X846030Y354319I-143J-140D01*
G01Y354317D01*
G02X846034Y354280I-196J-40D01*
G01Y316119D01*
G03X846105Y315695I1267J-6D01*
G01X846106Y315694D01*
X846107Y315691D01*
X846110Y315684D01*
X846114Y315674D01*
X846115Y315672D01*
G03X846144Y315601I1186J443D01*
G01X846406Y315225D01*
G03X846429Y315198I163J116D01*
G01X855681Y305945D01*
G02X855732Y305852I-143J-139D01*
G02X855738Y305805I-194J-49D01*
G01Y305254D01*
G03X856121Y304330I1306J0D01*
G01X864961Y295490D01*
G02X865014Y295388I-143J-139D01*
G02X865018Y295350I-196J-40D01*
G01Y267769D01*
G02X865015Y267737I-200J3D01*
G01Y267736D01*
X865014Y267731D01*
X865007Y267692D01*
G02X864995Y267654I-196J41D01*
G01X864989Y267639D01*
X864964Y267612D01*
G02X864934Y267586I-145J138D01*
G02X864908Y267571I-113J165D01*
G01X864855Y267544D01*
G03X864811Y267514I90J-179D01*
G01X864727Y267436D01*
G02X864629Y267392I-128J154D01*
G02X864580Y267391I-29J198D01*
G01X864576D01*
X864567Y267392D01*
G03X864409Y267399I-145J-1495D01*
G03X863486Y267073I11J-1502D01*
G01X863485Y267072D01*
X863473Y267062D01*
G02X863367Y267029I-110J167D01*
G01X863275D01*
G03X863192Y267011I0J-200D01*
G01X863138Y266986D01*
G02X863060Y266967I-85J181D01*
G02X863026Y266969I-5J200D01*
G02X862922Y267017I28J198D01*
G01X862921Y267018D01*
G03X861922Y267399I-1000J-1122D01*
G01X861920D01*
G03Y264395I0J-1502D01*
G01X861922D01*
G03X862856Y264722I-1J1501D01*
G01X862882Y264742D01*
X862926Y264757D01*
G02X862979Y264765I56J-192D01*
G01X863058D01*
G03X863149Y264787I0J200D01*
G01X863150Y264788D01*
G03X863154Y264790I-87J180D01*
G01X863159Y264792D01*
X863198Y264811D01*
G02X863381Y264797I78J-184D01*
G01X863437Y264761D01*
X863450Y264750D01*
X863456Y264745D01*
X863458Y264743D01*
X863470Y264733D01*
X863490Y264713D01*
G02X863535Y264644I-141J-141D01*
G02X863548Y264582I-187J-72D01*
G01X863558Y264394D01*
Y264392D01*
X863564Y264293D01*
X863566Y264245D01*
X863551Y264205D01*
G02X863505Y264135I-187J72D01*
G01X859094Y259724D01*
G02X859044Y259688I-140J142D01*
G02X858953Y259666I-91J178D01*
G01X850183D01*
X850151Y259677D01*
G03X850042Y259709I-422J-1236D01*
G03X849730Y259746I-309J-1269D01*
G01X847074D01*
G03X846152Y259364I1J-1306D01*
G01X844558Y257770D01*
X844516Y257745D01*
X844493Y257738D01*
G03X843442Y256174I446J-1435D01*
G01X843443Y256166D01*
Y256163D01*
X843448Y256114D01*
X843437Y256069D01*
G02X843397Y255996I-191J57D01*
G01X843223Y255800D01*
X843191Y255764D01*
G02X843105Y255714I-140J142D01*
G01X843103Y255713D01*
X843072Y255704D01*
X841005D01*
G02X840949Y255712I0J200D01*
G02X840931Y255718I54J193D01*
G01X840895Y255733D01*
X836852Y259776D01*
G03X836389Y260071I-896J-896D01*
G01X836347Y260085D01*
X836317Y260096D01*
G03X836289Y260104I-69J-188D01*
G01X836288D01*
G03X836272Y260107I-45J-195D01*
G01X836267Y260108D01*
X836265D01*
G03X835821Y260186I-445J-1228D01*
G01X822905D01*
X822888Y260195D01*
G03X822162Y260382I-726J-1317D01*
G01X822160D01*
G03Y257378I0J-1502D01*
G01X822161D01*
G03X822892Y257568I-1J1504D01*
G01X822903Y257574D01*
X835196D01*
G02X835232Y257571I1J-200D01*
G02X835337Y257516I-36J-197D01*
G01X838744Y254108D01*
X839378Y253474D01*
G03X839845Y253174I924J924D01*
G01X839861Y253168D01*
X839887Y253158D01*
X842113Y250931D01*
X842116Y250927D01*
G03X842686Y250584I916J877D01*
G01X842697Y250582D01*
X842708Y250579D01*
G03X843030Y250536I327J1225D01*
G01X851450D01*
G02X851556Y250503I-4J-200D01*
G01X851583Y250484D01*
G02X851601Y250468I-124J-157D01*
G02X851652Y250379I-142J-141D01*
G01X851666Y250328D01*
X851683Y250287D01*
X851701Y250240D01*
G03X851738Y250180I186J74D01*
G01X851742Y250175D01*
G02X851787Y250077I-152J-129D01*
G01X851791Y250050D01*
X851788Y250023D01*
G02X851772Y249967I-198J26D01*
G01X851738Y249891D01*
Y249889D01*
X851720Y249848D01*
X851694Y249821D01*
G03X851693Y249820I1062J-1063D01*
G03X851691Y249818I140J-142D01*
G03X851261Y248773I1072J-1052D01*
G01Y248741D01*
G03X852707Y247264I1502J24D01*
G01X852708D01*
G03X852763Y247263I55J1501D01*
G01X852765D01*
G03X853699Y247590I-1J1501D01*
G01X853725Y247610D01*
X853769Y247625D01*
G02X853822Y247633I56J-192D01*
G01X853908D01*
G03X853964Y247641I0J200D01*
G01X853978Y247644D01*
X854190D01*
G02X854315Y247600I0J-200D01*
G01X854316Y247599D01*
G03X854319Y247597I835J1249D01*
G03X854337Y247583I931J1178D01*
G02X854347Y247575I-120J-160D01*
G03X854350Y247572I1062J1059D01*
G03X854437Y247510I915J1192D01*
G01X854441Y247508D01*
X854472Y247487D01*
X854486Y247479D01*
G03X854760Y247349I777J1285D01*
G03X854763Y247348I64J186D01*
G01X854778Y247343D01*
G03X855183Y247265I484J1422D01*
G03X855260Y247263I77J1499D01*
G01X855263D01*
G03X855326Y247264I8J1502D01*
G01X855343Y247265D01*
G03X856197Y247589I-81J1500D01*
G01X856198Y247590D01*
X856210Y247600D01*
G02X856316Y247633I110J-167D01*
G01X856408D01*
G03X856491Y247651I0J200D01*
G01X856545Y247676D01*
G02X856623Y247695I85J-181D01*
G02X856657Y247693I5J-200D01*
G02X856761Y247645I-28J-198D01*
G01X856762Y247644D01*
G03X857761Y247263I1000J1122D01*
G01X857763D01*
G03X859265Y248765I0J1502D01*
G03X858832Y249820I-1502J0D01*
G01X858831Y249821D01*
X858807Y249846D01*
X858791Y249880D01*
X858776Y249912D01*
G02X858768Y249936I185J75D01*
G01X858756Y249992D01*
G02X858763Y250089I198J34D01*
G01X858838Y250273D01*
Y250275D01*
X858899Y250421D01*
G02X858926Y250464I182J-84D01*
G02X859080Y250536I154J-128D01*
G01X864060D01*
G02X864220Y250456I0J-200D01*
G01Y228906D01*
G02X864198Y228815I-200J0D01*
G02X864162Y228765I-178J90D01*
G01X862703Y227306D01*
G03X862320Y226382I923J-924D01*
G01Y222748D01*
G02X862240Y222685I-160J120D01*
G01X861876Y222552D01*
G02X861756Y222546I-70J187D01*
G01X861727Y222554D01*
X861675Y222587D01*
X861655Y222611D01*
G03X860506Y223144I-1149J-972D01*
G03Y220140I0J-1502D01*
G03X861633Y220648I0J1504D01*
G01X861656Y220674D01*
X861718Y220715D01*
G02X861875Y220733I99J-174D01*
G01X862098Y220652D01*
X862229Y220604D01*
G02X862320Y220536I-69J-188D01*
G01Y216982D01*
G03X862703Y216058I1306J0D01*
G01X870278Y208483D01*
X870303Y208441D01*
X870310Y208418D01*
G03X873180I1435J446D01*
G01X873187Y208441D01*
X873212Y208483D01*
X873583Y208854D01*
G02X873696Y208910I141J-142D01*
G02X873919Y208877I55J-396D01*
G01X873921D01*
G02X874077Y208746I-171J-361D01*
G02X874112Y208634I-165J-113D01*
G01Y190995D01*
G02X874090Y190904I-200J0D01*
G02X874054Y190854I-178J90D01*
G01X871445Y188245D01*
X871403Y188220D01*
X871380Y188213D01*
G03X870324Y186778I447J-1435D01*
G03X871826Y185276I1502J0D01*
G03X873261Y186332I0J1503D01*
G01X873268Y186355D01*
X873293Y186397D01*
X875119Y188223D01*
G02X875232Y188279I141J-142D01*
G02X875688Y187884I56J-396D01*
G01Y164283D01*
G02X875680Y164227I-200J0D01*
G02X875674Y164209I-193J54D01*
G01X875659Y164173D01*
X855397Y143911D01*
G03X855026Y143015I896J-896D01*
G01Y116665D01*
G03X855320Y115854I1266J0D01*
G01X855326Y115847D01*
X855342Y115824D01*
X855345Y115819D01*
G03X855393Y115746I1115J681D01*
G03X855536Y115576I1068J753D01*
G01X856158Y114954D01*
X857424Y113689D01*
G02X857464Y113473I-144J-138D01*
G01X857420Y113367D01*
X857394Y113350D01*
X847137D01*
G03X846222Y112959I1J-1267D01*
G01X846219Y112955D01*
X846037Y112773D01*
X842630Y109365D01*
G02X842522Y109309I-142J141D01*
G02X842488Y109306I-35J197D01*
G01X841774D01*
G02X841593Y109423I1J200D01*
G01X841546Y109532D01*
X841446Y109765D01*
G02X841430Y109845I184J78D01*
G01X841484Y109979D01*
X841508Y110006D01*
G03X841981Y111223I-1329J1217D01*
G01X841980Y113128D01*
Y114623D01*
G03X838376I-1802J0D01*
G01Y113128D01*
X838375Y111223D01*
G03X838848Y110006I1802J0D01*
G01X838872Y109979D01*
X838926Y109845D01*
G02X838910Y109765I-200J-2D01*
G01X838810Y109532D01*
X838763Y109423D01*
G02X838582Y109306I-182J83D01*
G01X838323D01*
G03X837401Y108924I1J-1306D01*
G01X833262Y104784D01*
G02X833191Y104738I-142J141D01*
G02X833024Y104750I-70J187D01*
G02X833008Y104759I90J179D01*
G02X832832Y105091I224J332D01*
G01Y107649D01*
G03X829226I-1803J0D01*
G01Y104249D01*
G03X830420Y102551I1804J0D01*
G01X830461Y102536D01*
X830521Y102478D01*
X830534Y102463D01*
G02X830571Y102394I-155J-127D01*
G01X830582Y102345D01*
Y102343D01*
X830604Y102248D01*
G02X830573Y102101I-197J-35D01*
G01X830565Y102090D01*
G02X830549Y102072I-157J124D01*
G01X829803Y101326D01*
G02X829753Y101290I-140J142D01*
G02X829662Y101268I-91J178D01*
G01X820787D01*
X820764Y101280D01*
X820742Y101291D01*
G03X820044Y101463I-698J-1330D01*
G03X818542Y99961I0J-1502D01*
G03X819667Y98507I1502J0D01*
G01X819694Y98500D01*
X819721Y98484D01*
G02X819760Y98454I-101J-172D01*
G01X819792Y98422D01*
G02X819848Y98252I-142J-141D01*
G01X818463Y96867D01*
G03X817820Y95624I1631J-1631D01*
G01X817804Y95527D01*
G02X817731Y95482I-139J144D01*
G01X817467Y95398D01*
X817465D01*
X817417Y95383D01*
G02X817383Y95376I-57J192D01*
G02X817357Y95374I-28J198D01*
G01X817335D01*
X817299Y95389D01*
G02X817234Y95432I76J185D01*
G01X816506Y96160D01*
G03X815584Y96542I-923J-924D01*
G01X810906D01*
X810889Y96551D01*
G03X810163Y96738I-726J-1317D01*
G01X810161D01*
G03Y93734I0J-1502D01*
G01X810162D01*
G03X810893Y93924I-1J1504D01*
G01X810904Y93930D01*
X814958D01*
X814971D01*
G02X815098Y93873I-13J-200D01*
G01X815413Y93557D01*
X815567Y93403D01*
G02X815568Y93349I-198J-31D01*
G02X815560Y93314I-198J27D01*
G01X815523Y93203D01*
Y93201D01*
X815439Y92928D01*
X815410Y92902D01*
X815313Y92885D01*
G03X813568Y91437I410J-2270D01*
G01X813535Y91351D01*
G02X813466Y91322I-111J166D01*
G01X813272Y91281D01*
X813270D01*
X813129Y91251D01*
G02X813073Y91252I-24J199D01*
G01X812043Y92282D01*
G03X810411Y92958I-1632J-1632D01*
G03X808103Y90650I0J-2308D01*
G03X808779Y89018I2308J0D01*
G01X810719Y87078D01*
G03X812351Y86402I1632J1632D01*
G03X812435Y86404I-13J2308D01*
G01X827437D01*
G02X827443Y86395I-163J-115D01*
G01X827447Y86389D01*
X827567Y86191D01*
Y86189D01*
X827628Y86087D01*
G02X827647Y86040I-174J-98D01*
G02X827653Y85994I-194J-49D01*
G01X827654Y85948D01*
X827632Y85901D01*
X827630Y85897D01*
G03X827456Y85197I1328J-702D01*
G01Y85180D01*
G03X827862Y84166I1502J13D01*
G01X827889Y84138D01*
X827903Y84103D01*
G02X827913Y84067I-187J-71D01*
G02X827916Y84032I-197J-35D01*
G01Y83755D01*
G02X827906Y83691I-200J-1D01*
G02X827903Y83684I-185J75D01*
G01X827890Y83650D01*
X827862Y83620D01*
G03Y81566I1096J-1027D01*
G01X827890Y81536D01*
X827903Y81502D01*
G02X827906Y81495I-182J-82D01*
G02X827916Y81431I-190J-63D01*
G01Y81155D01*
G02X827906Y81091I-200J-1D01*
G02X827903Y81084I-185J75D01*
G01X827890Y81050D01*
X827862Y81020D01*
G03Y78966I1096J-1027D01*
G01X827890Y78936D01*
X827903Y78902D01*
G02X827906Y78895I-182J-82D01*
G02X827916Y78831I-190J-63D01*
G01Y78555D01*
G02X827906Y78491I-200J-1D01*
G02X827903Y78484I-185J75D01*
G01X827890Y78450D01*
X827862Y78420D01*
G03Y76366I1096J-1027D01*
G01X827890Y76336D01*
X827903Y76302D01*
G02X827906Y76295I-182J-82D01*
G02X827916Y76231I-190J-63D01*
G01Y75955D01*
G02X827906Y75891I-200J-1D01*
G02X827903Y75884I-185J75D01*
G01X827890Y75850D01*
X827862Y75820D01*
G03X827456Y74793I1096J-1027D01*
G03X830460I1502J0D01*
G03X830054Y75820I-1502J0D01*
G01X830026Y75850D01*
X830013Y75884D01*
G02X830010Y75891I182J82D01*
G02X830000Y75955I190J63D01*
G01Y76231D01*
G02X830010Y76295I200J1D01*
G02X830013Y76302I185J-75D01*
G01X830026Y76336D01*
X830054Y76366D01*
G03Y78420I-1096J1027D01*
G01X830026Y78450D01*
X830013Y78484D01*
G02X830010Y78491I182J82D01*
G02X830000Y78555I190J63D01*
G01Y78831D01*
G02X830010Y78895I200J1D01*
G02X830013Y78902I185J-75D01*
G01X830026Y78936D01*
X830054Y78966D01*
G03Y81020I-1096J1027D01*
G01X830026Y81050D01*
X830013Y81084D01*
G02X830010Y81091I182J82D01*
G02X830000Y81155I190J63D01*
G01Y81431D01*
G02X830010Y81495I200J1D01*
G02X830013Y81502I185J-75D01*
G01X830026Y81536D01*
X830054Y81566D01*
G03Y83620I-1096J1027D01*
G01X830026Y83650D01*
X830013Y83684D01*
G02X830010Y83691I182J82D01*
G02X830000Y83755I190J63D01*
G01Y84032D01*
G02X830003Y84067I200J0D01*
G02X830013Y84103I197J-35D01*
G01X830027Y84138D01*
X830056Y84168D01*
G03X830460Y85179I-1098J1025D01*
G01Y85195D01*
G03X830286Y85897I-1502J0D01*
G01X830280Y85908D01*
G02X830263Y85993I183J81D01*
G01X830264Y86046D01*
X830349Y86189D01*
Y86191D01*
X830469Y86388D01*
G02X830480Y86404I170J-105D01*
G01X847901D01*
G02X847922Y86403I1J-200D01*
G02X848043Y86345I-21J-199D01*
G01X849270Y85117D01*
G02X849328Y84976I-142J-141D01*
G01Y84913D01*
X849316Y84866D01*
X849305Y84845D01*
G03X849129Y84143I1326J-705D01*
G01Y84110D01*
G03X850631Y82638I1502J30D01*
G01X850632D01*
G03X850695Y82639I8J1502D01*
G01X850737Y82641D01*
X850773Y82627D01*
G02X850836Y82589I-70J-187D01*
G01X850890Y82538D01*
G02X850892Y82536I-140J-142D01*
G01X851057Y82377D01*
G02X851072Y82359I-146J-137D01*
G01Y76586D01*
G03X851863Y74849I2307J2D01*
G01X851905Y74812D01*
X851913Y74795D01*
G02X851931Y74717I-182J-83D01*
G01X851937Y74497D01*
Y74494D01*
X851939Y74437D01*
X851748Y74247D01*
G03X851248Y73498I1632J-1631D01*
G03X851072Y72622I2131J-884D01*
G01Y72615D01*
G03X853379Y70308I2307J0D01*
G01X853416D01*
G03X854262Y70484I-39J2307D01*
G03X855011Y70984I-882J2132D01*
G01X856313Y72287D01*
X857249Y73223D01*
G03X857924Y74853I-1631J1630D01*
G01Y84546D01*
G02X857979Y84596I160J-120D01*
G01X858002Y84610D01*
X858346Y84754D01*
G02X858455Y84767I77J-184D01*
G01X860775Y82447D01*
G02Y82387I-198J-30D01*
G01Y82384D01*
X860754Y82254D01*
X860723Y82059D01*
G02X860618Y81922I-196J41D01*
G01X860591Y81908D01*
G03X859795Y80581I708J-1327D01*
G03X861297Y79079I1502J0D01*
G03X862799Y80572I0J1502D01*
G01Y80582D01*
G03X862723Y81054I-1502J0D01*
G01X862717Y81072D01*
X862712Y81108D01*
Y81109D01*
X862706Y81147D01*
X862718Y81194D01*
G02X862744Y81251I193J-53D01*
G01X862765Y81281D01*
X862787Y81311D01*
G02X862888Y81384I162J-117D01*
G02X862949Y81394I62J-190D01*
G01X868996D01*
G03X870626Y82069I0J2306D01*
G01X871606Y83049D01*
X872972Y84414D01*
G03X873648Y86045I-1631J1632D01*
G01Y86102D01*
X873647Y86125D01*
G03X871341Y88352I-2305J-79D01*
G03X869710Y87677I-1J-2306D01*
G01X869479Y87446D01*
G02X869456Y87444I-29J198D01*
G01X869407D01*
G02X869277Y87492I0J200D01*
G01X869271Y87497D01*
G03X867787Y88038I-1484J-1765D01*
G01X867166D01*
G02X867130Y88073I120J160D01*
G01X867057Y88164D01*
X866927Y88325D01*
G02X866917Y88341I165J114D01*
G02X866902Y88377I176J95D01*
G01X866886Y88439D01*
X866896Y88484D01*
G03X866929Y88791I-1469J313D01*
G03Y88793I-1502J1D01*
G01Y88816D01*
G03X865603Y90293I-1502J-15D01*
G01X865547Y90299D01*
G03X865416Y90304I-123J-1498D01*
G01X865408D01*
G03X864496Y89980I20J-1502D01*
G03X864430Y89925I928J-1181D01*
G01X864424Y89920D01*
X864417Y89914D01*
X864385Y89893D01*
G02X864207Y89878I-104J170D01*
G01X864113Y89919D01*
X864111D01*
X863871Y90026D01*
G02X863863Y90030I85J181D01*
G01X863809Y90057D01*
X863790Y90088D01*
Y102007D01*
G02X863806Y102086I200J1D01*
G01X863822Y102123D01*
X863844Y102144D01*
X863931Y102171D01*
G03X864819Y102907I-452J1449D01*
G03X864942Y103214I-1339J715D01*
G01X864952Y103245D01*
X868645Y106938D01*
G03X869028Y107862I-923J924D01*
G01Y118803D01*
G03X868645Y119727I-1306J0D01*
G01X865064Y123307D01*
G02X865009Y123414I142J141D01*
G02X865006Y123448I197J35D01*
G01Y139376D01*
G02X865016Y139439I200J1D01*
G02X865064Y139517I190J-63D01*
G01X885224Y159676D01*
G03X885547Y160209I-924J924D01*
G03X885585Y160364I-1248J388D01*
G01Y160366D01*
X885588Y160379D01*
G02X885640Y160471I194J-49D01*
G01X886551Y161382D01*
G03X886901Y162162I-913J878D01*
G01Y162169D01*
G03X886904Y162258I-1263J87D01*
G01Y247763D01*
G02X886912Y247819I200J0D01*
G01X886923Y247854D01*
X886954Y247899D01*
X886967Y247918D01*
X887056Y248000D01*
X887185Y248119D01*
G02X887254Y248161I136J-146D01*
G01X887280Y248170D01*
X887288Y248171D01*
G03X887298Y248172I-15J199D01*
G03X887308Y248173I-145J1498D01*
G01X887333Y248171D01*
G03X887412Y248168I96J1499D01*
G01X887416D01*
X887438Y248167D01*
X887450D01*
G03X888715Y248868I-6J1503D01*
G01X888739Y248908D01*
X888757Y248940D01*
G03X888797Y249017I-1313J731D01*
G03X888821Y249069I-1352J655D01*
G01X888837Y249105D01*
X888906Y249174D01*
G02X888996Y249224I139J-144D01*
G01X889010Y249227D01*
X889125Y249250D01*
G02X889193Y249252I40J-196D01*
G01X889943Y248501D01*
X890314Y248130D01*
G02X890372Y247989I-142J-141D01*
G01Y245897D01*
G02X890362Y245834I-200J-1D01*
G01X890343Y245776D01*
G02X890316Y245724I-189J65D01*
G03X890076Y244969I1066J-755D01*
G01Y243948D01*
X890064Y243925D01*
X890053Y243903D01*
G03X889881Y243205I1331J-698D01*
G01Y243203D01*
G03X891383Y241701I1502J0D01*
G03X891489Y241705I-4J1502D01*
G01X891498D01*
X891531Y241707D01*
X891620Y241702D01*
G03X891679Y241701I55J1501D01*
G03X893181Y243203I0J1502D01*
G01Y243205D01*
G03X892986Y243944I-1503J-1D01*
G01X892974Y243965D01*
X892952Y244042D01*
G02X892946Y244090I194J49D01*
G01Y244945D01*
X892951Y244968D01*
G03X892972Y245074I-1270J307D01*
G01Y245076D01*
G03X892986Y245265I-1293J191D01*
G01Y247162D01*
G02X893091Y247337I200J-1D01*
G01X893111Y247345D01*
G02X893227Y247357I78J-184D01*
G01X893253Y247352D01*
X893305Y247324D01*
X894800Y245829D01*
G02X894842Y245609I-142J-141D01*
G01X894840Y245603D01*
G03X894728Y245076I1194J-529D01*
G01Y244099D01*
G02X894705Y244007I-200J1D01*
G01Y244006D01*
G03X894532Y243307I1329J-700D01*
G01Y243305D01*
G03X894740Y242544I1502J2D01*
G01X894751Y242524D01*
X894764Y242482D01*
X894773Y242450D01*
X894772Y242417D01*
G02X894762Y242363I-200J9D01*
G01X894758Y242354D01*
Y242353D01*
X894730Y242283D01*
X894708Y242258D01*
G03X894537Y241995I914J-781D01*
G01X894438Y241788D01*
G03X894418Y241701I180J-87D01*
G01Y239276D01*
G03X894433Y239201I200J1D01*
G01X894586Y238823D01*
G03X894632Y238755I185J76D01*
G01X894746Y238645D01*
G02X894775Y238607I-143J-139D01*
G02X894803Y238514I-172J-102D01*
G01X894804Y238506D01*
G02X894784Y238403I-200J-15D01*
G01X894781Y238398D01*
G02X894671Y238300I-179J90D01*
G01X894652Y238293D01*
G02X894526Y238289I-69J187D01*
G01X894481Y238302D01*
X894449Y238319D01*
X894416Y238337D01*
G03X894136Y238455I-837J-1596D01*
G03X894053Y238480I-561J-1713D01*
G01X894000Y238493D01*
G03X893930Y238509I-437J-1749D01*
G01X893922D01*
X893902Y238514D01*
X893885Y238517D01*
G03X893872Y238519I-280J-1779D01*
G01X893858D01*
X893843Y238521D01*
G03X893581Y238542I-275J-1781D01*
G01X893579D01*
G03X893451Y238537I6J-1802D01*
G01X893447D01*
G02X893436Y238536I-24J199D01*
G03X893284Y238542I-147J-1796D01*
G03X891482Y236740I0J-1802D01*
G01Y233340D01*
G03X893284Y231538I1802J0D01*
G03X893420Y231543I2J1802D01*
G01X893435Y231544D01*
G02X893447Y231543I-11J-200D01*
G01X893451D01*
X893458Y231542D01*
G03X893580Y231538I120J1798D01*
G03X895382Y233340I0J1802D01*
G01Y236743D01*
G03X895254Y237409I-1802J-1D01*
G01X895253Y237411D01*
X895241Y237442D01*
X895220Y237497D01*
G02X895208Y237564I188J68D01*
G02X895287Y237725I200J2D01*
G01X895384Y237793D01*
X895387Y237795D01*
X895391Y237798D01*
X895397Y237802D01*
G03X895427Y237828I-115J164D01*
G01X895506Y237913D01*
X895508Y237915D01*
X895526Y237934D01*
X895527Y237935D01*
X895548Y237957D01*
X895570Y237970D01*
G02X895620Y237991I102J-172D01*
G01X895653Y237998D01*
X895701Y237997D01*
X895725Y237991D01*
X895726D01*
G03X895800Y237986I50J194D01*
G01X895973Y238009D01*
X896022Y238014D01*
X896025D01*
G02X896076Y238017I55J-497D01*
G02X896378Y237916I0J-501D01*
G01X896387Y237909D01*
X896449Y237857D01*
X896457Y237850D01*
X896510Y237804D01*
X896518Y237796D01*
G02X896560Y237734I-142J-141D01*
G01X896578Y237687D01*
X896576Y237644D01*
Y237643D01*
G03X896575Y237538I1201J-64D01*
G01Y237516D01*
G02X896572Y237464I-499J3D01*
G01X896571Y237449D01*
X896547Y237229D01*
G03X896557Y237141I199J-22D01*
G01X896708Y236712D01*
G03X896755Y236637I189J66D01*
G01X903523Y229870D01*
G03X904373Y229516I852J848D01*
G01X904758D01*
G03X904806Y229518I-26J1202D01*
G01X904827D01*
G02X904947Y229478I0J-200D01*
G01X904971Y229460D01*
X905006Y229411D01*
X905016Y229384D01*
G03X906169Y227588I4344J1521D01*
G03X913684Y229328I3191J3317D01*
G01X913695Y229358D01*
X913712Y229381D01*
G02X913753Y229421I159J-122D01*
G01X913843Y229484D01*
G02X913890Y229507I111J-166D01*
G02X913929Y229516I64J-189D01*
G01X913931D01*
G02X913954Y229518I29J-198D01*
G01X914618D01*
G03X914657Y229516I81J1199D01*
G01X917752D01*
G03X918617Y229884I-1J1203D01*
G01X918962Y230244D01*
G03X919002Y230306I-145J137D01*
G01X919003Y230308D01*
X919011Y230326D01*
Y230329D01*
X919150Y230698D01*
G03X919162Y230777I-188J69D01*
G01X919153Y230977D01*
G02X919152Y230994I498J38D01*
G01Y231001D01*
G02X919312Y231366I500J-2D01*
G01X919314Y231368D01*
X919505Y231547D01*
G02X919522Y231561I135J-147D01*
G02X919764Y231559I120J-160D01*
G01X919965Y231390D01*
X919973Y231383D01*
G02X920152Y231001I-321J-383D01*
G01Y230977D01*
X920147Y230878D01*
Y230876D01*
X920143Y230794D01*
X920141Y230740D01*
X920298Y230315D01*
G03X920341Y230246I188J69D01*
G01X920685Y229888D01*
G03X921551Y229518I867J831D01*
G01X921764D01*
G03X921801Y229516I83J1199D01*
G01X936224D01*
G03X937069Y229864I-1J1203D01*
G01X937409Y230200D01*
G03X937453Y230265I-140J142D01*
G01X937515Y230412D01*
Y230414D01*
X937613Y230640D01*
X937617Y230652D01*
G03X937626Y230743I-189J65D01*
G01X937624Y230757D01*
X937625Y230873D01*
Y230898D01*
G02X938125Y231390I500J-8D01*
G01X938127D01*
G02X938243Y231377I3J-500D01*
G01X938247Y231376D01*
X938276Y231369D01*
X938493Y231314D01*
X938496Y231313D01*
X938510Y231310D01*
X938532Y231304D01*
X938541Y231302D01*
X938553Y231305D01*
X939093Y231458D01*
X939099Y231459D01*
X939150Y231474D01*
X939151D01*
X944440Y236764D01*
G03X944794Y237614I-848J852D01*
G01Y238297D01*
G02X944798Y238334I200J-3D01*
G01Y238336D01*
G02X944851Y238437I196J-39D01*
G01X944904Y238490D01*
X944933Y238505D01*
G03X944907Y241196I-685J1339D01*
G01X944906D01*
X944904Y241197D01*
G02X944824Y241270I90J179D01*
G01X944809Y241293D01*
X944801Y241321D01*
G02X944794Y241374I193J52D01*
G01Y254543D01*
G02X944817Y254636I200J0D01*
G02X944860Y254692I178J-92D01*
G01X944868Y254698D01*
G02X944925Y254731I127J-154D01*
G01X944928Y254732D01*
X944934Y254735D01*
X944935D01*
X945207Y254855D01*
X945209D01*
X945246Y254872D01*
G02X945430Y254860I80J-183D01*
G01X945469Y254830D01*
X945471Y254828D01*
G03X946481Y254438I1010J1112D01*
G01X946516D01*
G03X947984Y255940I-34J1502D01*
G03X946538Y257441I-1502J0D01*
G03X946483Y257442I-55J-1501D01*
G01X946447D01*
G03X945517Y257092I34J-1502D01*
G01X945516Y257091D01*
X945496Y257075D01*
G02X945412Y257040I-117J162D01*
G01X945309Y257030D01*
X945267Y257026D01*
G02X945182Y257037I-17J199D01*
G01X945180D01*
G02X945168Y257042I71J187D01*
G01X944919Y257152D01*
X944911Y257156D01*
X944910D01*
X944900Y257161D01*
G02X944795Y257319I94J176D01*
G02X944794Y257338I199J20D01*
G01Y267669D01*
G03X944449Y268510I-1203J-2D01*
G03X944439Y268520I-855J-845D01*
G01X937439Y275521D01*
G03X936593Y275870I-847J-854D01*
G01X921926D01*
G03X921883Y275868I34J-1202D01*
G01X921707D01*
X921698Y275869D01*
X921673D01*
G03X921242Y275789I0J-1202D01*
G03X920849Y275541I433J-1121D01*
G01X920509Y275219D01*
G03X920465Y275158I137J-145D01*
G01X920440Y275105D01*
X920398Y275015D01*
X920308Y274820D01*
X920305Y274814D01*
X920293Y274787D01*
X920290Y274755D01*
Y274751D01*
X920275Y274560D01*
X920274Y274550D01*
G02X919847Y274085I-499J30D01*
G01X919820Y274083D01*
X919809Y274082D01*
G02X919281Y274503I-35J498D01*
G01Y274506D01*
G02X919279Y274519I197J37D01*
G01X919261Y274754D01*
G03X919243Y274823I-200J-15D01*
G01X919165Y274989D01*
G03X919160Y274999I-1077J-532D01*
G01X919157Y275003D01*
X919110Y275104D01*
Y275106D01*
X919090Y275148D01*
X919089Y275151D01*
G03X919056Y275204I-184J-78D01*
G03X919041Y275219I-149J-134D01*
G03X919034Y275225I-134J-149D01*
G01X919030Y275229D01*
X918942Y275313D01*
X918939Y275317D01*
G03X918928Y275329I-892J-807D01*
G01X918910Y275346D01*
G03X918909Y275347I-851J-850D01*
G01X918706Y275539D01*
G03X917899Y275870I-829J-872D01*
G01X914457D01*
G03X914418Y275868I42J-1201D01*
G01X913998D01*
G02X913937Y275878I1J200D01*
G01X913908Y275887D01*
X913792Y275972D01*
G02X913766Y275996I122J158D01*
G01X913736Y276036D01*
X913725Y276067D01*
G03X905841Y277572I-4364J-1461D01*
G03X905038Y276188I3519J-2967D01*
G03X904977Y276009I4325J-1574D01*
G02X904787Y275870I-190J61D01*
G01X900818D01*
G03X900750Y275858I0J-200D01*
G01X900575Y275795D01*
G03X900077Y275445I420J-1127D01*
G03X900048Y275409I922J-772D01*
G01X899717Y274985D01*
X899714Y274982D01*
X899705Y274970D01*
X899686Y274945D01*
X899684Y274936D01*
X899680Y274919D01*
X899676Y274903D01*
G03X899675Y274894I198J-27D01*
G01X899673Y274885D01*
X899644Y274758D01*
X899575Y274453D01*
G03X899576Y274361I195J-44D01*
G01X899632Y274134D01*
Y274133D01*
G02X899646Y274016I-485J-117D01*
G01Y274015D01*
G02X898648I-499J0D01*
G02X898651Y274072I499J2D01*
G01X898653Y274091D01*
X898655Y274104D01*
G02X898661Y274134I493J-83D01*
G01X898701Y274299D01*
X898716Y274361D01*
G03X898717Y274451I-194J47D01*
G01X898700Y274529D01*
Y274531D01*
X898680Y274620D01*
X898618Y274901D01*
Y274903D01*
X898615Y274912D01*
X898608Y274945D01*
X898589Y274970D01*
X898564Y275003D01*
X898246Y275409D01*
G03X897290Y275869I-946J-742D01*
G01X897272D01*
X897265Y275868D01*
X897048D01*
G03X897000Y275862I1J-200D01*
G01X896987Y275858D01*
X896601Y275714D01*
X896574Y275690D01*
X896573Y275689D01*
X896554Y275672D01*
X896437Y275567D01*
G02X896428Y275560I-987J1260D01*
G01X896416Y275548D01*
X896401Y275538D01*
G02X895743Y275213I-1019J1234D01*
G01X895734Y275211D01*
X895686Y275199D01*
X895684D01*
X895582Y275173D01*
X895571Y275170D01*
X895566Y275167D01*
X895548Y275158D01*
X895313Y275028D01*
X895306Y275025D01*
G03X895298Y275021I86J-181D01*
G01X895291Y275016D01*
X895283Y275012D01*
X895268Y274997D01*
G03X895265Y274994I140J-143D01*
G01X894772Y274501D01*
G03X894530Y274154I849J-850D01*
G01X894516Y274123D01*
X894502Y274093D01*
X894483Y274038D01*
G02X894261Y273906I-189J65D01*
G01X894258Y273907D01*
G02X894140Y273974I34J197D01*
G01X894118Y274001D01*
X894106Y274032D01*
G02X894094Y274102I188J68D01*
G01Y274988D01*
G03X893724Y275883I-1267J0D01*
G01X893723Y275884D01*
X893662Y275946D01*
G02X893606Y276084I144J139D01*
G01Y278558D01*
G02X893614Y278615I200J1D01*
G02X893644Y278675I192J-58D01*
G01X893652Y278685D01*
G02X893662Y278697I158J-122D01*
G01X893856Y278890D01*
X893892Y278926D01*
G03X894334Y279991I-1065J1066D01*
G01Y286705D01*
G02X894381Y286834I200J0D01*
G01X894384Y286838D01*
X894496Y286860D01*
G03X895548Y287657I-289J1475D01*
G03X894521Y289806I-1340J679D01*
G01X894484Y289814D01*
X894457Y289831D01*
G02X894404Y289880I107J169D01*
G01X894374Y289921D01*
X894371Y289926D01*
G02X894334Y290041I163J116D01*
G01Y335586D01*
X894354Y335608D01*
G03X894944Y336286I-787J1280D01*
G03X894429Y338124I-1376J606D01*
G01X894420Y338130D01*
X894357Y338249D01*
G02X894334Y338343I177J93D01*
G01Y372672D01*
G02X894341Y372681I161J-118D01*
G01X895102Y373443D01*
G02X895247Y373498I138J-145D01*
G01X895293Y373495D01*
G02X895360Y373475I-23J-199D01*
G01X895399Y373455D01*
X895426Y373422D01*
G03X896591Y372867I1166J946D01*
G01X896592D01*
G03X898094Y374369I0J1502D01*
G01Y374374D01*
G03X898090Y374481I-1502J-3D01*
G03X898012Y374861I-1498J-110D01*
G01X898006Y374879D01*
X898000Y374914D01*
Y374986D01*
G02X898030Y375061I197J-35D01*
G01X898058Y375099D01*
X898059Y375100D01*
X898090Y375143D01*
G02X898120Y375172I153J-128D01*
G01X905722D01*
G03X906787Y375613I0J1506D01*
G01X906990Y375815D01*
X909268Y378093D01*
G02X909408Y378150I140J-143D01*
G01X914825D01*
G02X914838Y378122I-175J-98D01*
G01Y377940D01*
X914837Y377926D01*
X914836Y377922D01*
G03X914826Y377750I1494J-173D01*
G01Y377748D01*
G03X917834I1504J0D01*
G03Y377756I-1504J4D01*
G01Y377791D01*
X917849Y377827D01*
G02X917892Y377892I185J-76D01*
G01X918091Y378091D01*
G02X918139Y378126I140J-142D01*
G02X918216Y378149I95J-176D01*
G01X918226Y378150D01*
X920006D01*
G02X920021Y378149I-6J-200D01*
G02X920161Y378076I-15J-200D01*
G01X920206Y378011D01*
G02X920203Y377916I-196J-41D01*
G01X920201Y377909D01*
X920174Y377832D01*
X920154Y377806D01*
G03X919841Y376888I1190J-918D01*
G03X922845I1502J0D01*
G03X922532Y377806I-1503J0D01*
G01X922512Y377832D01*
X922485Y377908D01*
G02X922481Y378012I191J59D01*
G01X922528Y378078D01*
G02X922681Y378150I154J-128D01*
G01X928660D01*
G02X928687Y378148I-1J-200D01*
G02X928808Y378084I-27J-198D01*
G01X928860Y378010D01*
G02X928864Y377967I-196J-40D01*
G01Y377965D01*
G02X928851Y377896I-200J2D01*
G01X928822Y377818D01*
X928800Y377792D01*
G03X928445Y376822I1147J-970D01*
G01Y376775D01*
X928446Y376759D01*
Y376758D01*
X928447Y376750D01*
Y376742D01*
G03X928455Y376646I1500J77D01*
G01Y376644D01*
G03X929947Y375319I1492J178D01*
G03X931184Y375969I0J1502D01*
G01X931189Y375976D01*
G03X931445Y376709I-1242J845D01*
G01X931446Y376717D01*
G03X931448Y376759I-1499J92D01*
G01Y376775D01*
X931449Y376785D01*
Y376827D01*
G03X931089Y377796I-1502J-7D01*
G01Y377797D01*
X931056Y377837D01*
X931045Y377856D01*
G02X931023Y377971I177J93D01*
G01X931026Y378004D01*
X931040Y378035D01*
X931052Y378061D01*
X931088Y378103D01*
X931113Y378118D01*
G02X931221Y378150I108J-168D01*
G01X934118D01*
G03X935183Y378592I-1J1507D01*
G01X962550Y405959D01*
G02X962747Y406009I141J-142D01*
G01X962768Y406000D01*
G02X962858Y405927I-76J-185D01*
G01X962873Y405905D01*
X962890Y405848D01*
Y315523D01*
G02X962832Y315382I-200J0D01*
G01X961270Y313820D01*
X958098Y310647D01*
G02X957987Y310592I-140J143D01*
G02X957958Y310590I-28J198D01*
G01X944337D01*
G03X943415Y310208I1J-1306D01*
G01X939157Y305950D01*
G02X939107Y305914I-140J142D01*
G02X939016Y305892I-91J178D01*
G01X924477D01*
X924454Y305904D01*
X924432Y305915D01*
G03X923734Y306087I-698J-1331D01*
G01X923732D01*
G03Y303083I0J-1502D01*
G01X923734D01*
G03X924432Y303255I0J1503D01*
G01X924454Y303266D01*
X924477Y303278D01*
X928977D01*
G02X929004Y303254I-119J-161D01*
G01X929204Y303014D01*
G02X929231Y302972I-153J-128D01*
G02X929250Y302891I-181J-85D01*
G01Y302848D01*
X929247Y302831D01*
G03X929225Y302576I1480J-256D01*
G03Y302573I1502J-2D01*
G01Y302571D01*
G03X930727Y301069I1502J0D01*
G03X932229Y302561I0J1502D01*
G01Y302573D01*
G03X932204Y302845I-1502J-1D01*
G01X932196Y302889D01*
X932210Y302940D01*
G02X932242Y303003I191J-57D01*
G01X932450Y303254D01*
G02X932477Y303278I146J-137D01*
G01X939640D01*
G03X940564Y303661I0J1306D01*
G01X944823Y307921D01*
G02X944935Y307976I140J-143D01*
G02X944963Y307978I28J-198D01*
G01X958584D01*
G03X959506Y308360I-1J1306D01*
G01X963960Y312814D01*
G02X964157Y312864I141J-142D01*
G01X964178Y312855D01*
G02X964268Y312782I-76J-185D01*
G01X964283Y312760D01*
X964300Y312703D01*
Y166701D01*
G02X964278Y166610I-200J0D01*
G02X964242Y166560I-178J90D01*
G01X942911Y145229D01*
X942869Y145204D01*
X942846Y145197D01*
G03X941857Y144208I446J-1435D01*
G01X941850Y144185D01*
X941825Y144143D01*
X935940Y138258D01*
G03X935558Y137336I924J-923D01*
G01Y127683D01*
G02X935539Y127597I-200J-1D01*
G01X935525Y127568D01*
X935523Y127566D01*
X935406Y127471D01*
X935280Y127368D01*
X935249Y127344D01*
X935157Y127363D01*
X935156D01*
G03X934891Y127404I-485J-2255D01*
G03X934678Y127414I-215J-2297D01*
G01X934494D01*
Y127407D01*
G03X932372Y125109I184J-2299D01*
G01Y121166D01*
G02X932361Y121153I-158J123D01*
G01X932345Y121135D01*
X932040Y120946D01*
G02X931846Y120941I-102J172D01*
G01X931836Y120946D01*
X931803Y120962D01*
X931772Y120976D01*
G03X931144Y121113I-630J-1382D01*
G03X929625Y119594I0J-1519D01*
G03X930181Y118421I1515J0D01*
G01X930183Y118419D01*
X930205Y118400D01*
X930221Y118387D01*
X930235Y118371D01*
G02X930258Y118336I-155J-127D01*
G01X930284Y118280D01*
G02X930298Y118207I-186J-74D01*
G01Y117983D01*
G02X930280Y117900I-200J0D01*
G01X930267Y117873D01*
Y117871D01*
X930240Y117817D01*
G02X930207Y117772I-176J95D01*
G01X930188Y117753D01*
X930181Y117747D01*
G03X929642Y116594I964J-1153D01*
G03X931144Y115092I1502J0D01*
G03X932219Y115545I0J1502D01*
G01X932227Y115553D01*
G02X932270Y115583I135J-148D01*
G01X932375Y115630D01*
X932393Y115638D01*
X932439Y115635D01*
X932440D01*
X932452Y115634D01*
X932497Y115604D01*
G02X932567Y115520I-113J-165D01*
G01X932576Y115501D01*
G03X933047Y114819I2102J948D01*
G01X942647Y105219D01*
G02X942700Y105117I-143J-139D01*
G02X942704Y105079I-196J-40D01*
G01Y95111D01*
G03X947318I2307J0D01*
G01Y105213D01*
G02X947359Y105254I160J-119D01*
G01X948519D01*
X948529D01*
G02X948610Y105232I-11J-200D01*
G03X948703Y105182I773J1327D01*
G01X948726Y105171D01*
X948728Y105170D01*
X948763Y105140D01*
X948778Y105119D01*
G02X948732Y104840I-163J-116D01*
G01X948709Y104824D01*
X948685Y104815D01*
G03X947719Y103411I537J-1404D01*
G03X950723I1502J0D01*
G03X950144Y104596I-1502J0D01*
G01X950126Y104610D01*
X950089Y104655D01*
G02X950059Y104704I154J128D01*
G01Y104706D01*
G02X950043Y104793I184J79D01*
G01X950048Y104897D01*
Y104899D01*
X950059Y105081D01*
X950070Y105129D01*
X950094Y105173D01*
G02X950154Y105236I172J-103D01*
G01X950158Y105239D01*
X950164Y105242D01*
G03X950915Y106561I-783J1319D01*
G03X949380Y108096I-1535J0D01*
G01X949379D01*
G03X948617Y107894I0J-1537D01*
G01X948594Y107881D01*
X948570Y107875D01*
G02X948519Y107868I-52J193D01*
G01X948028D01*
G02X947887Y107926I0J200D01*
G01X941772Y114039D01*
X938189Y117623D01*
G02X938170Y117645I141J141D01*
G01Y136710D01*
G02X938172Y136740I200J2D01*
G02X938227Y136850I198J-30D01*
G01X941889Y140511D01*
X943673Y142295D01*
X943715Y142320D01*
X943738Y142327D01*
G03X944727Y143316I-446J1435D01*
G01X944734Y143339D01*
X944759Y143381D01*
X966531Y165153D01*
G03X966914Y166077I-923J924D01*
G01Y342698D01*
G02X967019Y342873I200J-1D01*
G01X967039Y342881D01*
G02X967155Y342893I78J-184D01*
G01X967181Y342888D01*
X967233Y342860D01*
X969730Y340362D01*
G03X971361Y339686I1632J1631D01*
G01X974512D01*
G03X975067Y339754I-1J2307D01*
G03X975220Y339798I-561J2237D01*
G01X975313Y339828D01*
G02X975387Y339784I-63J-190D01*
G01X975388Y339783D01*
X975461Y339713D01*
X975645Y339538D01*
G02X975695Y339453I-142J-141D01*
G01X975702Y339429D01*
X975703Y339375D01*
X975696Y339348D01*
G03X975648Y338972I1454J-377D01*
G03X978652I1502J0D01*
G03X977190Y340474I-1503J0D01*
G01X977189D01*
X977162Y340475D01*
X977121Y340487D01*
X977100Y340493D01*
X977067Y340511D01*
X977065Y340512D01*
G02X976975Y340604I90J178D01*
G01X976898Y340792D01*
Y340794D01*
X976839Y340938D01*
Y340939D01*
X976831Y340958D01*
X976825Y340972D01*
X976824Y340996D01*
X976839Y341034D01*
G02X976884Y341103I186J-72D01*
G01X977262Y341480D01*
G03X977938Y343111I-1631J1632D01*
G01Y343168D01*
X977937Y343191D01*
G03X977285Y344720I-2305J-79D01*
G01X977257Y344749D01*
X977243Y344784D01*
G02X977228Y344859I185J76D01*
G01Y344917D01*
G02X977231Y344949I200J-3D01*
G01X977251Y344969D01*
G03X977938Y346612I-1621J1643D01*
G03X977262Y348243I-2307J-1D01*
G01X972852Y352653D01*
G02X972816Y352703I142J140D01*
G02X972794Y352794I178J91D01*
G01Y402708D01*
G02X972798Y402746I200J-2D01*
G02X972851Y402848I196J-37D01*
G01X973352Y403349D01*
G03X974028Y404980I-1631J1632D01*
G01Y407762D01*
G03X972227Y410013I-2307J0D01*
G01X972225D01*
X972131Y410035D01*
G02X972094Y410097I150J132D01*
G01X972068Y410186D01*
Y410188D01*
X972000Y410427D01*
G03X971999Y410430I-190J-62D01*
G01X971989Y410456D01*
X971985Y410511D01*
X971991Y410540D01*
G02X972045Y410641I196J-40D01*
G01X1007938Y446534D01*
G02X1008135Y446584I141J-142D01*
G01X1008156Y446575D01*
G02X1008246Y446502I-76J-185D01*
G01X1008261Y446480D01*
X1008278Y446423D01*
Y437227D01*
G03X1008661Y436303I1306J0D01*
G01X1059237Y385727D01*
G03X1060161Y385344I924J923D01*
G01X1062361D01*
G02X1062401Y385340I0J-200D01*
G02X1062501Y385287I-40J-196D01*
G01X1092407Y355382D01*
G02X1092405Y355310I-198J-31D01*
G01X1092401Y355292D01*
X1092396Y355275D01*
X1092395Y355272D01*
X1092367Y355168D01*
X1092312Y354964D01*
X1092298Y354928D01*
G02X1092263Y354879I-178J90D01*
G01X1092245Y354860D01*
X1092221Y354846D01*
G02X1092177Y354827I-101J173D01*
G01X1092146Y354818D01*
X1092141Y354817D01*
G03X1091860Y354704I417J-1444D01*
G01X1091838Y354692D01*
X1091791Y354680D01*
X1090981D01*
G03X1090059Y354298I1J-1306D01*
G01X1084695Y348934D01*
G02X1084644Y348933I-29J198D01*
G01X1084555Y348949D01*
X1084553D01*
X1084356Y348986D01*
X1084313Y348994D01*
X1084273Y349022D01*
G02X1084265Y349028I116J163D01*
G01X1084196Y349082D01*
G02X1084164Y349113I122J158D01*
G01X1084152Y349128D01*
X1084141Y349151D01*
G03X1082787Y350003I-1354J-650D01*
G01X1082784D01*
G03X1082077Y349826I1J-1504D01*
G01X1082064Y349820D01*
X1082041Y349808D01*
X1078189D01*
G03X1077265Y349425I0J-1306D01*
G01X1056903Y329063D01*
G03X1056520Y328139I923J-924D01*
G01Y308321D01*
G02X1056498Y308230I-200J0D01*
G02X1056462Y308180I-178J90D01*
G01X1051846Y303564D01*
G02X1051815Y303562I-28J198D01*
G01X1051676Y303570D01*
X1051674D01*
X1051537Y303579D01*
X1051503Y303581D01*
X1051473Y303593D01*
G02X1051418Y303628I79J184D01*
G01X1051379Y303662D01*
X1051365Y303679D01*
G03X1051332Y303722I-1222J-904D01*
G01X1051330Y303724D01*
X1051325Y303730D01*
G03X1051230Y303833I-1164J-979D01*
G03X1051173Y303886I-1064J-1087D01*
G01X1051150Y303909D01*
G02X1051094Y304027I143J140D01*
G01X1051087Y304212D01*
X1051083Y304309D01*
G02X1051129Y304439I200J2D01*
G01X1051136Y304447D01*
G02X1051141Y304452I144J-139D01*
G01X1051145Y304456D01*
G03X1051493Y305014I-1070J1055D01*
G03X1051578Y305473I-1417J500D01*
G01Y305513D01*
G03Y305528I-1502J7D01*
G01Y305536D01*
G03X1051577Y305576I-1502J-18D01*
G01X1051576Y305595D01*
G03X1050076Y307014I-1500J-83D01*
G03X1048584Y305688I0J-1502D01*
G01X1048578Y305631D01*
G03X1048573Y305512I1498J-123D01*
G01Y305429D01*
X1048577Y305394D01*
X1048578Y305390D01*
X1048579Y305375D01*
G03X1049079Y304386I1497J136D01*
G01X1049097Y304370D01*
X1049111Y304350D01*
G02X1049147Y304243I-164J-115D01*
G01X1049154Y304052D01*
Y304050D01*
X1049156Y303979D01*
Y303964D01*
G02X1049149Y303921I-200J10D01*
G01X1049145Y303909D01*
G02X1049127Y303869I-190J62D01*
G01X1049119Y303857D01*
G02X1049097Y303831I-163J116D01*
G01X1049096Y303830D01*
G03X1048643Y302748I1066J-1082D01*
G03X1049238Y301542I1520J0D01*
G01X1049250Y301533D01*
X1049275Y301508D01*
G02X1049327Y301418I-141J-142D01*
G02X1049333Y301381I-194J-50D01*
G01X1049343Y301238D01*
X1049351Y301128D01*
Y301095D01*
G02X1049349Y301067I-200J0D01*
G01X1018331Y270049D01*
G03X1018145Y269815I923J-925D01*
G01X1018133Y269795D01*
X1016271Y267933D01*
G03X1015900Y267037I896J-896D01*
G01Y267019D01*
G02X1015700Y266819I-200J0D01*
G01X1015671D01*
X1015626Y266833D01*
X1015611Y266840D01*
G03X1014420Y267416I-1191J-943D01*
G03X1014198Y267400I-2J-1519D01*
G01X1014080Y267415D01*
X1013974Y267354D01*
G02X1013937Y267337I-101J172D01*
G03X1013416Y267037I482J-1440D01*
G02X1013361Y267029I-56J192D01*
G01X1013294D01*
G03X1013183Y266995I1J-200D01*
G01X1013149Y266974D01*
X1013096Y266968D01*
G02X1013019Y266978I-13J200D01*
G01X1012929Y267010D01*
X1012901Y267034D01*
G03X1011920Y267399I-981J-1136D01*
G03Y264395I0J-1502D01*
G01X1011923D01*
G03X1012815Y264690I-2J1502D01*
G03X1012864Y264728I-896J1206D01*
G02X1012866Y264730I140J-138D01*
G01X1012885Y264741D01*
G02X1012979Y264765I95J-176D01*
G01X1013046D01*
G03X1013157Y264799I-1J200D01*
G01X1013191Y264820D01*
X1013244Y264826D01*
G02X1013317Y264818I15J-200D01*
G01X1013334Y264812D01*
G02X1013398Y264772I-72J-186D01*
G03X1014420Y264378I1021J1126D01*
G01X1014421D01*
G03X1015612Y264954I0J1520D01*
G01X1015633Y264964D01*
X1015673Y264975D01*
X1015700D01*
G02X1015900Y264775I0J-200D01*
G01Y264586D01*
G02X1015892Y264530I-200J0D01*
G02X1015886Y264512I-193J54D01*
G01X1015871Y264476D01*
X1015841Y264446D01*
X1014579Y263183D01*
X1013336Y261940D01*
G02X1013291Y261907I-140J143D01*
G02X1013246Y261890I-93J177D01*
G02X1013198Y261884I-49J194D01*
G01X999254D01*
G03X998830Y261813I-6J-1267D01*
G01X998829Y261812D01*
X998826Y261811D01*
X998819Y261808D01*
X998816Y261807D01*
X998807Y261803D01*
G03X998736Y261774I443J-1186D01*
G01X998360Y261512D01*
G03X998333Y261489I116J-163D01*
G01X996444Y259599D01*
X996429Y259590D01*
X996423Y259586D01*
G03X996193Y259405I688J-1111D01*
G03X996189Y259401I922J-926D01*
G01X994558Y257770D01*
X994516Y257745D01*
X994493Y257738D01*
G03X993442Y256174I446J-1435D01*
G01X993443Y256166D01*
Y256163D01*
X993448Y256114D01*
X993437Y256069D01*
G02X993397Y255996I-191J57D01*
G01X993223Y255800D01*
X993193Y255766D01*
G02X993114Y255716I-144J139D01*
G01X993072Y255704D01*
X991005D01*
G02X990949Y255712I0J200D01*
G02X990931Y255718I54J193D01*
G01X990895Y255733D01*
X986852Y259776D01*
G03X986388Y260071I-895J-896D01*
G01X986383D01*
X986318Y260096D01*
X986310Y260099D01*
X986296Y260103D01*
G03X986272Y260108I-53J-194D01*
G01X986269D01*
X986251Y260111D01*
X986246Y260112D01*
X986243Y260113D01*
X986241D01*
G03X986093Y260139I-293J-1232D01*
G01X986092D01*
X986082Y260140D01*
G03X985956Y260146I-123J-1260D01*
G01X973049D01*
X972997Y260153D01*
X972955Y260164D01*
X972910Y260183D01*
X972900Y260189D01*
G03X972162Y260382I-737J-1311D01*
G01X972160D01*
G03X970658Y258880I0J-1502D01*
G01X970657D01*
G03X971714Y257445I1503J0D01*
G01X971715D01*
G02X971797Y257395I-60J-191D01*
G01X972197Y256995D01*
G03X973121Y256612I924J923D01*
G01X984546D01*
G02X984584Y256608I-2J-200D01*
G02X984686Y256555I-37J-196D01*
G01X988057Y253184D01*
G03X988979Y252802I923J924D01*
G01X990160D01*
G02X990185Y252800I-3J-200D01*
G02X990302Y252743I-24J-198D01*
G01X992113Y250931D01*
X992116Y250927D01*
G03X992686Y250584I916J877D01*
G01X992697Y250582D01*
X992708Y250579D01*
G03X993030Y250536I327J1225D01*
G01X1001450D01*
G02X1001556Y250503I-4J-200D01*
G01X1001583Y250484D01*
G02X1001601Y250468I-124J-157D01*
G02X1001652Y250379I-142J-141D01*
G01X1001666Y250328D01*
X1001683Y250287D01*
X1001701Y250240D01*
G03X1001738Y250180I186J74D01*
G01X1001742Y250175D01*
G02X1001787Y250077I-152J-129D01*
G01X1001791Y250050D01*
X1001788Y250023D01*
G02X1001772Y249967I-198J26D01*
G01X1001738Y249891D01*
Y249889D01*
X1001720Y249848D01*
X1001694Y249821D01*
G03X1001693Y249820I1062J-1063D01*
G03X1001691Y249818I140J-142D01*
G03X1001261Y248773I1072J-1052D01*
G01Y248741D01*
G03X1002707Y247264I1502J24D01*
G01X1002708D01*
G03X1002763Y247263I55J1501D01*
G01X1002765D01*
G03X1003699Y247590I-1J1501D01*
G01X1003725Y247610D01*
X1003769Y247625D01*
G02X1003822Y247633I56J-192D01*
G01X1003908D01*
G03X1003964Y247641I0J200D01*
G01X1003978Y247644D01*
X1004190D01*
G02X1004315Y247600I0J-200D01*
G01X1004316Y247599D01*
G03X1004319Y247597I835J1249D01*
G03X1004337Y247583I931J1178D01*
G02X1004347Y247575I-120J-160D01*
G03X1004350Y247572I1062J1059D01*
G03X1004437Y247510I915J1192D01*
G01X1004441Y247508D01*
X1004472Y247487D01*
X1004486Y247479D01*
G03X1004760Y247349I777J1285D01*
G03X1004763Y247348I64J186D01*
G01X1004778Y247343D01*
G03X1005183Y247265I484J1422D01*
G03X1005260Y247263I77J1499D01*
G01X1005263D01*
G03X1005326Y247264I8J1502D01*
G01X1005343Y247265D01*
G03X1006197Y247589I-81J1500D01*
G01X1006198Y247590D01*
X1006210Y247600D01*
G02X1006316Y247633I110J-167D01*
G01X1006408D01*
G03X1006491Y247651I0J200D01*
G01X1006545Y247676D01*
G02X1006623Y247695I85J-181D01*
G02X1006657Y247693I5J-200D01*
G02X1006761Y247645I-28J-198D01*
G01X1006762Y247644D01*
G03X1007761Y247263I1000J1122D01*
G01X1007763D01*
G03X1009265Y248765I0J1502D01*
G03X1008832Y249820I-1502J0D01*
G01X1008831Y249821D01*
X1008807Y249846D01*
X1008791Y249880D01*
X1008776Y249912D01*
G02X1008768Y249936I185J75D01*
G01X1008756Y249992D01*
G02X1008763Y250089I198J34D01*
G01X1008838Y250273D01*
Y250275D01*
X1008899Y250421D01*
G02X1008926Y250464I182J-84D01*
G02X1009080Y250536I154J-128D01*
G01X1013784D01*
G02X1013898Y250482I-24J-198D01*
G01X1014202Y250178D01*
G02X1014220Y250157I-142J-140D01*
G01Y229061D01*
G02X1014198Y228970I-200J0D01*
G02X1014162Y228920I-178J90D01*
G01X1012894Y227652D01*
G03X1012609Y227215I896J-896D01*
G01X1012605Y227204D01*
G02X1012582Y227167I-180J86D01*
G03X1012581Y227165I176J-89D01*
G03X1012320Y226392I1046J-784D01*
G01Y222748D01*
G02X1012240Y222685I-160J120D01*
G01X1011876Y222552D01*
G02X1011756Y222546I-70J187D01*
G01X1011727Y222554D01*
X1011675Y222587D01*
X1011655Y222611D01*
G03X1010506Y223144I-1149J-972D01*
G03Y220140I0J-1502D01*
G03X1011633Y220648I0J1504D01*
G01X1011656Y220674D01*
X1011718Y220715D01*
G02X1011875Y220733I99J-174D01*
G01X1012098Y220652D01*
X1012229Y220604D01*
G02X1012320Y220536I-69J-188D01*
G01Y215280D01*
G03X1012703Y214356I1306J0D01*
G01X1012858Y214201D01*
X1012865Y214175D01*
X1012852Y214124D01*
X1012816Y213982D01*
X1012810Y213971D01*
X1012803Y213960D01*
X1012785Y213928D01*
X1012731Y213881D01*
X1012724Y213878D01*
X1012720Y213877D01*
X1012695Y213868D01*
G03X1011703Y212455I510J-1413D01*
G03X1013205Y210953I1502J0D01*
G03X1014540Y211764I0J1504D01*
G01X1014541Y211766D01*
X1014547Y211777D01*
G02X1014591Y211828I171J-103D01*
G01X1014704Y211914D01*
X1014753Y211922D01*
X1015024Y211970D01*
G02X1015088Y211971I35J-197D01*
G01X1019119Y207940D01*
G03X1020041Y207558I923J924D01*
G01X1020976D01*
X1021021Y207546D01*
X1021044Y207534D01*
G03X1023199Y208487I700J1329D01*
G01X1023206Y208514D01*
X1023222Y208541D01*
G02X1023251Y208579I172J-101D01*
G01X1025825Y211152D01*
G03X1026196Y212048I-896J896D01*
G01Y216192D01*
G02X1026251Y216329I200J-1D01*
G01X1026260Y216338D01*
X1026482Y216539D01*
G02X1026511Y216561I135J-148D01*
G02X1026616Y216591I105J-170D01*
G01X1026635D01*
X1026644Y216590D01*
G03X1026790Y216583I145J1495D01*
G03X1026792I1J1502D01*
G01X1026820D01*
G03X1027873Y217040I-26J1502D01*
G01X1027901Y217069D01*
X1028016Y217119D01*
G02X1028084Y217133I74J-186D01*
G01X1028299D01*
X1028338Y217126D01*
X1028376Y217118D01*
X1028487Y217069D01*
X1028514Y217041D01*
G03X1029594Y216583I1080J1044D01*
G03Y219587I0J1502D01*
G03X1028515Y219130I0J-1502D01*
G01X1028487Y219101D01*
X1028372Y219051D01*
G02X1028304Y219037I-74J186D01*
G01X1028111D01*
G02X1028071Y219041I0J200D01*
G01X1028028Y219050D01*
X1028006Y219054D01*
X1027901Y219101D01*
X1027874Y219130D01*
G03X1027392Y219463I-1079J-1046D01*
G01X1027361Y219477D01*
X1027338Y219497D01*
G02X1027304Y219537I134J149D01*
G01X1027253Y219626D01*
Y219627D01*
X1027242Y219646D01*
G02X1027216Y219763I173J100D01*
G01X1027217Y219781D01*
G03X1027220Y219875I-1265J87D01*
G01Y272770D01*
G02X1027222Y272797I200J-1D01*
G01X1036438Y282013D01*
G02X1036452Y282026I143J-140D01*
G02X1036706I127J-155D01*
G01X1036722Y282010D01*
G02X1036771Y281930I-141J-142D01*
G01X1036784Y281889D01*
X1036781Y281873D01*
X1036776Y281840D01*
G03X1036760Y281639I1291J-204D01*
G01Y276833D01*
G03X1037143Y275909I1306J0D01*
G01X1053774Y259279D01*
G02X1053823Y259197I-142J-141D01*
G02X1053832Y259138I-191J-59D01*
G01Y249622D01*
G02X1053830Y249594I-200J0D01*
G02X1053775Y249482I-198J28D01*
G01X1051270Y246978D01*
X1050056Y245764D01*
X1050014Y245739D01*
X1049992Y245732D01*
G03X1049976Y245727I440J-1436D01*
G03X1049827Y245670I462J-1430D01*
G03X1049713Y245613I614J-1371D01*
G01X1049711D01*
G03X1049692Y245601I792J-1275D01*
G01X1049690D01*
G03X1049577Y245529I750J-1302D01*
G01X1049559Y245517D01*
G02X1049346Y245524I-101J173D01*
G01Y245525D01*
G02X1049261Y245652I111J166D01*
G01X1049257Y245686D01*
G02X1049261Y245751I199J20D01*
G01X1049267Y245777D01*
X1049292Y245823D01*
X1049310Y245842D01*
G03X1049719Y246872I-1093J1030D01*
G01Y246910D01*
X1049718Y246939D01*
G03X1048217Y248376I-1501J-65D01*
G03Y245372I0J-1502D01*
G01X1048220D01*
G03X1048569Y245413I0J1502D01*
G01X1048574Y245415D01*
X1048599Y245419D01*
X1048627Y245421D01*
G02X1048774Y245363I6J-200D01*
G01X1048785Y245352D01*
X1049001Y245103D01*
G02X1049050Y244972I-151J-131D01*
G01Y244917D01*
X1049036Y244843D01*
X1049030Y244827D01*
G03X1048934Y244299I1407J-529D01*
G01Y244297D01*
G03X1048935Y244249I1503J7D01*
G01X1048937Y244223D01*
Y244219D01*
G03X1049341Y243270I1500J78D01*
G03X1050378Y242796I1096J1027D01*
G03X1050424Y242795I56J1501D01*
G01X1050443D01*
G03X1051143Y242967I2J1503D01*
G02X1051236Y242990I93J-177D01*
G01X1051817D01*
G02X1051957Y242933I0J-200D01*
G01X1052617Y242273D01*
X1053953Y240938D01*
G02X1054012Y240799I-141J-142D01*
G01Y231656D01*
G02X1053953Y231603I-160J119D01*
G01X1053833Y231533D01*
X1053658Y231431D01*
G02X1053520Y231412I-95J176D01*
G01X1053457Y231427D01*
X1053435Y231439D01*
G03X1052722Y231619I-713J-1322D01*
G01X1052720D01*
G03Y228615I0J-1502D01*
G01X1052723D01*
G03X1053445Y228800I0J1503D01*
G03X1053452Y228804I-96J176D01*
G01X1053489Y228826D01*
X1053531Y228831D01*
X1053533D01*
G02X1053610Y228825I23J-199D01*
G01X1053642Y228815D01*
X1053668Y228798D01*
X1053953Y228631D01*
G02X1054012Y228578I-101J-172D01*
G01Y216099D01*
G02X1053899Y215919I-200J0D01*
G01X1053887Y215914D01*
G02X1053769Y215903I-77J185D01*
G01X1053743Y215908D01*
X1053693Y215935D01*
X1040601Y229027D01*
X1040576Y229069D01*
X1040569Y229092D01*
G03X1039134Y230148I-1435J-447D01*
G03X1037632Y228646I0J-1502D01*
G01X1037631D01*
G03X1038688Y227211I1503J0D01*
G01X1038689D01*
G02X1038771Y227161I-60J-191D01*
G01X1052544Y213389D01*
G02X1052594Y213304I-142J-141D01*
G02X1052602Y213248I-192J-56D01*
G01Y181780D01*
G02X1052580Y181689I-200J0D01*
G02X1052544Y181639I-178J90D01*
G01X1029639Y158734D01*
G02X1029589Y158698I-140J142D01*
G02X1029498Y158676I-91J178D01*
G01X1018374D01*
X1018357Y158685D01*
G03X1017631Y158872I-726J-1317D01*
G01X1017629D01*
G03Y155868I0J-1502D01*
G01X1017630D01*
G03X1018361Y156058I-1J1504D01*
G01X1018372Y156064D01*
X1028480D01*
G02X1028665Y155940I0J-200D01*
G01X1028671Y155927D01*
X1028677Y155912D01*
X1028683Y155853D01*
X1028677Y155825D01*
G02X1028623Y155724I-196J40D01*
G01X1015511Y142612D01*
G02X1015461Y142576I-140J142D01*
G02X1015370Y142554I-91J178D01*
G01X1011569D01*
G02X1011534Y142586I117J163D01*
G01X1011406Y142763D01*
X1011341Y142854D01*
G02X1011308Y142960I167J110D01*
G01Y143039D01*
X1011317Y143069D01*
G03X1011386Y143518I-1433J450D01*
G03X1009884Y145020I-1502J0D01*
G03X1008382Y143529I0J-1502D01*
G01Y143515D01*
G03X1008451Y143066I1502J1D01*
G01X1008454Y143056D01*
X1008460Y143037D01*
X1008466Y142986D01*
G02X1008435Y142864I-199J-14D01*
G01X1008360Y142759D01*
X1008238Y142590D01*
G02X1008201Y142554I-157J124D01*
G01X1006143D01*
X1006120Y142566D01*
X1006107Y142572D01*
G03X1005400Y142749I-708J-1327D01*
G01X1005397D01*
G03Y139745I0J-1502D01*
G01X1005400D01*
G03X1006107Y139922I-1J1504D01*
G01X1006120Y139928D01*
X1006143Y139940D01*
X1014353D01*
G02X1014528Y139835I-1J-200D01*
G01X1014536Y139815D01*
G02X1014548Y139699I-184J-78D01*
G01X1014543Y139673D01*
X1014515Y139621D01*
X1005316Y130422D01*
G03X1004934Y129500I924J-923D01*
G01Y116632D01*
G03X1005316Y115710I1306J1D01*
G01X1007296Y113730D01*
G02X1007346Y113533I-142J-141D01*
G01X1007337Y113512D01*
G02X1007264Y113422I-185J76D01*
G01X1007242Y113407D01*
X1007185Y113390D01*
X997140D01*
G03X996216Y113007I0J-1306D01*
G01X992185Y108975D01*
G02X992073Y108920I-140J143D01*
G02X992045Y108918I-28J198D01*
G01X987927D01*
G03X987005Y108536I1J-1306D01*
G01X983256Y104786D01*
G02X983000Y104766I-140J143D01*
G02X982832Y105091I232J326D01*
G01Y107649D01*
G03X979226I-1803J0D01*
G01Y104249D01*
G03X980420Y102551I1804J0D01*
G01X980461Y102536D01*
X980521Y102478D01*
X980534Y102463D01*
G02X980571Y102394I-155J-127D01*
G01X980582Y102345D01*
Y102343D01*
X980646Y102061D01*
G02X980624Y101931I-197J-33D01*
G01X980604Y101900D01*
X979048Y100344D01*
G02X979028Y100327I-139J144D01*
G01X978861Y100209D01*
X978429Y99905D01*
G02X978314Y99868I-116J163D01*
G01X972067D01*
X972054D01*
G02X971927Y99925I13J200D01*
G01X971636Y100217D01*
X971511Y100342D01*
X971486Y100384D01*
X971479Y100407D01*
G03X970044Y101463I-1435J-447D01*
G03X968542Y99961I0J-1502D01*
G01X968541D01*
G03X969598Y98526I1503J0D01*
G01X969599D01*
G02X969681Y98476I-60J-191D01*
G01X969848Y98309D01*
G02Y98252I-198J-29D01*
G01X968463Y96867D01*
G03X967820Y95624I1631J-1631D01*
G01X967804Y95527D01*
G02X967731Y95482I-139J144D01*
G01X967467Y95398D01*
X967465D01*
X967417Y95383D01*
G02X967383Y95376I-57J192D01*
G02X967357Y95374I-28J198D01*
G01X967335D01*
X967299Y95389D01*
G02X967234Y95432I76J185D01*
G01X966506Y96160D01*
G03X965584Y96542I-923J-924D01*
G01X960906D01*
X960889Y96551D01*
G03X960163Y96738I-726J-1317D01*
G01X960161D01*
G03Y93734I0J-1502D01*
G01X960162D01*
G03X960893Y93924I-1J1504D01*
G01X960904Y93930D01*
X964958D01*
X964971D01*
G02X965098Y93873I-13J-200D01*
G01X965413Y93557D01*
X965567Y93403D01*
G02X965568Y93349I-198J-31D01*
G02X965560Y93314I-198J27D01*
G01X965523Y93203D01*
Y93201D01*
X965439Y92928D01*
X965410Y92902D01*
X965313Y92885D01*
G03X963568Y91437I410J-2270D01*
G01X963535Y91351D01*
G02X963466Y91322I-111J166D01*
G01X963272Y91281D01*
X963270D01*
X963129Y91251D01*
G02X963073Y91252I-24J199D01*
G01X962043Y92282D01*
G03X960411Y92958I-1632J-1632D01*
G03X958103Y90650I0J-2308D01*
G03X958779Y89018I2308J0D01*
G01X960719Y87078D01*
G03X962351Y86402I1632J1632D01*
G03X962435Y86404I-13J2308D01*
G01X977437D01*
G02X977443Y86395I-163J-115D01*
G01X977447Y86389D01*
X977567Y86191D01*
Y86189D01*
X977628Y86087D01*
G02X977647Y86040I-174J-98D01*
G02X977653Y85994I-194J-49D01*
G01X977654Y85948D01*
X977632Y85901D01*
X977630Y85897D01*
G03X977456Y85197I1328J-702D01*
G01Y85180D01*
G03X977862Y84166I1502J13D01*
G01X977889Y84138D01*
X977903Y84103D01*
G02X977913Y84067I-187J-71D01*
G02X977916Y84032I-197J-35D01*
G01Y83755D01*
G02X977906Y83691I-200J-1D01*
G02X977903Y83684I-185J75D01*
G01X977890Y83650D01*
X977862Y83620D01*
G03Y81566I1096J-1027D01*
G01X977890Y81536D01*
X977903Y81502D01*
G02X977906Y81495I-182J-82D01*
G02X977916Y81431I-190J-63D01*
G01Y81155D01*
G02X977906Y81091I-200J-1D01*
G02X977903Y81084I-185J75D01*
G01X977890Y81050D01*
X977862Y81020D01*
G03Y78966I1096J-1027D01*
G01X977890Y78936D01*
X977903Y78902D01*
G02X977906Y78895I-182J-82D01*
G02X977916Y78831I-190J-63D01*
G01Y78555D01*
G02X977906Y78491I-200J-1D01*
G02X977903Y78484I-185J75D01*
G01X977890Y78450D01*
X977862Y78420D01*
G03Y76366I1096J-1027D01*
G01X977890Y76336D01*
X977903Y76302D01*
G02X977906Y76295I-182J-82D01*
G02X977916Y76231I-190J-63D01*
G01Y75955D01*
G02X977906Y75891I-200J-1D01*
G02X977903Y75884I-185J75D01*
G01X977890Y75850D01*
X977862Y75820D01*
G03X977456Y74793I1096J-1027D01*
G03X980460I1502J0D01*
G03X980054Y75820I-1502J0D01*
G01X980026Y75850D01*
X980013Y75884D01*
G02X980010Y75891I182J82D01*
G02X980000Y75955I190J63D01*
G01Y76231D01*
G02X980010Y76295I200J1D01*
G02X980013Y76302I185J-75D01*
G01X980026Y76336D01*
X980054Y76366D01*
G03Y78420I-1096J1027D01*
G01X980026Y78450D01*
X980013Y78484D01*
G02X980010Y78491I182J82D01*
G02X980000Y78555I190J63D01*
G01Y78831D01*
G02X980010Y78895I200J1D01*
G02X980013Y78902I185J-75D01*
G01X980026Y78936D01*
X980054Y78966D01*
G03Y81020I-1096J1027D01*
G01X980026Y81050D01*
X980013Y81084D01*
G02X980010Y81091I182J82D01*
G02X980000Y81155I190J63D01*
G01Y81431D01*
G02X980010Y81495I200J1D01*
G02X980013Y81502I185J-75D01*
G01X980026Y81536D01*
X980054Y81566D01*
G03Y83620I-1096J1027D01*
G01X980026Y83650D01*
X980013Y83684D01*
G02X980010Y83691I182J82D01*
G02X980000Y83755I190J63D01*
G01Y84032D01*
G02X980003Y84067I200J0D01*
G02X980013Y84103I197J-35D01*
G01X980027Y84138D01*
X980056Y84168D01*
G03X980460Y85179I-1098J1025D01*
G01Y85195D01*
G03X980286Y85897I-1502J0D01*
G01X980280Y85908D01*
G02X980263Y85993I183J81D01*
G01X980264Y86046D01*
X980349Y86189D01*
Y86191D01*
X980469Y86388D01*
G02X980480Y86404I170J-105D01*
G01X997845D01*
G02X997959Y86369I1J-200D01*
G02X997975Y86356I-118J-162D01*
G01X999326Y85005D01*
G02X999328Y84976I-198J-28D01*
G01Y84913D01*
X999316Y84867D01*
X999299Y84834D01*
G03X999129Y84143I1332J-694D01*
G01Y84110D01*
G03X1000631Y82638I1502J30D01*
G01X1000632D01*
G03X1000695Y82639I8J1502D01*
G01X1000737Y82641D01*
X1000773Y82627D01*
G02X1000836Y82589I-70J-187D01*
G01X1000890Y82538D01*
G02X1000892Y82536I-140J-142D01*
G01X1001057Y82377D01*
G02X1001072Y82359I-146J-137D01*
G01Y76586D01*
G03X1001863Y74849I2307J2D01*
G01X1001905Y74812D01*
X1001913Y74795D01*
G02X1001931Y74717I-182J-83D01*
G01X1001937Y74497D01*
Y74494D01*
X1001939Y74437D01*
X1001748Y74247D01*
G03X1001248Y73498I1632J-1631D01*
G03X1001072Y72622I2131J-884D01*
G01Y72615D01*
G03X1003379Y70308I2307J0D01*
G01X1003416D01*
G03X1004262Y70484I-39J2307D01*
G03X1005011Y70984I-882J2132D01*
G01X1006313Y72287D01*
X1007249Y73223D01*
G03X1007924Y74853I-1631J1630D01*
G01Y84546D01*
G02X1007979Y84596I160J-120D01*
G01X1008002Y84610D01*
X1008346Y84754D01*
G02X1008455Y84767I77J-184D01*
G01X1010775Y82447D01*
G02Y82387I-198J-30D01*
G01Y82384D01*
X1010754Y82254D01*
X1010723Y82059D01*
G02X1010618Y81922I-196J41D01*
G01X1010591Y81908D01*
G03X1009795Y80581I708J-1327D01*
G03X1011297Y79079I1502J0D01*
G03X1012799Y80572I0J1502D01*
G01Y80582D01*
G03X1012723Y81054I-1502J0D01*
G01X1012717Y81072D01*
X1012712Y81108D01*
Y81109D01*
X1012706Y81147D01*
X1012716Y81189D01*
G02X1012747Y81255I194J-51D01*
G01X1012789Y81313D01*
G03X1012791Y81315I-139J141D01*
G01X1012831Y81372D01*
G02X1012871Y81413I162J-118D01*
G02X1012983Y81456I124J-157D01*
G01X1019059D01*
G03X1020690Y82132I-1J2307D01*
G01X1022972Y84414D01*
G03X1023648Y86045I-1631J1632D01*
G01Y86102D01*
X1023647Y86125D01*
G03X1021341Y88352I-2305J-79D01*
G03X1019710Y87677I-1J-2306D01*
G01X1019479Y87446D01*
G02X1019456Y87444I-29J198D01*
G01X1019407D01*
G02X1019277Y87492I0J200D01*
G01X1019271Y87497D01*
G03X1017787Y88038I-1484J-1765D01*
G01X1017166D01*
G02X1017130Y88073I120J160D01*
G01X1017057Y88164D01*
X1016927Y88325D01*
G02X1016917Y88341I165J114D01*
G02X1016902Y88377I176J95D01*
G01X1016886Y88439D01*
X1016896Y88484D01*
G03X1016929Y88791I-1469J313D01*
G03Y88793I-1502J1D01*
G01Y88816D01*
G03X1015603Y90293I-1502J-15D01*
G01X1015547Y90299D01*
G03X1015416Y90304I-123J-1498D01*
G01X1015408D01*
G03X1014496Y89980I20J-1502D01*
G03X1014430Y89925I928J-1181D01*
G01X1014424Y89920D01*
X1014417Y89914D01*
X1014385Y89893D01*
G02X1014207Y89878I-104J170D01*
G01X1014113Y89919D01*
X1014111D01*
X1013871Y90026D01*
G02X1013863Y90030I85J181D01*
G01X1013809Y90057D01*
X1013790Y90088D01*
Y102018D01*
G02X1013801Y102083I200J0D01*
G01X1013811Y102112D01*
X1013829Y102136D01*
X1013931Y102167D01*
G03X1014586Y102576I-452J1453D01*
G03X1014948Y103218I-1105J1046D01*
G01X1014957Y103250D01*
X1018646Y106939D01*
G03X1019028Y107861I-924J923D01*
G01Y118934D01*
G03X1018646Y119856I-1306J-1D01*
G01X1014844Y123657D01*
G02X1014789Y123763I142J141D01*
G02X1014786Y123798I197J35D01*
G01Y125874D01*
G02X1014826Y125994I200J0D01*
G01X1037520Y148689D01*
G02X1037593Y148685I26J-198D01*
G01X1037712Y148649D01*
X1037714D01*
X1037904Y148590D01*
G02X1037974Y148543I-74J-186D01*
G01X1038013Y148500D01*
X1038015Y148498D01*
X1038047Y148463D01*
G02X1038072Y148425I-154J-128D01*
G01X1038085Y148400D01*
X1038089Y148384D01*
X1038091Y148374D01*
G03X1039554Y147215I1463J344D01*
G03X1041056Y148717I0J1502D01*
G03X1039897Y150180I-1503J0D01*
G01X1039896D01*
X1039868Y150187D01*
X1039827Y150208D01*
X1039800Y150232D01*
X1039799Y150233D01*
X1039773Y150256D01*
X1039771Y150258D01*
X1039728Y150297D01*
G02X1039681Y150367I139J144D01*
G01X1039622Y150557D01*
Y150559D01*
X1039586Y150678D01*
G02X1039582Y150751I194J47D01*
G01X1063473Y174642D01*
G02X1063574Y174687I129J-153D01*
G02X1064030Y174292I56J-396D01*
G01Y164011D01*
G02X1064028Y163984I-200J1D01*
G01X1045273Y145229D01*
X1045231Y145204D01*
X1045208Y145197D01*
G03X1044219Y144208I446J-1435D01*
G01X1044212Y144185D01*
X1044187Y144143D01*
X1038302Y138258D01*
G03X1037920Y137336I924J-923D01*
G01Y127603D01*
G02X1037887Y127568I-161J119D01*
G01X1037746Y127452D01*
X1037744Y127450D01*
X1037652Y127375D01*
G02X1037603Y127345I-128J154D01*
G01X1037519Y127363D01*
G03X1037040Y127414I-482J-2256D01*
G01X1036856D01*
Y127407D01*
G03X1034734Y125109I184J-2299D01*
G01Y121166D01*
G02X1034723Y121153I-158J123D01*
G01X1034707Y121135D01*
X1034402Y120946D01*
G02X1034208Y120941I-102J172D01*
G01X1034198Y120946D01*
X1034165Y120962D01*
X1034134Y120976D01*
G03X1033506Y121113I-630J-1382D01*
G03X1031987Y119594I0J-1519D01*
G03X1032543Y118421I1515J0D01*
G01X1032545Y118419D01*
X1032567Y118400D01*
X1032583Y118387D01*
X1032597Y118371D01*
G02X1032620Y118336I-155J-127D01*
G01X1032646Y118280D01*
G02X1032660Y118207I-186J-74D01*
G01Y117983D01*
G02X1032642Y117900I-200J0D01*
G01X1032629Y117873D01*
Y117871D01*
X1032602Y117817D01*
G02X1032569Y117772I-176J95D01*
G01X1032550Y117753D01*
X1032543Y117747D01*
G03X1032004Y116594I964J-1153D01*
G03X1033506Y115092I1502J0D01*
G03X1034581Y115545I0J1502D01*
G01X1034589Y115553D01*
G02X1034632Y115583I135J-148D01*
G01X1034755Y115638D01*
X1034801Y115635D01*
X1034802D01*
X1034855Y115632D01*
X1034900Y115602D01*
G02X1034970Y115523I-109J-167D01*
G03X1035409Y114909I2070J1016D01*
G01X1045009Y105309D01*
G02X1045062Y105207I-143J-139D01*
G02X1045066Y105169I-196J-40D01*
G01Y95111D01*
G03X1049680I2307J0D01*
G01Y105213D01*
G02X1049721Y105254I160J-119D01*
G01X1050881D01*
X1050891D01*
G02X1050972Y105232I-11J-200D01*
G03X1051065Y105182I773J1327D01*
G01X1051088Y105171D01*
X1051090Y105170D01*
X1051125Y105140D01*
X1051140Y105119D01*
G02X1051094Y104840I-163J-116D01*
G01X1051071Y104824D01*
X1051047Y104815D01*
G03X1050081Y103411I537J-1404D01*
G03X1053085I1502J0D01*
G03X1052506Y104596I-1502J0D01*
G01X1052488Y104610D01*
X1052451Y104655D01*
G02X1052421Y104704I154J128D01*
G01Y104706D01*
G02X1052405Y104793I184J79D01*
G01X1052410Y104897D01*
Y104899D01*
X1052421Y105081D01*
G02X1052433Y105126I198J-29D01*
G01X1052461Y105177D01*
G02X1052486Y105210I171J-104D01*
G01X1052503Y105228D01*
X1052511Y105233D01*
X1052528Y105243D01*
G03X1053277Y106561I-785J1318D01*
G03X1051742Y108096I-1535J0D01*
G01X1051741D01*
G03X1050979Y107894I0J-1537D01*
G01X1050956Y107881D01*
X1050932Y107875D01*
G02X1050881Y107868I-52J193D01*
G01X1050390D01*
G02X1050249Y107926I0J200D01*
G01X1044134Y114039D01*
X1040551Y117623D01*
G02X1040532Y117645I141J141D01*
G01Y136710D01*
G02X1040534Y136740I200J2D01*
G02X1040589Y136850I198J-30D01*
G01X1044251Y140511D01*
X1046035Y142295D01*
X1046077Y142320D01*
X1046100Y142327D01*
G03X1047089Y143316I-446J1435D01*
G01X1047096Y143339D01*
X1047121Y143381D01*
X1066542Y162802D01*
G03X1066924Y163724I-924J923D01*
G01Y291096D01*
G02X1066946Y291187I200J0D01*
G02X1066982Y291237I178J-90D01*
G01X1079579Y303834D01*
G02X1079629Y303870I140J-142D01*
G02X1079720Y303892I91J-178D01*
G01X1091111D01*
G03X1092033Y304274I-1J1306D01*
G01X1096351Y308592D01*
G03X1096734Y309516I-923J924D01*
G01Y338910D01*
Y338914D01*
G02X1096830Y339081I200J-4D01*
G01X1096864Y339100D01*
X1096879Y339109D01*
X1096880D01*
X1096930Y339138D01*
X1096932D01*
X1096945Y339147D01*
G03X1096948Y339149I-109J167D01*
G03X1096963Y339161I-117J162D01*
G01X1096992Y339186D01*
X1097001Y339194D01*
X1097098Y339215D01*
X1097100Y339214D01*
X1097105Y339213D01*
X1097212Y339183D01*
X1097233Y339171D01*
G03X1097875Y338978I743J1306D01*
G01X1097887D01*
X1097891Y338977D01*
X1097899D01*
X1097906Y338976D01*
X1097930D01*
X1097939Y338975D01*
X1097982D01*
G03Y341979I-6J1502D01*
G01X1097974D01*
G03X1097241Y341787I2J-1503D01*
G01X1097219Y341775D01*
X1097141Y341754D01*
G02X1097074Y341752I-39J196D01*
G01X1097027Y341761D01*
X1096991Y341782D01*
X1096988Y341784D01*
X1096835Y341871D01*
G02X1096734Y342044I99J174D01*
G01Y354209D01*
G03X1096351Y355133I-1306J0D01*
G01X1063909Y387575D01*
G03X1062985Y387958I-924J-923D01*
G01X1060900D01*
X1060881Y387978D01*
G03X1060874Y387984I-134J-149D01*
G01X1060865Y387991D01*
X1011648Y437208D01*
G02X1011612Y437258I142J140D01*
G02X1011590Y437349I178J91D01*
G01Y441127D01*
G02X1011594Y441164I200J-3D01*
G01Y441166D01*
G02X1011647Y441267I196J-39D01*
G01X1011655Y441275D01*
X1011881Y441483D01*
G02X1011943Y441517I126J-156D01*
G01X1011967Y441523D01*
G02X1012015Y441526I36J-197D01*
G01X1012019D01*
X1012065Y441523D01*
G03X1012086Y441522I101J1899D01*
G01X1012095D01*
G03X1012171Y441520I88J1899D01*
G01X1012177D01*
G03X1012188I5J1901D01*
G01X1012189D01*
G03X1013533Y442076I0J1902D01*
G01X1016320Y444864D01*
G02X1016602I141J-142D01*
G01X1031075Y430391D01*
G03X1031217Y430332I142J141D01*
G01X1048343D01*
G02X1048372Y430330I1J-200D01*
G02X1048457Y430296I-30J-198D01*
G01X1048482Y430279D01*
X1048518Y430232D01*
X1048529Y430202D01*
X1048531Y430196D01*
X1048534Y430188D01*
X1048535Y430183D01*
G03X1049967Y429136I1432J456D01*
G03X1050188Y429152I2J1502D01*
G01X1050197Y429154D01*
X1050200D01*
X1050227Y429155D01*
G02X1050353Y429112I2J-200D01*
G01X1050401Y429072D01*
X1050404Y429069D01*
X1050589Y428912D01*
G02X1050608Y428893I-131J-150D01*
G03X1050610Y428891I142J140D01*
G02X1050660Y428759I-150J-132D01*
G01Y426460D01*
G03X1054266I1803J0D01*
G01Y428426D01*
G02X1054379Y428599I200J-7D01*
G01X1054486D01*
G02X1054518Y428596I-3J-200D01*
G01X1054520D01*
G02X1054626Y428542I-34J-197D01*
G01X1055092Y428076D01*
G03X1055682Y427591I2754J2749D01*
G01X1061162Y423929D01*
X1061194Y423907D01*
X1061215Y423877D01*
G02X1061247Y423806I-163J-116D01*
G01X1061254Y423775D01*
Y423773D01*
X1061275Y423687D01*
Y423639D01*
X1061269Y423615D01*
X1061267Y423606D01*
X1061254Y423557D01*
X1061245Y423539D01*
G03X1061062Y422748I1620J-791D01*
G01Y419347D01*
G03X1064668I1803J0D01*
G01Y421215D01*
G02X1064671Y421252I200J2D01*
G02X1064762Y421385I197J-37D01*
G01X1064822Y421417D01*
X1064876Y421415D01*
G02X1064971Y421386I-9J-200D01*
G01X1065064Y421324D01*
X1065428Y421082D01*
X1065436Y421077D01*
X1080323Y409218D01*
X1080338Y409206D01*
X1085182Y404362D01*
G03X1085324Y404303I142J141D01*
G01X1086431D01*
G02X1086546Y404260I-9J-200D01*
G01X1086547Y404259D01*
X1088148Y402985D01*
G03X1088515Y402726I2424J3045D01*
G03X1088635Y402654I2062J3300D01*
G03X1088836Y402547I1928J3380D01*
G01X1103310Y395327D01*
X1103337Y395304D01*
X1107923Y390718D01*
G03X1108065Y390659I142J141D01*
G01X1112625D01*
G02X1112661Y390655I-4J-200D01*
G01X1115912Y389030D01*
G02X1115969Y388919I-141J-142D01*
G01Y388918D01*
G03X1117452Y387651I1484J235D01*
G01X1117454D01*
G03X1117588Y387658I-11J1502D01*
G01X1117630Y387662D01*
G03X1118582Y388162I-177J1494D01*
G02X1118649Y388212I150J-132D01*
G01X1118653Y388214D01*
X1123555D01*
X1123584Y388202D01*
X1123611Y388174D01*
X1123632Y388153D01*
G03X1124750Y387651I1122J1003D01*
G01X1124753D01*
G03X1124756I1J1502D01*
G01X1124759D01*
G03X1124977Y387668I-7J1502D01*
G02X1124984Y387669I32J-197D01*
G02X1125111Y387641I23J-199D01*
G03X1126504Y387122I2042J3353D01*
G03X1127153Y387068I649J3873D01*
G03X1129256Y387679I-1J3927D01*
G02X1129269Y387678I-9J-200D01*
G03X1129459Y387654I283J1475D01*
G03X1129537Y387651I97J1499D01*
G01X1129549D01*
G03X1129556I4J1502D01*
G03X1131055Y389153I-3J1502D01*
G01Y389157D01*
G03X1130920Y389779I-1502J0D01*
G01X1130910Y389801D01*
X1130904Y389831D01*
Y389833D01*
G03X1131080Y390989I-3751J1162D01*
G01Y390995D01*
G03X1130738Y392598I-3927J0D01*
G01X1130731Y392614D01*
X1130713Y392693D01*
G02Y392697I200J2D01*
G01X1130727Y392757D01*
G02X1130739Y392795I196J-41D01*
G03X1131080Y394395I-3586J1601D01*
G03X1131037Y394972I-3927J-3D01*
G01Y394974D01*
X1131027Y395044D01*
X1131046Y395082D01*
G02X1131084Y395135I179J-88D01*
G01X1132180Y396231D01*
G03X1132239Y396373I-141J142D01*
G01Y549116D01*
G03X1132180Y549258I-200J0D01*
G01X1120392Y561046D01*
G02X1120335Y561162I141J141D01*
G01Y561212D01*
X1120337Y561225D01*
G03X1120349Y561413I-1490J190D01*
G01Y561424D01*
G03X1118847Y562922I-1502J-4D01*
G01X1118846D01*
G03X1118642Y562908I1J-1502D01*
G01X1118594Y562901D01*
X1118551Y562916D01*
G02X1118474Y562964I65J189D01*
G01X1117046Y564392D01*
G02X1117015Y564432I141J142D01*
G01X1117002Y564454D01*
X1116995Y564479D01*
G03X1116846Y564909I-3745J-1057D01*
G01X1116180Y566518D01*
G03X1115700Y567361I-3595J-1489D01*
G03X1115541Y567560I-3118J-2328D01*
G03X1115539Y567562I-142J-140D01*
G03X1115508Y567597I-2928J-2562D01*
G01X1115507Y567598D01*
X1115493Y567613D01*
X1115481Y567627D01*
X1115465Y567670D01*
G02X1115456Y567715I190J61D01*
G02X1115455Y567732I199J20D01*
G01Y573263D01*
G03X1115396Y573405I-200J0D01*
G01X1108799Y580002D01*
G03X1108657Y580061I-142J-141D01*
G01X1104971D01*
G02X1104898Y580075I0J200D01*
G01X1104864Y580088D01*
X1104837Y580113D01*
X1104830Y580119D01*
X1104039Y580910D01*
G03X1102691Y581788I-2752J-2752D01*
G01X1102651Y581803D01*
X1100177Y584277D01*
X1099672Y584781D01*
G02X1099619Y584897I146J137D01*
G01X1099611Y585002D01*
Y585004D01*
X1099529Y586012D01*
G02X1099528Y586028I199J20D01*
G01Y586110D01*
G02X1099535Y586136I196J-39D01*
G01X1099538Y586146D01*
Y586147D01*
X1099548Y586178D01*
G03X1099752Y587402I-3688J1244D01*
G01Y587421D01*
G03X1099739Y587736I-3892J-3D01*
G01X1099598Y589472D01*
G03X1099178Y590939I-3879J-317D01*
G01X1099162Y590970D01*
X1099158Y591003D01*
G02X1099160Y591069I198J27D01*
G01X1107501Y632889D01*
G02X1107697Y633050I196J-39D01*
G01X1108148D01*
G03X1111850Y636752I0J3702D01*
G03X1111848Y636883I-3702J9D01*
G01X1111847Y636910D01*
G03X1109233Y640292I-3699J-157D01*
G01X1109201Y640302D01*
X1109163Y640329D01*
G02X1109134Y640358I126J155D01*
G01X1109116Y640381D01*
X1109081Y640426D01*
X1109079Y640428D01*
X1109076Y640433D01*
X1109074Y640435D01*
G02X1109038Y640594I160J120D01*
G01X1109561Y643221D01*
X1113264Y661782D01*
G02X1113307Y661863I193J-51D01*
G02X1113343Y661896I152J-130D01*
G01X1113360Y661907D01*
G02X1113393Y661922I99J-174D01*
G01X1113558Y661969D01*
X1113560D01*
X1113728Y662016D01*
G03X1113800Y662064I-72J186D01*
G01X1113925Y661987D01*
X1113948Y661964D01*
X1113958Y661953D01*
G03X1114712Y661518I1096J1028D01*
G03X1115046Y661479I340J1463D01*
G01X1115078D01*
G03X1116556Y662981I-24J1502D01*
G03X1115054Y664483I-1502J0D01*
G03X1114441Y664352I0J-1502D01*
G01X1114422Y664344D01*
X1114377Y664334D01*
G02X1114210Y664372I-43J195D01*
G01X1113969Y664562D01*
X1113967Y664564D01*
X1113938Y664587D01*
G02X1113861Y664777I121J159D01*
G01X1113863Y664784D01*
Y664785D01*
X1116183Y676415D01*
G02X1116769Y676687I392J-78D01*
G03X1117500Y676497I731J1313D01*
G03X1118696Y677090I0J1503D01*
G02X1119348Y677069I319J-242D01*
G03X1120600Y676397I1252J830D01*
G03Y679403I0J1503D01*
G03X1119404Y678810I0J-1503D01*
G02X1118752Y678831I-319J242D01*
G03X1117500Y679503I-1252J-830D01*
G03X1117329Y679493I2J-1503D01*
G02X1116891Y679969I-46J398D01*
G01X1121044Y700783D01*
G02X1121052Y700810I195J-43D01*
G01X1121946Y702970D01*
X1122608Y704569D01*
G03X1122621Y704600I-1198J521D01*
G01Y704602D01*
G03X1122708Y705069I-1220J469D01*
G01Y709100D01*
G02X1122712Y709139I200J-1D01*
G01X1123605Y713627D01*
X1126392Y727599D01*
G02X1126445Y727697I195J-42D01*
G01X1129852Y731104D01*
X1129894Y731129D01*
X1129917Y731136D01*
G03X1130973Y732571I-447J1435D01*
G03X1129471Y734073I-1502J0D01*
G01Y734074D01*
G03X1128036Y733017I0J-1503D01*
G01Y733016D01*
G02X1127986Y732934I-191J60D01*
G01X1127790Y732738D01*
G02X1127577Y732693I-141J141D01*
G01X1127488Y732740D01*
X1127470Y732772D01*
G02X1127450Y732897I177J92D01*
G01X1139710Y794368D01*
G02X1139713Y794380I195J-42D01*
G01X1152662Y843027D01*
G02X1152719Y843121I193J-53D01*
G01X1152739Y843140D01*
X1152786Y843165D01*
X1152815Y843171D01*
G03X1154012Y844642I-305J1471D01*
G03X1153489Y845782I-1504J0D01*
G01X1153488Y845783D01*
G02X1153486Y845785I140J142D01*
G01X1153478Y845792D01*
X1153463Y845805D01*
X1153447Y845859D01*
G02X1153445Y845967I192J58D01*
G01X1153459Y846019D01*
X1153742Y847083D01*
G02X1153784Y847163I194J-51D01*
G01X1153812Y847195D01*
X1153853Y847214D01*
G03X1154721Y848404I-624J1367D01*
G01X1154727Y848459D01*
G03X1154732Y848581I-1498J122D01*
G03X1154479Y849415I-1502J0D01*
G01X1154462Y849439D01*
X1154445Y849496D01*
Y849694D01*
G02X1154452Y849745I200J-1D01*
G01X1159136Y867342D01*
G02X1159223Y867460I193J-51D01*
G01X1159249Y867476D01*
X1159457Y867606D01*
G02X1159524Y867633I107J-169D01*
G01X1159558Y867640D01*
X1159598Y867632D01*
G03X1159887Y867604I289J1474D01*
G01X1159898D01*
G03X1161389Y869106I-11J1502D01*
G03X1160370Y870529I-1503J0D01*
G01X1160334Y870541D01*
X1160305Y870565D01*
G02X1160258Y870624I130J152D01*
G01X1160129Y870864D01*
G02X1160121Y870882I178J90D01*
G02X1160107Y870980I185J76D01*
G02X1160112Y871010I199J-18D01*
G01X1172997Y919408D01*
X1184901Y964124D01*
G02X1184904Y964135I194J-47D01*
G02X1184953Y964214I190J-63D01*
G01X1185182Y964443D01*
G02X1185283Y964496I140J-143D01*
G01X1185285D01*
G02X1185322Y964500I40J-196D01*
G01X1197198D01*
G02X1197230Y964497I-3J-200D01*
G01X1197232D01*
G02X1197338Y964443I-34J-197D01*
G01X1198997Y962784D01*
G02X1199055Y962641I-142J-141D01*
G01X1198287Y951691D01*
G02X1198254Y951595I-199J15D01*
G02X1198225Y951560I-168J109D01*
G01X1198151Y951498D01*
X1198124Y951501D01*
X1198114Y951502D01*
X1198113D01*
X1197875Y951527D01*
G02X1197833Y951539I34J197D01*
G01X1197722Y951650D01*
X1197708Y951680D01*
G03X1196352Y952535I-1356J-648D01*
G03X1194850Y951033I0J-1502D01*
G03X1196176Y949541I1502J0D01*
G01X1196230Y949535D01*
G03X1197535Y950106I122J1498D01*
G01X1197540Y950113D01*
X1197558Y950136D01*
X1197608Y950175D01*
G02X1197686Y950210I119J-161D01*
G02X1197724Y950214I40J-196D01*
G01X1197750D01*
X1198080Y950177D01*
G02X1198177Y950139I-22J-199D01*
G01X1198067Y948572D01*
X1197888Y946017D01*
X1197642Y942507D01*
G02X1197584Y942390I-199J26D01*
G02X1197578Y942384I-144J138D01*
G01X1197313Y942144D01*
X1197265Y942145D01*
G03X1197179Y942147I-78J-1501D01*
G01X1197173D01*
G03X1195671Y940645I0J-1502D01*
G03X1197018Y939151I1502J0D01*
G01X1197057Y939147D01*
X1197091Y939129D01*
G02X1197151Y939081I-93J-177D01*
G01X1197333Y938865D01*
G02X1197376Y938725I-156J-125D01*
G01X1193647Y885599D01*
Y885598D01*
G02X1193525Y885428I-200J14D01*
G01X1193442Y885398D01*
G02X1193440Y885397I-88J174D01*
G02X1193326Y885391I-67J189D01*
G01X1193318Y885394D01*
X1193313Y885395D01*
G02X1193231Y885444I59J191D01*
G01X1193226Y885449D01*
G03X1192152Y885901I-1074J-1050D01*
G03Y882897I0J-1502D01*
G03X1193051Y883196I0J1501D01*
G01X1193059Y883202D01*
X1193074Y883213D01*
X1193129Y883234D01*
X1193138Y883237D01*
G02X1193297Y883225I66J-189D01*
G01X1193359Y883192D01*
G02X1193465Y883009I-94J-177D01*
G01X1193238Y879773D01*
X1192950Y875671D01*
X1192563Y870161D01*
G02X1192478Y870125I-118J161D01*
G01X1192415Y870122D01*
X1192402D01*
G03X1190931Y868695I29J-1502D01*
G03X1191086Y867951I1500J-76D01*
G03X1191296Y867636I1345J669D01*
G03X1192199Y867136I1135J984D01*
G02X1192205Y867135I-30J-197D01*
G01X1192216Y867133D01*
X1192254Y867126D01*
G02X1192310Y867105I-41J-195D01*
G01X1192338Y867090D01*
X1192347Y867079D01*
X1192311Y866560D01*
X1191725Y858212D01*
X1191711Y858011D01*
G02X1191671Y857905I-199J15D01*
G01X1191637Y857859D01*
X1191615Y857850D01*
X1191591Y857842D01*
X1191503Y857811D01*
G02X1191295Y857858I-67J188D01*
G01X1191287Y857866D01*
G03X1190213Y858318I-1074J-1050D01*
G03Y855314I0J-1502D01*
G01X1190215D01*
G03X1191128Y855623I0J1504D01*
G01X1191145Y855636D01*
X1191179Y855652D01*
G02X1191254Y855671I86J-181D01*
G01X1191268D01*
G02X1191357Y855649I-2J-200D01*
G01X1191430Y855609D01*
G02X1191529Y855423I-100J-173D01*
G01X1191216Y850964D01*
X1191166Y850247D01*
G02X1191057Y850205I-123J157D01*
G01X1190966D01*
G03X1189476Y848879I2J-1502D01*
G01X1189470Y848828D01*
G03X1189465Y848703I1498J-123D01*
G03X1190764Y847214I1503J0D01*
G01X1190825Y847206D01*
X1190868Y847200D01*
X1190898Y847184D01*
X1190932Y847166D01*
X1190948Y847147D01*
X1188279Y809120D01*
X1176527Y641715D01*
G02X1176526Y641701I-200J7D01*
G01X1176084Y638565D01*
X1174625Y628214D01*
G02X1174613Y628168I-198J27D01*
G01X1174605Y628147D01*
X1174591Y628127D01*
G03X1173918Y626419I3216J-2254D01*
G01X1173646Y624487D01*
G03X1173608Y623940I3888J-545D01*
G03X1173633Y623495I3926J-3D01*
G01X1173636Y623470D01*
X1173599Y623210D01*
G03X1173562Y622782I3855J-549D01*
G02X1173545Y622707I-200J6D01*
G03X1173248Y621668I3591J-1588D01*
G01X1172975Y619736D01*
G03X1172936Y619187I3888J-552D01*
G03X1172963Y618731I3927J4D01*
G01X1172966Y618705D01*
X1172926Y618422D01*
X1172919Y618375D01*
X1172895Y618340D01*
G02X1172829Y618277I-167J109D01*
G01X1172542Y618115D01*
G02X1172489Y618099I-84J182D01*
G01X1172413Y618131D01*
G03X1172357Y618154I-1520J-3621D01*
G02X1172353Y618156I87J179D01*
G01X1172350Y618157D01*
G03X1172346Y618159I-91J-177D01*
G03X1170842Y618444I-1469J-3642D01*
G01X1170834D01*
G03X1169473Y618184I45J-3926D01*
G03X1168776Y617834I1405J-3667D01*
G02X1168769Y617835I25J198D01*
G01X1168752Y617836D01*
G03X1168495Y617861I-273J-1477D01*
G01X1168478D01*
G03X1166976Y616359I0J-1502D01*
G01Y616356D01*
G03X1167112Y615731I1502J0D01*
G01X1167121Y615711D01*
X1167128Y615681D01*
G03X1166952Y614521I3750J-1162D01*
G01Y614517D01*
G03X1167304Y612891I3928J-1D01*
G02Y612743I-186J-74D01*
G03X1166952Y611117I3576J-1625D01*
G03X1167067Y610171I3926J-3D01*
G03X1167128Y609951I3813J939D01*
G01X1167127Y609946D01*
X1167122Y609923D01*
G03X1166976Y609276I1356J-646D01*
G01Y609272D01*
G03X1168478Y607770I1502J0D01*
G01X1168481D01*
G03X1168483I1J1502D01*
G03X1168753Y607795I-3J1502D01*
G01X1168778Y607799D01*
G03X1170878Y607190I2100J3318D01*
G01X1170900D01*
G03X1172976Y607798I-23J3927D01*
G01X1172997Y607796D01*
G03X1173144Y607776I276J1477D01*
G01X1173146D01*
G03X1173197Y607772I143J1495D01*
G03X1173214Y607771I97J1498D01*
G01X1173227D01*
G03X1173245Y607770I92J1499D01*
G01X1173284D01*
G03X1173746Y607843I-1J1503D01*
G01X1173755Y607846D01*
X1173788Y607854D01*
G02X1173943Y607819I37J-197D01*
G01X1174205Y607630D01*
X1174214Y607621D01*
X1174246Y607596D01*
X1174254Y607581D01*
X1174252Y607506D01*
Y607430D01*
G03X1174604Y605804I3928J-1D01*
G02Y605656I-186J-74D01*
G03X1174252Y604030I3576J-1625D01*
G01Y603959D01*
Y603953D01*
X1174254Y603880D01*
G02X1174207Y603830I-167J110D01*
G01X1174091Y603746D01*
X1174089D01*
X1173965Y603655D01*
G02X1173951Y603645I-123J158D01*
G01X1173926Y603630D01*
G02X1173800Y603603I-103J172D01*
G01X1173770Y603606D01*
X1173751Y603612D01*
X1173748Y603613D01*
G03X1173281Y603688I-469J-1427D01*
G01X1173249D01*
G03X1173011Y603665I25J-1502D01*
G01X1172982Y603659D01*
G03X1170878Y604270I-2103J-3315D01*
G03X1168776Y603661I-2J-3926D01*
G01X1168768D01*
G02X1168755Y603662I9J200D01*
G03X1168496Y603688I-279J-1476D01*
G01X1168478D01*
G03X1166976Y602207I0J-1502D01*
G01Y602185D01*
G03X1167121Y601540I1502J-1D01*
G01X1167128Y601510D01*
G03X1167021Y601081I3750J-1163D01*
G03X1166952Y600344I3857J-733D01*
G03X1167304Y598718I3928J-1D01*
G02Y598570I-186J-74D01*
G03X1166952Y596944I3576J-1625D01*
G03X1167067Y595998I3926J-3D01*
G03X1167128Y595778I3813J939D01*
G01X1167127Y595773D01*
X1167122Y595750D01*
G03X1166977Y595151I1357J-645D01*
G01Y595149D01*
G03X1166976Y595115I1501J-61D01*
G01Y595099D01*
G03X1168442Y593597I1502J0D01*
G01X1168480Y593596D01*
X1168481D01*
G03X1168741Y593618I4J1504D01*
G01X1168780Y593625D01*
G03X1170878Y593018I2097J3319D01*
G03X1172971Y593622I1J3926D01*
G01X1173005D01*
G03X1173278Y593597I273J1478D01*
G01X1173311D01*
G03X1173744Y593671I-34J1502D01*
G01X1173760Y593676D01*
X1173817Y593685D01*
G02X1173984Y593628I26J-198D01*
G01X1174014Y593598D01*
G03X1174037Y593578I142J140D01*
G01X1174208Y593454D01*
G02X1174254Y593405I-121J-159D01*
G01X1174252Y593332D01*
Y593257D01*
G03X1174604Y591631I3928J-1D01*
G02Y591483I-186J-74D01*
G03X1174252Y589857I3576J-1625D01*
G01Y589786D01*
Y589780D01*
X1174254Y589707D01*
G02X1174207Y589657I-167J110D01*
G01X1174091Y589573D01*
X1174089D01*
X1173965Y589482D01*
G02X1173951Y589472I-123J158D01*
G01X1173926Y589457D01*
G02X1173800Y589430I-103J172D01*
G01X1173770Y589433D01*
X1173751Y589439D01*
X1173748Y589440D01*
G03X1173281Y589515I-469J-1427D01*
G01X1173276D01*
G03X1173020Y589493I0J-1502D01*
G01X1172982Y589486D01*
G03X1170878Y590098I-2105J-3315D01*
G03X1169679Y589910I1J-3926D01*
G03X1168776Y589488I1198J-3740D01*
G02X1168769Y589489I25J198D01*
G01X1168752Y589490D01*
G03X1168495Y589515I-273J-1477D01*
G01X1168478D01*
G03X1166976Y588013I0J-1502D01*
G01Y588010D01*
G03X1167112Y587385I1502J0D01*
G01X1167121Y587365D01*
X1167128Y587335D01*
G03X1166952Y586175I3750J-1162D01*
G01Y586171D01*
G03X1167304Y584545I3928J-1D01*
G02Y584397I-186J-74D01*
G03X1166952Y582771I3576J-1625D01*
G03X1167067Y581825I3926J-3D01*
G03X1167128Y581605I3813J939D01*
G01X1167127Y581600D01*
X1167122Y581577D01*
G03X1166976Y580930I1356J-646D01*
G01Y580926D01*
G03X1168478Y579424I1502J0D01*
G01X1168481D01*
G03X1168483I1J1502D01*
G03X1168753Y579449I-3J1502D01*
G01X1168778Y579453D01*
G03X1170878Y578844I2100J3318D01*
G01X1170900D01*
G03X1172976Y579452I-23J3927D01*
G01X1172997Y579450D01*
G03X1173144Y579430I276J1477D01*
G01X1173146D01*
G03X1173197Y579426I143J1495D01*
G03X1173214Y579425I97J1498D01*
G01X1173227D01*
G03X1173245Y579424I92J1499D01*
G01X1173284D01*
G03X1173746Y579497I-1J1503D01*
G01X1173755Y579500D01*
X1173788Y579508D01*
G02X1173943Y579473I37J-197D01*
G01X1174205Y579284D01*
X1174214Y579275D01*
X1174246Y579250D01*
X1174254Y579235D01*
X1174252Y579160D01*
Y579084D01*
G03X1174604Y577458I3928J-1D01*
G02Y577310I-186J-74D01*
G03X1174252Y575686I3576J-1625D01*
G01Y575530D01*
G02X1174213Y575487I-166J112D01*
G01X1174091Y575399D01*
X1174089D01*
X1173965Y575308D01*
G02X1173951Y575298I-123J158D01*
G01X1173926Y575283D01*
G02X1173800Y575256I-103J172D01*
G01X1173770Y575259D01*
X1173751Y575265D01*
X1173748Y575266D01*
G03X1173281Y575341I-469J-1427D01*
G01X1173276D01*
G03X1173020Y575319I0J-1502D01*
G01X1172982Y575312D01*
G03X1170878Y575924I-2105J-3315D01*
G03X1169679Y575736I1J-3926D01*
G03X1168776Y575314I1198J-3740D01*
G02X1168769Y575315I25J198D01*
G01X1168752Y575316D01*
G03X1168495Y575341I-273J-1477D01*
G01X1168478D01*
G03X1166976Y573839I0J-1502D01*
G01Y573836D01*
G03X1167112Y573211I1502J0D01*
G01X1167121Y573191D01*
X1167128Y573161D01*
G03X1166952Y572001I3750J-1162D01*
G01Y571997D01*
G03X1167304Y570371I3928J-1D01*
G02Y570223I-186J-74D01*
G03X1166952Y568597I3576J-1625D01*
G03X1167067Y567651I3926J-3D01*
G03X1167128Y567431I3813J939D01*
G01X1167127Y567426D01*
X1167122Y567403D01*
G03X1166976Y566756I1356J-646D01*
G01Y566752D01*
G03X1168478Y565250I1502J0D01*
G01X1168481D01*
G03X1168483I1J1502D01*
G03X1168753Y565275I-3J1502D01*
G01X1168778Y565279D01*
G03X1170878Y564670I2100J3318D01*
G01X1170900D01*
G03X1172976Y565278I-23J3927D01*
G01X1172997Y565276D01*
G03X1173144Y565256I276J1477D01*
G01X1173146D01*
G03X1173197Y565252I143J1495D01*
G03X1173214Y565251I97J1498D01*
G01X1173227D01*
G03X1173245Y565250I92J1499D01*
G01X1173284D01*
G03X1173746Y565323I-1J1503D01*
G01X1173755Y565326D01*
X1173788Y565334D01*
G02X1173943Y565299I37J-197D01*
G01X1174205Y565110D01*
X1174214Y565101D01*
X1174246Y565076D01*
X1174254Y565061D01*
X1174252Y564986D01*
Y564910D01*
G03X1174604Y563284I3928J-1D01*
G02Y563136I-186J-74D01*
G03X1174252Y561510I3576J-1625D01*
G03X1174367Y560564I3926J-3D01*
G03X1174428Y560344I3813J939D01*
G01X1174427Y560339D01*
X1174422Y560316D01*
G03X1174276Y559669I1356J-646D01*
G01Y559665D01*
G03X1175778Y558163I1502J0D01*
G01X1175783D01*
G03X1176053Y558188I-3J1502D01*
G01X1176081Y558190D01*
G03X1176753Y557851I2096J3320D01*
G01X1176845Y557815D01*
G02X1176881Y557710I-164J-115D01*
G01X1176682Y549006D01*
X1176466Y539557D01*
G02X1176465Y539546I-199J13D01*
G02X1176335Y539374I-199J16D01*
G02X1176279Y539362I-70J188D01*
G01X1175404D01*
G03X1174539Y539252I55J-3891D01*
G03X1174299Y539186I911J-3783D01*
G02X1174127Y539212I-59J191D01*
G03X1173297Y539475I-849J-1239D01*
G01X1173278D01*
G03X1173275I-2J-1502D01*
G01X1173256D01*
G03X1173156Y539470I25J-1502D01*
G01X1173152D01*
X1173145Y539469D01*
X1173143D01*
G03X1173026Y539454I132J-1496D01*
G01X1173025D01*
X1172997Y539449D01*
X1172980Y539448D01*
G03X1172386Y539757I-2102J-3316D01*
G03X1168776Y539448I-1508J-3625D01*
G01X1168749Y539451D01*
X1168741Y539452D01*
G03X1168478Y539475I-262J-1479D01*
G01X1168469D01*
G03X1166976Y537973I9J-1502D01*
G01Y537970D01*
G03X1167112Y537345I1502J0D01*
G01X1167121Y537325D01*
X1167128Y537295D01*
G03X1166952Y536135I3750J-1162D01*
G01Y536131D01*
G03X1167304Y534505I3928J-1D01*
G02Y534357I-186J-74D01*
G03X1166952Y532731I3576J-1625D01*
G03X1167067Y531785I3926J-3D01*
G03X1167128Y531565I3813J939D01*
G01X1167127Y531560D01*
X1167122Y531537D01*
G03X1166976Y530890I1356J-646D01*
G01Y530886D01*
G03X1168478Y529384I1502J0D01*
G01X1168481D01*
G03X1168483I1J1502D01*
G03X1168753Y529409I-3J1502D01*
G01X1168778Y529413D01*
G03X1170878Y528804I2100J3318D01*
G01X1170900D01*
G03X1172976Y529412I-23J3927D01*
G01X1172997Y529410D01*
G03X1173144Y529390I276J1477D01*
G01X1173146D01*
G03X1173197Y529386I143J1495D01*
G03X1173214Y529385I97J1498D01*
G01X1173227D01*
G03X1173245Y529384I92J1499D01*
G01X1173284D01*
G03X1173746Y529457I-1J1503D01*
G01X1173755Y529460D01*
X1173788Y529468D01*
G02X1173943Y529433I37J-197D01*
G01X1174205Y529244D01*
X1174214Y529235D01*
X1174246Y529210D01*
X1174254Y529195D01*
X1174252Y529120D01*
Y529044D01*
G03X1174604Y527418I3928J-1D01*
G02Y527270I-186J-74D01*
G03X1174252Y525644I3576J-1625D01*
G01Y525573D01*
Y525567D01*
X1174254Y525494D01*
G02X1174207Y525444I-167J110D01*
G01X1174091Y525360D01*
X1174089D01*
X1173965Y525269D01*
G02X1173951Y525259I-123J158D01*
G01X1173926Y525244D01*
G02X1173800Y525217I-103J172D01*
G01X1173770Y525220D01*
X1173751Y525226D01*
X1173748Y525227D01*
G03X1173281Y525302I-469J-1427D01*
G01X1173249D01*
G03X1173011Y525279I25J-1502D01*
G01X1172982Y525273D01*
G03X1170878Y525884I-2103J-3315D01*
G03X1168776Y525275I-2J-3926D01*
G01X1168768D01*
G02X1168755Y525276I9J200D01*
G03X1168496Y525302I-279J-1476D01*
G01X1168478D01*
G03X1166976Y523821I0J-1502D01*
G01Y523799D01*
G03X1167121Y523154I1502J-1D01*
G01X1167128Y523124D01*
G03X1167021Y522695I3750J-1163D01*
G03X1166952Y521958I3857J-733D01*
G03X1167304Y520332I3928J-1D01*
G02Y520184I-186J-74D01*
G03X1166952Y518558I3576J-1625D01*
G03X1167067Y517612I3926J-3D01*
G03X1167128Y517392I3812J939D01*
G01X1167127Y517387D01*
X1167122Y517364D01*
G03X1166977Y516765I1357J-645D01*
G01Y516763D01*
G03X1166976Y516729I1501J-61D01*
G01Y516713D01*
G03X1168442Y515211I1502J0D01*
G01X1168480Y515210D01*
X1168481D01*
G03X1168741Y515232I4J1504D01*
G01X1168780Y515239D01*
G03X1170878Y514632I2097J3319D01*
G03X1172971Y515236I1J3926D01*
G01X1173005D01*
G03X1173278Y515211I273J1478D01*
G01X1173311D01*
G03X1173744Y515285I-34J1502D01*
G01X1173760Y515290D01*
X1173817Y515299D01*
G02X1173984Y515242I26J-198D01*
G01X1174014Y515212D01*
G03X1174037Y515192I142J140D01*
G01X1174208Y515068D01*
G02X1174254Y515019I-121J-159D01*
G01X1174252Y514946D01*
Y514871D01*
G03X1174604Y513245I3928J-1D01*
G02Y513097I-186J-74D01*
G03X1174252Y511471I3576J-1625D01*
G03X1174428Y510305I3927J-4D01*
G01X1174422Y510276D01*
G03X1174339Y510061I1356J-647D01*
G03X1174297Y509883I1439J-433D01*
G03X1174275Y509628I1480J-256D01*
G01Y509626D01*
G03X1175546Y508142I1502J0D01*
G01X1175571Y508137D01*
X1175599Y508122D01*
X1175691Y508073D01*
X1175692Y508072D01*
X1175694Y508071D01*
G02X1175744Y507950I-150J-133D01*
G01X1175562Y499987D01*
X1175446Y494923D01*
G02X1175378Y494778I-200J5D01*
G01X1174475D01*
X1174445Y494792D01*
X1174419Y494819D01*
X1174415Y494823D01*
X1174408Y494831D01*
X1174402Y494837D01*
G03X1173287Y495342I-1124J-998D01*
G01X1173255Y495341D01*
X1173253D01*
G03X1173024Y495320I22J-1503D01*
G01X1173009Y495317D01*
G03X1172982Y495312I260J-1481D01*
G03X1170879Y495924I-2105J-3315D01*
G01X1170878D01*
G03X1169400Y495635I1J-3927D01*
G03X1168782Y495317I1481J-3637D01*
G01X1168745D01*
G03X1168728Y495320I-270J-1478D01*
G03X1168481Y495341I-250J-1481D01*
G01X1168478D01*
G03X1166976Y493839I0J-1502D01*
G01Y493836D01*
G03X1167121Y493191I1502J-1D01*
G01X1167128Y493161D01*
G03X1166952Y492003I3750J-1162D01*
G03Y492001I3926J-1D01*
G01Y491997D01*
G03X1167304Y490371I3928J-1D01*
G02Y490223I-186J-74D01*
G03X1166952Y488597I3576J-1625D01*
G03X1167067Y487651I3926J-3D01*
G03X1167128Y487431I3812J939D01*
G01X1167127Y487426D01*
X1167122Y487403D01*
G03X1166976Y486756I1356J-646D01*
G01Y486752D01*
G03X1168478Y485250I1502J0D01*
G01X1168497D01*
G03X1168753Y485275I-17J1502D01*
G01X1168778Y485279D01*
G03X1170878Y484670I2100J3318D01*
G01X1170900D01*
G03X1172976Y485278I-23J3927D01*
G01X1172997Y485276D01*
G03X1173144Y485256I276J1477D01*
G01X1173146D01*
G03X1173197Y485252I143J1495D01*
G03X1173214Y485251I97J1498D01*
G01X1173227D01*
G03X1173245Y485250I92J1499D01*
G01X1173284D01*
G03X1173746Y485323I-1J1503D01*
G01X1173755Y485326D01*
X1173788Y485334D01*
G02X1173943Y485299I37J-197D01*
G01X1174205Y485110D01*
X1174214Y485101D01*
X1174246Y485076D01*
X1174254Y485061D01*
X1174252Y484986D01*
Y484910D01*
G03X1174604Y483284I3928J-1D01*
G02Y483136I-186J-74D01*
G03X1174252Y481510I3576J-1625D01*
G01Y481439D01*
Y481433D01*
X1174254Y481360D01*
G02X1174207Y481310I-167J110D01*
G01X1174091Y481226D01*
X1174089D01*
X1173965Y481135D01*
G02X1173951Y481125I-123J158D01*
G01X1173926Y481110D01*
G02X1173800Y481083I-103J172D01*
G01X1173770Y481086D01*
X1173751Y481092D01*
X1173748Y481093D01*
G03X1173281Y481168I-469J-1427D01*
G01X1173249D01*
G03X1173011Y481145I25J-1502D01*
G01X1172982Y481139D01*
G03X1170878Y481750I-2103J-3315D01*
G03X1168776Y481141I-2J-3926D01*
G01X1168768D01*
G02X1168755Y481142I9J200D01*
G03X1168496Y481168I-279J-1476D01*
G01X1168478D01*
G03X1166976Y479687I0J-1502D01*
G01Y479665D01*
G03X1167121Y479020I1502J-1D01*
G01X1167128Y478990D01*
G03X1167021Y478561I3750J-1163D01*
G03X1166952Y477824I3857J-733D01*
G03X1167304Y476198I3928J-1D01*
G02Y476050I-186J-74D01*
G03X1166952Y474424I3576J-1625D01*
G03X1167067Y473478I3926J-3D01*
G03X1167128Y473258I3812J939D01*
G01X1167127Y473253D01*
X1167122Y473230D01*
G03X1166977Y472631I1357J-645D01*
G01Y472629D01*
G03X1166976Y472595I1501J-61D01*
G01Y472579D01*
G03X1168442Y471077I1502J0D01*
G01X1168480Y471076D01*
X1168481D01*
G03X1168741Y471098I4J1504D01*
G01X1168780Y471105D01*
G03X1170878Y470498I2097J3319D01*
G03X1172971Y471102I1J3926D01*
G01X1173005D01*
G03X1173278Y471077I273J1478D01*
G01X1173311D01*
G03X1173744Y471151I-34J1502D01*
G01X1173760Y471156D01*
X1173817Y471165D01*
G02X1173984Y471108I26J-198D01*
G01X1174014Y471078D01*
G03X1174037Y471058I142J140D01*
G01X1174208Y470934D01*
G02X1174254Y470885I-121J-159D01*
G01X1174252Y470812D01*
Y470737D01*
G03X1174604Y469111I3928J-1D01*
G02Y468963I-186J-74D01*
G03X1174252Y467337I3576J-1625D01*
G03X1174367Y466391I3926J-3D01*
G03X1174428Y466171I3812J939D01*
G01X1174427Y466166D01*
X1174422Y466143D01*
G03X1174276Y465496I1356J-646D01*
G01Y465492D01*
G03X1175778Y463990I1502J0D01*
G01X1175797D01*
G03X1176053Y464015I-17J1502D01*
G01X1176078Y464019D01*
G03X1178178Y463410I2100J3318D01*
G03X1179078Y463515I-2J3927D01*
G03X1180227Y463988I-901J3822D01*
G02X1180349Y464007I90J-179D01*
G01X1180351D01*
G03X1180386Y464002I230J1484D01*
G03X1180441Y463996I190J1490D01*
G01X1180500Y463991D01*
G03X1180571Y463989I78J1501D01*
G01X1180578D01*
G03X1181600Y464391I-1J1502D01*
G03X1181749Y464551I-1022J1101D01*
G01X1181787Y464572D01*
G03X1182089Y464611I-352J3911D01*
G03X1182799Y464802I-661J3871D01*
G01X1182802Y464803D01*
G03X1182829Y464813I-1350J3687D01*
G01X1182855Y464815D01*
G02X1182915Y464812I20J-199D01*
G01X1187733Y463768D01*
X1187753Y463763D01*
X1187754D01*
X1187815Y463748D01*
X1187817D01*
X1188329Y463618D01*
G02X1188393Y463589I-49J-194D01*
G01X1188410Y463577D01*
X1188434Y463553D01*
X1188478Y463501D01*
G02X1188510Y463446I-155J-127D01*
G01X1188521Y463417D01*
X1188523Y463385D01*
G03X1190046Y461953I1523J94D01*
G03X1191359Y462701I0J1526D01*
G01X1191366Y462713D01*
X1191379Y462734D01*
X1191419Y462765D01*
G02X1191574Y462798I116J-163D01*
G01X1218713Y455943D01*
G02X1218824Y455869I-49J-194D01*
G01Y426536D01*
X1218804Y426517D01*
G03X1218798Y426510I148J-133D01*
G01X1218791Y426501D01*
X1215615Y423325D01*
G03X1215244Y422429I896J-896D01*
G01Y376743D01*
G02X1215243Y376721I-200J-2D01*
G02X1215228Y376665I-199J23D01*
G01X1215214Y376633D01*
X1215188Y376606D01*
G03X1215178Y376594I147J-133D01*
G01X1215171Y376585D01*
X1208468Y369882D01*
G03X1208173Y369418I896J-895D01*
G01Y369413D01*
X1208148Y369347D01*
G03X1208141Y369321I189J-65D01*
G01Y369320D01*
X1208139Y369310D01*
X1208136Y369299D01*
G03X1208098Y368986I1229J-308D01*
G01Y360896D01*
G02X1208088Y360834I-200J0D01*
G02X1208084Y360822I-192J57D01*
G01X1208070Y360788D01*
X1208042Y360759D01*
X1208038Y360754D01*
X1208032Y360747D01*
X1178020Y330736D01*
G03X1177769Y330378I896J-895D01*
G03X1177722Y330264I1146J-539D01*
G01X1177709Y330225D01*
X1177700Y330201D01*
G03X1177697Y330191I190J-62D01*
G02X1177693Y330181I-187J69D01*
G01X1177692Y330178D01*
G03X1177636Y329983I1224J-457D01*
G03X1177610Y329720I1280J-259D01*
G01Y321004D01*
X1177594Y320987D01*
G03X1177591Y320983I156J-120D01*
G01X1177584Y320975D01*
X1176690Y320081D01*
G02X1176560Y320023I-141J142D01*
G01X1176537D01*
X1176415Y320030D01*
X1176240Y320040D01*
G02X1176187Y320051I14J199D01*
G01X1176185D01*
G02X1176159Y320062I65J189D01*
G01X1176122Y320081D01*
X1176095Y320114D01*
G03X1174930Y320669I-1166J-946D01*
G01X1174927D01*
G03X1174925I-1J-1504D01*
G03X1174227Y320497I0J-1504D01*
G02X1174134Y320474I-93J177D01*
G01X1171508D01*
G03X1171319Y320460I2J-1307D01*
G01X1171317D01*
G03X1171211Y320439I201J-1291D01*
G01X1171188Y320434D01*
X1168994D01*
G03X1168098Y320063I0J-1267D01*
G01X1151626Y303591D01*
G03X1151567Y303449I141J-142D01*
G01Y264431D01*
G02X1151559Y264375I-200J0D01*
G02X1151553Y264357I-193J54D01*
G01X1151538Y264321D01*
X1147215Y259998D01*
G02X1147165Y259962I-140J142D01*
G02X1147074Y259940I-91J178D01*
G01X1111888D01*
G02X1111832Y259948I0J200D01*
G02X1111814Y259954I54J193D01*
G01X1111778Y259969D01*
X1111732Y260015D01*
X1111696Y260030D01*
G03X1111620Y260045I-76J-185D01*
G01X1099335D01*
G03X1099193Y259986I0J-200D01*
G01X1097017Y257810D01*
G02X1096978Y257780I-140J142D01*
G01X1096951Y257764D01*
X1096924Y257757D01*
G03X1095799Y256329I377J-1454D01*
G01X1095798Y256290D01*
X1095778Y256243D01*
G02X1095740Y256189I-180J86D01*
G01X1095045Y255494D01*
G02X1094995Y255458I-140J142D01*
G02X1094904Y255436I-91J178D01*
G01X1093635D01*
G02X1093579Y255444I0J200D01*
G02X1093561Y255450I54J193D01*
G01X1093525Y255465D01*
X1089214Y259776D01*
G03X1088751Y260071I-896J-896D01*
G01X1088709Y260085D01*
X1088679Y260096D01*
G03X1088651Y260104I-69J-188D01*
G01X1088644Y260105D01*
X1088632Y260108D01*
X1088627Y260109D01*
G03X1088319Y260147I-308J-1229D01*
G01X1088296D01*
X1088287Y260146D01*
X1087702D01*
X1087679Y260151D01*
G03X1087379Y260186I-300J-1271D01*
G01X1075267D01*
X1075250Y260195D01*
G03X1074524Y260382I-726J-1317D01*
G01X1074522D01*
G03Y257378I0J-1502D01*
G01X1074523D01*
G03X1075254Y257568I-1J1504D01*
G01X1075265Y257574D01*
X1086754D01*
G02X1086797Y257569I-1J-200D01*
G02X1086895Y257516I-42J-195D01*
G01X1093333Y251077D01*
G03X1094257Y250694I924J923D01*
G01X1094778D01*
X1094809Y250679D01*
G03X1095048Y250584I585J1125D01*
G01X1095059Y250582D01*
X1095070Y250579D01*
G03X1095392Y250536I327J1225D01*
G01X1103812D01*
G02X1103918Y250503I-4J-200D01*
G01X1103945Y250484D01*
G02X1103963Y250468I-124J-157D01*
G02X1104014Y250379I-142J-141D01*
G01X1104028Y250328D01*
X1104045Y250287D01*
X1104063Y250240D01*
G03X1104100Y250180I186J74D01*
G01X1104104Y250175D01*
G02X1104149Y250077I-152J-129D01*
G01X1104153Y250050D01*
X1104150Y250023D01*
G02X1104134Y249967I-198J26D01*
G01X1104100Y249891D01*
Y249889D01*
X1104082Y249848D01*
X1104056Y249821D01*
G03X1104055Y249820I1062J-1063D01*
G03X1104053Y249818I140J-142D01*
G03X1103623Y248773I1072J-1052D01*
G01Y248741D01*
G03X1105069Y247264I1502J24D01*
G01X1105070D01*
G03X1105125Y247263I55J1501D01*
G01X1105127D01*
G03X1106061Y247590I-1J1501D01*
G01X1106087Y247610D01*
X1106131Y247625D01*
G02X1106184Y247633I56J-192D01*
G01X1106270D01*
G03X1106326Y247641I0J200D01*
G01X1106340Y247644D01*
X1106552D01*
G02X1106677Y247600I0J-200D01*
G01X1106678Y247599D01*
G03X1106681Y247597I835J1249D01*
G03X1106699Y247583I931J1178D01*
G02X1106709Y247575I-120J-160D01*
G03X1106712Y247572I1062J1059D01*
G03X1106758Y247539I898J1204D01*
G02X1106760Y247537I-140J-142D01*
G03X1106798Y247511I867J1226D01*
G03X1106800Y247509I142J140D01*
G03X1107122Y247349I824J1255D01*
G03X1107125Y247348I64J186D01*
G01X1107140Y247343D01*
G03X1107484Y247269I486J1422D01*
G01X1107486D01*
G03X1107543Y247265I134J1496D01*
G01X1107546D01*
G03X1107561Y247264I107J1497D01*
G01X1107627Y247261D01*
X1107676Y247264D01*
G03X1108559Y247589I-51J1501D01*
G01X1108560Y247590D01*
X1108572Y247600D01*
G02X1108678Y247633I110J-167D01*
G01X1108770D01*
G03X1108853Y247651I0J200D01*
G01X1108907Y247676D01*
G02X1108985Y247695I85J-181D01*
G02X1109019Y247693I5J-200D01*
G02X1109123Y247645I-28J-198D01*
G01X1109124Y247644D01*
G03X1110123Y247263I1000J1122D01*
G01X1110125D01*
G03X1111627Y248765I0J1502D01*
G03X1111194Y249820I-1502J0D01*
G01X1111193Y249821D01*
X1111169Y249846D01*
X1111135Y249919D01*
G02X1111132Y249930I191J58D01*
G01X1111117Y249997D01*
G02X1111125Y250089I198J29D01*
G01X1111200Y250273D01*
Y250275D01*
X1111261Y250421D01*
G02X1111288Y250464I182J-84D01*
G02X1111442Y250536I154J-128D01*
G01X1115762D01*
G02X1115788Y250534I-2J-200D01*
G01X1116523Y249800D01*
G02X1116565Y249739I-141J-142D01*
G02X1116582Y249657I-183J-81D01*
G01Y229061D01*
G02X1116560Y228970I-200J0D01*
G02X1116524Y228920I-178J90D01*
G01X1115256Y227652D01*
G03X1114971Y227216I895J-896D01*
G02X1114948Y227173I-186J72D01*
G02X1114944Y227167I-168J108D01*
G03X1114682Y226382I1045J-785D01*
G01Y222748D01*
G02X1114602Y222685I-160J120D01*
G01X1114238Y222552D01*
G02X1114118Y222546I-70J187D01*
G01X1114089Y222554D01*
X1114037Y222587D01*
X1114017Y222611D01*
G03X1112868Y223144I-1149J-972D01*
G03Y220140I0J-1502D01*
G03X1113995Y220648I0J1504D01*
G01X1114018Y220674D01*
X1114080Y220715D01*
G02X1114237Y220733I99J-174D01*
G01X1114460Y220652D01*
X1114591Y220604D01*
G02X1114682Y220536I-69J-188D01*
G01Y216982D01*
G03X1115065Y216058I1306J0D01*
G01X1122640Y208483D01*
X1122665Y208441D01*
X1122672Y208418D01*
G03X1125542I1435J446D01*
G01X1125549Y208441D01*
X1125574Y208483D01*
X1128025Y210934D01*
G03X1128026Y210935I-923J924D01*
G03X1128217Y211177I-923J925D01*
G02X1128219Y211181I180J-87D01*
G01X1128238Y211205D01*
G03X1128558Y212047I-948J842D01*
G01Y216195D01*
G02X1128625Y216344I200J0D01*
G01X1128687Y216399D01*
X1128856Y216549D01*
G02X1128916Y216582I125J-156D01*
G01X1128957Y216596D01*
X1128988Y216592D01*
G03X1129156Y216583I164J1493D01*
G01X1129165D01*
G03X1130235Y217040I-9J1502D01*
G01X1130263Y217069D01*
X1130378Y217119D01*
G02X1130446Y217133I74J-186D01*
G01X1130661D01*
X1130700Y217126D01*
X1130738Y217118D01*
X1130849Y217069D01*
X1130876Y217041D01*
G03X1131956Y216583I1080J1044D01*
G03Y219587I0J1502D01*
G03X1130877Y219130I0J-1502D01*
G01X1130849Y219101D01*
X1130734Y219051D01*
G02X1130666Y219037I-74J186D01*
G01X1130473D01*
G02X1130433Y219041I0J200D01*
G01X1130390Y219050D01*
X1130368Y219054D01*
X1130263Y219101D01*
X1130236Y219130D01*
G03X1129754Y219463I-1079J-1046D01*
G01X1129723Y219477D01*
X1129700Y219497D01*
G02X1129666Y219537I134J149D01*
G01X1129615Y219626D01*
Y219627D01*
X1129604Y219646D01*
G02X1129578Y219763I173J100D01*
G01X1129579Y219781D01*
G03X1129582Y219875I-1265J87D01*
G01Y220018D01*
X1129587Y220041D01*
G03X1129608Y220147I-1270J307D01*
G01Y220149D01*
G03X1129622Y220338I-1293J191D01*
G01Y240420D01*
G02X1129629Y240429I161J-118D01*
G01X1132906Y243707D01*
G03X1133201Y244171I-896J895D01*
G01Y244176D01*
X1133226Y244242D01*
G03X1133232Y244262I-188J67D01*
G01X1133234Y244272D01*
X1133236Y244280D01*
G03X1133276Y244602I-1227J316D01*
G01Y247400D01*
G02X1133382Y247562I200J-15D01*
G01X1133646Y247732D01*
G02X1133648Y247733I90J-178D01*
G03X1133656Y247737I-85J181D01*
G02X1133692Y247753I99J-174D01*
G01X1133711Y247758D01*
G02X1133792Y247759I43J-195D01*
G01X1133796Y247758D01*
X1133845Y247748D01*
X1133865Y247739D01*
G03X1134483Y247606I618J1369D01*
G03X1135985Y249108I0J1502D01*
G03X1134504Y250610I-1502J0D01*
G01X1134475D01*
G03X1133874Y250485I-1J-1503D01*
G01X1133836Y250468D01*
X1133733D01*
G02X1133631Y250496I0J200D01*
G01X1133483Y250590D01*
X1133386Y250652D01*
G02X1133353Y250679I110J168D01*
G01X1133308Y250724D01*
G02X1133301Y250735I165J113D01*
G01Y250737D01*
G02X1133276Y250832I175J97D01*
G01Y252075D01*
G02X1133280Y252112I200J-3D01*
G01Y252114D01*
G02X1133333Y252215I196J-39D01*
G01X1135665Y254547D01*
G02X1135766Y254600I140J-143D01*
G01X1135768D01*
G02X1135805Y254604I40J-196D01*
G01X1145976D01*
G02X1145992Y254603I-4J-200D01*
G01X1145994D01*
G02X1146149Y254505I-17J-199D01*
G01X1146204Y254405D01*
X1146320Y254195D01*
G02X1146345Y254098I-175J-97D01*
G01Y254040D01*
X1146315Y253992D01*
G03X1146088Y253198I1275J-794D01*
G03X1149092I1502J0D01*
G03X1148865Y253992I-1502J0D01*
G01X1148849Y254017D01*
X1148835Y254065D01*
Y254105D01*
G02X1148859Y254193I200J-7D01*
G01X1148914Y254292D01*
Y254294D01*
X1149035Y254510D01*
G02X1149204Y254604I169J-106D01*
G01X1149898D01*
G02X1149930Y254601I-3J-200D01*
G01X1149932D01*
G02X1150037Y254548I-34J-197D01*
G01X1151434Y253150D01*
G02X1151492Y253009I-142J-141D01*
G01Y248433D01*
G02X1151467Y248337I-200J1D01*
G01X1151443Y248293D01*
X1151416Y248275D01*
G02X1151308Y248243I-109J168D01*
G01X1151203D01*
X1151166Y248259D01*
G03X1150584Y248376I-581J-1386D01*
G01X1150578D01*
G03X1150515Y248375I-8J-1502D01*
G01X1150479Y248373D01*
G03X1149146Y246423I100J-1499D01*
G03X1150572Y245372I1433J451D01*
G01X1150581D01*
G03X1150677Y245375I1J1502D01*
G01X1150680D01*
X1150687Y245376D01*
X1150693D01*
G03X1150815Y245390I-110J1498D01*
G03X1151202Y245507I-237J1484D01*
G01X1151203Y245508D01*
X1151204D01*
G03X1151209Y245510I-555J1396D01*
G01X1151249Y245529D01*
X1151291D01*
G02X1151398Y245498I0J-200D01*
G01X1151399Y245497D01*
G02X1151492Y245328I-107J-169D01*
G01Y245096D01*
G02X1151469Y245003I-200J0D01*
G03X1151297Y244321I1331J-698D01*
G01Y244284D01*
G03X1152786Y242795I1502J13D01*
G01X1152822D01*
G03X1153505Y242967I-15J1503D01*
G02X1153598Y242990I93J-177D01*
G01X1154179D01*
G02X1154319Y242933I0J-200D01*
G01X1154979Y242273D01*
X1156315Y240938D01*
G02X1156374Y240799I-141J-142D01*
G01Y231656D01*
G02X1156315Y231603I-160J119D01*
G01X1156195Y231533D01*
X1156020Y231431D01*
G02X1155882Y231412I-95J176D01*
G01X1155819Y231427D01*
X1155797Y231439D01*
G03X1155084Y231619I-713J-1322D01*
G01X1155082D01*
G03Y228615I0J-1502D01*
G01X1155085D01*
G03X1155807Y228800I0J1503D01*
G03X1155814Y228804I-96J176D01*
G01X1155851Y228826D01*
X1155893Y228831D01*
X1155895D01*
G02X1155972Y228825I23J-199D01*
G01X1156004Y228815D01*
X1156030Y228798D01*
X1156315Y228631D01*
G02X1156374Y228578I-101J-172D01*
G01Y216099D01*
G02X1156261Y215919I-200J0D01*
G01X1156249Y215914D01*
G02X1156131Y215903I-77J185D01*
G01X1156105Y215908D01*
X1156055Y215935D01*
X1142963Y229027D01*
X1142938Y229069D01*
X1142931Y229092D01*
G03X1141496Y230148I-1435J-447D01*
G03X1139994Y228646I0J-1502D01*
G01X1139993D01*
G03X1141050Y227211I1503J0D01*
G01X1141051D01*
G02X1141133Y227161I-60J-191D01*
G01X1154826Y213469D01*
G02X1154876Y213384I-142J-141D01*
G02X1154884Y213328I-192J-56D01*
G01Y181700D01*
G02X1154862Y181609I-200J0D01*
G02X1154826Y181559I-178J90D01*
G01X1132001Y158734D01*
G02X1131951Y158698I-140J142D01*
G02X1131860Y158676I-91J178D01*
G01X1120736D01*
X1120719Y158685D01*
G03X1119993Y158872I-726J-1317D01*
G01X1119991D01*
G03Y155868I0J-1502D01*
G01X1119992D01*
G03X1120723Y156058I-1J1504D01*
G01X1120734Y156064D01*
X1130842D01*
G02X1131027Y155940I0J-200D01*
G01X1131033Y155927D01*
X1131039Y155912D01*
X1131045Y155853D01*
X1131039Y155825D01*
G02X1130985Y155724I-196J40D01*
G01X1117873Y142612D01*
G02X1117823Y142576I-140J142D01*
G02X1117732Y142554I-91J178D01*
G01X1113931D01*
G02X1113896Y142586I117J163D01*
G01X1113768Y142763D01*
X1113703Y142854D01*
G02X1113670Y142960I167J110D01*
G01Y143039D01*
X1113679Y143069D01*
G03X1113748Y143518I-1433J450D01*
G03X1112246Y145020I-1502J0D01*
G03X1110744Y143529I0J-1502D01*
G01Y143515D01*
G03X1110813Y143066I1502J1D01*
G01X1110816Y143056D01*
X1110822Y143037D01*
X1110828Y142986D01*
G02X1110797Y142864I-199J-14D01*
G01X1110722Y142759D01*
X1110600Y142590D01*
G02X1110563Y142554I-157J124D01*
G01X1108505D01*
X1108482Y142566D01*
X1108469Y142572D01*
G03X1107762Y142749I-708J-1327D01*
G01X1107759D01*
G03Y139745I0J-1502D01*
G01X1107762D01*
G03X1108469Y139922I-1J1504D01*
G01X1108482Y139928D01*
X1108505Y139940D01*
X1116715D01*
G02X1116890Y139835I-1J-200D01*
G01X1116898Y139815D01*
G02X1116910Y139699I-184J-78D01*
G01X1116905Y139673D01*
X1116877Y139621D01*
X1107678Y130422D01*
G03X1107296Y129500I924J-923D01*
G01Y116898D01*
G03X1107678Y115976I1306J1D01*
G01X1109924Y113730D01*
G02X1109974Y113533I-142J-141D01*
G01X1109965Y113512D01*
G02X1109892Y113422I-185J76D01*
G01X1109870Y113407D01*
X1109813Y113390D01*
X1099501D01*
G03X1098577Y113007I0J-1306D01*
G01X1094546Y108975D01*
G02X1094434Y108920I-140J143D01*
G02X1094406Y108918I-28J198D01*
G01X1090289D01*
G03X1089367Y108536I1J-1306D01*
G01X1085618Y104786D01*
G02X1085362Y104766I-140J143D01*
G02X1085194Y105091I232J326D01*
G01Y107649D01*
G03X1081588I-1803J0D01*
G01Y104249D01*
G03X1082782Y102551I1804J0D01*
G01X1082823Y102536D01*
X1082883Y102478D01*
X1082896Y102463D01*
G02X1082933Y102394I-155J-127D01*
G01X1082944Y102345D01*
Y102343D01*
X1083008Y102061D01*
G02X1082986Y101931I-197J-33D01*
G01X1082966Y101900D01*
X1081410Y100344D01*
G02X1081390Y100327I-139J144D01*
G01X1081223Y100209D01*
X1080791Y99905D01*
G02X1080676Y99868I-116J163D01*
G01X1074429D01*
X1074416D01*
G02X1074289Y99925I13J200D01*
G01X1073998Y100217D01*
X1073873Y100342D01*
X1073848Y100384D01*
X1073841Y100407D01*
G03X1072406Y101463I-1435J-447D01*
G03X1070904Y99961I0J-1502D01*
G01X1070903D01*
G03X1071960Y98526I1503J0D01*
G01X1071961D01*
G02X1072043Y98476I-60J-191D01*
G01X1072210Y98309D01*
G02Y98252I-198J-29D01*
G01X1070825Y96867D01*
G03X1070182Y95624I1631J-1631D01*
G01X1070166Y95527D01*
G02X1070093Y95482I-139J144D01*
G01X1069829Y95398D01*
X1069827D01*
X1069779Y95383D01*
G02X1069745Y95376I-57J192D01*
G02X1069719Y95374I-28J198D01*
G01X1069697D01*
X1069661Y95389D01*
G02X1069596Y95432I76J185D01*
G01X1068868Y96160D01*
G03X1067946Y96542I-923J-924D01*
G01X1063268D01*
X1063251Y96551D01*
G03X1062525Y96738I-726J-1317D01*
G01X1062523D01*
G03Y93734I0J-1502D01*
G01X1062524D01*
G03X1063255Y93924I-1J1504D01*
G01X1063266Y93930D01*
X1067320D01*
X1067333D01*
G02X1067460Y93873I-13J-200D01*
G01X1067775Y93557D01*
X1067929Y93403D01*
G02X1067930Y93349I-198J-31D01*
G02X1067922Y93314I-198J27D01*
G01X1067885Y93203D01*
Y93201D01*
X1067801Y92928D01*
X1067772Y92902D01*
X1067675Y92885D01*
G03X1065930Y91437I410J-2270D01*
G01X1065897Y91351D01*
G02X1065828Y91322I-111J166D01*
G01X1065634Y91281D01*
X1065632D01*
X1065491Y91251D01*
G02X1065435Y91252I-24J199D01*
G01X1064405Y92282D01*
G03X1062773Y92958I-1632J-1632D01*
G03X1060465Y90650I0J-2308D01*
G03X1061141Y89018I2308J0D01*
G01X1063121Y87038D01*
G03X1064753Y86362I1632J1632D01*
G03X1064837Y86364I-13J2308D01*
G01X1079711D01*
G02X1079882Y86268I0J-200D01*
G01X1079929Y86191D01*
Y86189D01*
X1079990Y86087D01*
G02X1080009Y86040I-174J-98D01*
G02X1080015Y85994I-194J-49D01*
G01X1080016Y85948D01*
X1079994Y85901D01*
X1079992Y85897D01*
G03X1079818Y85197I1328J-702D01*
G01Y85180D01*
G03X1080224Y84166I1502J13D01*
G01X1080251Y84138D01*
X1080265Y84103D01*
G02X1080275Y84067I-187J-71D01*
G02X1080278Y84032I-197J-35D01*
G01Y83755D01*
G02X1080268Y83691I-200J-1D01*
G02X1080265Y83684I-185J75D01*
G01X1080252Y83650D01*
X1080224Y83620D01*
G03Y81566I1096J-1027D01*
G01X1080252Y81536D01*
X1080265Y81502D01*
G02X1080268Y81495I-182J-82D01*
G02X1080278Y81431I-190J-63D01*
G01Y81155D01*
G02X1080268Y81091I-200J-1D01*
G02X1080265Y81084I-185J75D01*
G01X1080252Y81050D01*
X1080224Y81020D01*
G03Y78966I1096J-1027D01*
G01X1080252Y78936D01*
X1080265Y78902D01*
G02X1080268Y78895I-182J-82D01*
G02X1080278Y78831I-190J-63D01*
G01Y78555D01*
G02X1080268Y78491I-200J-1D01*
G02X1080265Y78484I-185J75D01*
G01X1080252Y78450D01*
X1080224Y78420D01*
G03Y76366I1096J-1027D01*
G01X1080252Y76336D01*
X1080265Y76302D01*
G02X1080268Y76295I-182J-82D01*
G02X1080278Y76231I-190J-63D01*
G01Y75955D01*
G02X1080268Y75891I-200J-1D01*
G02X1080265Y75884I-185J75D01*
G01X1080252Y75850D01*
X1080224Y75820D01*
G03X1079818Y74793I1096J-1027D01*
G03X1082822I1502J0D01*
G03X1082416Y75820I-1502J0D01*
G01X1082388Y75850D01*
X1082375Y75884D01*
G02X1082372Y75891I182J82D01*
G02X1082362Y75955I190J63D01*
G01Y76231D01*
G02X1082372Y76295I200J1D01*
G02X1082375Y76302I185J-75D01*
G01X1082388Y76336D01*
X1082416Y76366D01*
G03Y78420I-1096J1027D01*
G01X1082388Y78450D01*
X1082375Y78484D01*
G02X1082372Y78491I182J82D01*
G02X1082362Y78555I190J63D01*
G01Y78831D01*
G02X1082372Y78895I200J1D01*
G02X1082375Y78902I185J-75D01*
G01X1082388Y78936D01*
X1082416Y78966D01*
G03Y81020I-1096J1027D01*
G01X1082388Y81050D01*
X1082375Y81084D01*
G02X1082372Y81091I182J82D01*
G02X1082362Y81155I190J63D01*
G01Y81431D01*
G02X1082372Y81495I200J1D01*
G02X1082375Y81502I185J-75D01*
G01X1082388Y81536D01*
X1082416Y81566D01*
G03Y83620I-1096J1027D01*
G01X1082388Y83650D01*
X1082375Y83684D01*
G02X1082372Y83691I182J82D01*
G02X1082362Y83755I190J63D01*
G01Y84032D01*
G02X1082365Y84067I200J0D01*
G02X1082375Y84103I197J-35D01*
G01X1082389Y84138D01*
X1082418Y84168D01*
G03X1082822Y85179I-1098J1025D01*
G01Y85195D01*
G03X1082648Y85897I-1502J0D01*
G01X1082642Y85908D01*
G02X1082625Y85993I183J81D01*
G01X1082626Y86046D01*
X1082711Y86189D01*
Y86191D01*
X1082758Y86268D01*
G02X1082929Y86364I171J-104D01*
G01X1100247D01*
G02X1100361Y86329I1J-200D01*
G02X1100377Y86316I-118J-162D01*
G01X1101688Y85005D01*
G02X1101690Y84976I-198J-28D01*
G01Y84913D01*
X1101678Y84867D01*
X1101661Y84834D01*
G03X1101491Y84143I1332J-694D01*
G01Y84110D01*
G03X1102993Y82638I1502J30D01*
G01X1102994D01*
G03X1103057Y82639I8J1502D01*
G01X1103099Y82641D01*
X1103135Y82627D01*
G02X1103198Y82589I-70J-187D01*
G01X1103252Y82538D01*
G02X1103254Y82536I-140J-142D01*
G01X1103419Y82377D01*
G02X1103434Y82359I-146J-137D01*
G01Y76586D01*
G03X1104225Y74849I2307J2D01*
G01X1104267Y74812D01*
X1104275Y74795D01*
G02X1104293Y74717I-182J-83D01*
G01X1104299Y74497D01*
Y74494D01*
X1104301Y74437D01*
X1104110Y74247D01*
G03X1103610Y73498I1632J-1631D01*
G03X1103434Y72622I2131J-884D01*
G01Y72615D01*
G03X1105741Y70308I2307J0D01*
G01X1105778D01*
G03X1106624Y70484I-39J2307D01*
G03X1107373Y70984I-882J2132D01*
G01X1108675Y72287D01*
X1109611Y73223D01*
G03X1110286Y74853I-1631J1630D01*
G01Y84546D01*
G02X1110341Y84596I160J-120D01*
G01X1110364Y84610D01*
X1110708Y84754D01*
G02X1110817Y84767I77J-184D01*
G01X1113137Y82447D01*
G02Y82387I-198J-30D01*
G01Y82384D01*
X1113116Y82254D01*
X1113085Y82059D01*
G02X1112980Y81922I-196J41D01*
G01X1112953Y81908D01*
G03X1112157Y80581I708J-1327D01*
G03X1113659Y79079I1502J0D01*
G03X1115161Y80572I0J1502D01*
G01Y80582D01*
G03X1115085Y81054I-1502J0D01*
G01X1115079Y81072D01*
X1115074Y81108D01*
Y81109D01*
X1115068Y81147D01*
X1115080Y81194D01*
G02X1115104Y81248I193J-53D01*
G01X1115171Y81341D01*
X1115214Y81400D01*
G02X1115238Y81429I165J-112D01*
G02X1115362Y81484I138J-145D01*
G01X1121449D01*
G03X1123080Y82160I-1J2307D01*
G01X1125334Y84414D01*
G03X1126010Y86045I-1631J1632D01*
G01Y86102D01*
X1126009Y86125D01*
G03X1123703Y88352I-2305J-79D01*
G03X1122072Y87677I-1J-2306D01*
G01X1121793Y87398D01*
G02X1121754Y87396I-30J198D01*
G01X1121633Y87497D01*
G03X1120149Y88038I-1484J-1765D01*
G01X1119528D01*
G02X1119492Y88073I120J160D01*
G01X1119419Y88164D01*
X1119289Y88325D01*
G02X1119279Y88341I165J114D01*
G02X1119264Y88377I176J95D01*
G01X1119248Y88439D01*
X1119258Y88484D01*
G03X1119291Y88791I-1469J313D01*
G03Y88793I-1502J1D01*
G01Y88816D01*
G03X1117965Y90293I-1502J-15D01*
G01X1117909Y90299D01*
G03X1117778Y90304I-123J-1498D01*
G01X1117770D01*
G03X1116858Y89980I20J-1502D01*
G03X1116792Y89925I928J-1181D01*
G01X1116786Y89920D01*
X1116779Y89914D01*
X1116747Y89893D01*
G02X1116569Y89878I-104J170D01*
G01X1116475Y89919D01*
X1116473D01*
X1116233Y90026D01*
G02X1116225Y90030I85J181D01*
G01X1116171Y90057D01*
X1116152Y90088D01*
Y102018D01*
G02X1116163Y102083I200J0D01*
G01X1116173Y102112D01*
X1116191Y102136D01*
X1116293Y102167D01*
G03X1116948Y102576I-452J1453D01*
G03X1117310Y103218I-1105J1046D01*
G01X1117319Y103250D01*
X1121037Y106968D01*
G03X1121420Y107892I-923J924D01*
G01Y118873D01*
G03X1121037Y119797I-1306J0D01*
G01X1117206Y123627D01*
G02X1117151Y123733I142J141D01*
G02X1117148Y123768I197J35D01*
G01Y125874D01*
G02X1117188Y125994I200J0D01*
G01X1139882Y148689D01*
G02X1139955Y148685I26J-198D01*
G01X1140074Y148649D01*
X1140076D01*
X1140266Y148590D01*
G02X1140336Y148543I-74J-186D01*
G01X1140375Y148500D01*
X1140377Y148498D01*
X1140409Y148463D01*
G02X1140434Y148425I-154J-128D01*
G01X1140447Y148400D01*
X1140451Y148384D01*
X1140453Y148374D01*
G03X1141916Y147215I1463J344D01*
G03X1143418Y148717I0J1502D01*
G03X1142259Y150180I-1503J0D01*
G01X1142258D01*
X1142230Y150187D01*
X1142189Y150208D01*
X1142162Y150232D01*
X1142161Y150233D01*
X1142135Y150256D01*
X1142133Y150258D01*
X1142090Y150297D01*
G02X1142043Y150367I139J144D01*
G01X1141984Y150557D01*
Y150559D01*
X1141948Y150678D01*
G02X1141944Y150751I194J47D01*
G01X1165835Y174642D01*
G02X1165936Y174687I129J-153D01*
G02X1166392Y174292I56J-396D01*
G01Y174009D01*
G02X1166390Y173982I-200J1D01*
G01X1147131Y154723D01*
G03X1146748Y153799I923J-924D01*
G01Y144624D01*
G02X1146747Y144609I-200J6D01*
G02X1146735Y144554I-199J15D01*
G02X1146721Y144523I-189J67D01*
G03X1146649Y144386I1292J-766D01*
G01Y144384D01*
G03X1146609Y144290I1361J-635D01*
G01X1146604Y144275D01*
X1146593Y144243D01*
X1146592Y144241D01*
X1146589Y144231D01*
X1146588Y144228D01*
G03X1146585Y144219I1423J-479D01*
G02X1146583Y144213I-191J60D01*
G03X1146580Y144205I1404J-531D01*
G01X1146576Y144193D01*
G02X1146571Y144181I-187J71D01*
G02X1146532Y144126I-180J87D01*
G01X1140664Y138258D01*
G03X1140282Y137336I924J-923D01*
G01Y127603D01*
G02X1140249Y127568I-161J119D01*
G01X1140108Y127452D01*
X1140106Y127450D01*
X1140014Y127375D01*
G02X1139965Y127345I-128J154D01*
G01X1139881Y127363D01*
G03X1139402Y127414I-482J-2256D01*
G01X1139218D01*
Y127407D01*
G03X1137096Y125109I184J-2299D01*
G01Y121166D01*
G02X1137085Y121153I-158J123D01*
G01X1137067Y121133D01*
X1137054Y121125D01*
X1137016Y121102D01*
X1137014Y121101D01*
X1136750Y120938D01*
G02X1136644Y120908I-105J170D01*
G01X1136596Y120909D01*
X1136553Y120931D01*
X1136527Y120944D01*
X1136508Y120961D01*
G03X1136459Y120993I-133J-150D01*
G03X1136442Y121000I-85J-181D01*
G02X1136434Y121003I66J189D01*
G03X1135868Y121113I-567J-1409D01*
G03X1134349Y119594I0J-1519D01*
G03X1134905Y118421I1515J0D01*
G01X1134907Y118419D01*
X1134929Y118400D01*
X1134945Y118387D01*
X1134959Y118371D01*
G02X1134982Y118336I-155J-127D01*
G01X1135008Y118280D01*
G02X1135022Y118207I-186J-74D01*
G01Y117983D01*
G02X1135004Y117900I-200J0D01*
G01X1134991Y117873D01*
Y117871D01*
X1134964Y117817D01*
G02X1134931Y117772I-176J95D01*
G01X1134912Y117753D01*
X1134905Y117747D01*
G03X1134366Y116594I964J-1153D01*
G03X1135868Y115092I1502J0D01*
G03X1136945Y115547I0J1502D01*
G01X1136972Y115575D01*
X1137112Y115637D01*
X1137161Y115635D01*
X1137245Y115631D01*
G02X1137348Y115597I-9J-200D01*
G02X1137397Y115550I-112J-166D01*
G01X1137408Y115532D01*
G03X1137712Y115122I1994J1160D01*
G03X1137771Y115061I1687J1573D01*
G01X1147371Y105461D01*
G02X1147424Y105359I-143J-139D01*
G02X1147428Y105321I-196J-40D01*
G01Y95111D01*
G03X1152042I2307J0D01*
G01Y105214D01*
G02X1152082Y105254I160J-120D01*
G01X1153243D01*
X1153253D01*
G02X1153334Y105232I-11J-200D01*
G03X1153427Y105182I773J1327D01*
G01X1153450Y105171D01*
X1153452Y105170D01*
X1153487Y105140D01*
X1153502Y105119D01*
G02X1153456Y104840I-163J-116D01*
G01X1153433Y104824D01*
X1153409Y104815D01*
G03X1152443Y103411I537J-1404D01*
G03X1155447I1502J0D01*
G03X1154868Y104596I-1502J0D01*
G01X1154850Y104610D01*
X1154813Y104655D01*
G02X1154783Y104704I154J128D01*
G01Y104706D01*
G02X1154767Y104793I184J79D01*
G01X1154772Y104897D01*
Y104899D01*
X1154783Y105081D01*
G02X1154795Y105126I198J-29D01*
G01X1154823Y105177D01*
G02X1154848Y105210I171J-104D01*
G01X1154865Y105228D01*
X1154873Y105233D01*
X1154890Y105243D01*
G03X1155639Y106561I-785J1318D01*
G03X1154104Y108096I-1535J0D01*
G01X1154103D01*
G03X1153341Y107894I0J-1537D01*
G01X1153318Y107881D01*
X1153294Y107875D01*
G02X1153243Y107868I-52J193D01*
G01X1152752D01*
G02X1152611Y107926I0J200D01*
G01X1146496Y114039D01*
X1142913Y117623D01*
G02X1142894Y117645I141J141D01*
G01Y136710D01*
G02X1142896Y136740I200J2D01*
G02X1142951Y136850I198J-30D01*
G01X1146613Y140511D01*
X1148415Y142313D01*
X1148441Y142321D01*
G03X1149518Y143749I-425J1441D01*
G01Y143776D01*
G03X1149491Y144050I-1502J-10D01*
G01X1149486Y144074D01*
G03X1149379Y144397I-1471J-308D01*
G01X1149362Y144434D01*
Y153175D01*
G02X1149366Y153213I200J-2D01*
G02X1149419Y153315I196J-37D01*
G01X1168664Y172560D01*
G03X1169046Y173482I-924J923D01*
G01Y287322D01*
G02X1169058Y287391I200J1D01*
G02X1169104Y287463I188J-69D01*
G01X1198795Y317153D01*
G03X1198924Y317304I-926J922D01*
G03X1198985Y317395I-1054J772D01*
G02X1199007Y317421I163J-116D01*
G01X1200168Y318582D01*
G03X1200463Y319046I-896J895D01*
G01Y319051D01*
X1200488Y319117D01*
G03X1200495Y319143I-189J65D01*
G01Y319144D01*
X1200497Y319154D01*
X1200500Y319165D01*
G03X1200538Y319478I-1229J308D01*
G01Y346728D01*
G02X1200542Y346765I200J-3D01*
G01Y346767D01*
G02X1200595Y346868I196J-39D01*
G01X1220641Y366913D01*
G03X1221012Y367809I-896J896D01*
G01Y368119D01*
G02X1221115Y368294I200J0D01*
G01X1221146Y368310D01*
X1221244Y368343D01*
G02X1221412Y368313I52J-193D01*
G01X1221453Y368281D01*
X1221465Y368267D01*
G03X1222601Y367748I1136J984D01*
G01X1222602D01*
G03X1222724Y367753I0J1503D01*
G01X1222778Y367759D01*
G03X1223689Y368215I-178J1493D01*
G03X1223873Y368451I-1088J1038D01*
G02X1223901Y368486I169J-107D01*
G01X1223922Y368507D01*
G02X1224054Y368565I141J-142D01*
G01X1224124Y368568D01*
X1224375Y368579D01*
G02X1224525Y368521I9J-200D01*
G01X1224545Y368501D01*
X1224552Y368492D01*
X1224558Y368484D01*
G03X1224566Y368475I1123J990D01*
G01Y368474D01*
G03X1225063Y368058I1190J917D01*
G03X1225371Y367939I691J1331D01*
G03X1225644Y367893I385J1449D01*
G01X1225645D01*
G03X1225754Y367889I109J1495D01*
G01X1225755D01*
G03X1226639Y368176I1J1502D01*
G01X1226663Y368194D01*
X1226761Y368228D01*
X1226812Y368232D01*
X1226837Y368228D01*
X1227102Y368184D01*
G02X1227141Y368170I-48J-195D01*
G01X1227184Y368104D01*
G03X1229122Y367048I1938J1250D01*
G03X1229756Y367137I-1J2307D01*
G03X1230754Y367724I-633J2218D01*
G01X1230777Y367748D01*
X1230793Y367764D01*
G03X1231468Y369394I-1631J1630D01*
G01Y451472D01*
G02X1231469Y451490I200J-2D01*
G02X1231523Y451610I199J-17D01*
G01X1232287Y452373D01*
X1232387Y452473D01*
G02X1232447I30J-198D01*
G01X1235107Y451801D01*
X1237591Y451174D01*
G02X1237742Y450980I-49J-194D01*
G01Y334300D01*
G02X1237736Y334253I-200J2D01*
G02X1237684Y334159I-194J46D01*
G01X1229541Y326017D01*
X1229499Y325992D01*
X1229476Y325985D01*
G03X1228420Y324550I447J-1435D01*
G03X1229653Y323072I1502J0D01*
G01X1229688Y323066D01*
X1229782Y323012D01*
G02X1229821Y322981I-104J-171D01*
G01X1229840Y322961D01*
X1229858Y322940D01*
Y320876D01*
G03X1229878Y320573I2307J0D01*
G03X1229887Y320511I2287J300D01*
G01X1229889Y320501D01*
X1229890Y320493D01*
Y316964D01*
G03X1229894Y316833I2307J5D01*
G01Y316831D01*
G03X1229899Y316768I2302J151D01*
G01Y316767D01*
X1229906Y316680D01*
G02X1229879Y316645I-171J104D01*
G01X1229832Y316601D01*
X1229830Y316599D01*
X1229632Y316417D01*
G02X1229501Y316374I-124J157D01*
G01X1229494D01*
X1229480Y316375D01*
X1229473Y316376D01*
X1229467Y316377D01*
G03X1229267Y316392I-212J-1487D01*
G01X1229247D01*
G03X1227760Y315066I5J-1502D01*
G01X1227757Y315038D01*
G03X1227750Y314890I1495J-145D01*
G03X1228320Y313712I1502J0D01*
G01X1228330Y313704D01*
X1228345Y313689D01*
G02X1228391Y313617I-142J-141D01*
G01X1228406Y313578D01*
X1228403Y313534D01*
X1228381Y313205D01*
G02X1228322Y313076I-199J13D01*
G01X1228300Y313055D01*
X1228280Y313043D01*
X1228279Y313042D01*
G03X1227526Y311740I749J-1302D01*
G03X1230530I1502J0D01*
G03X1229960Y312918I-1502J0D01*
G01X1229950Y312926D01*
X1229935Y312941D01*
G02X1229889Y313013I142J141D01*
G01X1229874Y313052D01*
X1229877Y313096D01*
X1229889Y313275D01*
Y313277D01*
X1229897Y313390D01*
G02X1229919Y313455I198J-31D01*
G01X1229977Y313548D01*
G02X1229998Y313574I165J-112D01*
G01X1230018Y313594D01*
X1230026Y313599D01*
X1230039Y313607D01*
G03X1230484Y314030I-791J1278D01*
G03X1230487Y314035I-1284J774D01*
G01X1230516Y314076D01*
X1230534Y314107D01*
G03X1230685Y314438I-1281J784D01*
G03X1230718Y314562I-1434J448D01*
G01X1230728Y314602D01*
X1230813Y314717D01*
X1230829Y314731D01*
X1230851Y314751D01*
X1231110Y314887D01*
G02X1231156Y314903I88J-179D01*
G01X1231238Y314866D01*
G03X1231580Y314741I960J2097D01*
G03X1232197Y314658I613J2224D01*
G03X1233529Y315081I1J2306D01*
G02X1233542Y315080I-9J-200D01*
G03X1234162Y314758I1361J1862D01*
G03X1234904Y314636I740J2184D01*
G03X1236535Y315311I1J2306D01*
G01X1237301Y316077D01*
G02X1237353Y316078I30J-198D01*
G01X1237377Y316075D01*
X1237448Y316054D01*
X1237481Y316032D01*
X1237518Y316009D01*
G03X1238291Y315794I774J1287D01*
G01X1238311D01*
G03X1239734Y316871I-18J1502D01*
G01X1239742Y316897D01*
X1241213Y318368D01*
X1244202Y321358D01*
G02X1244419Y321399I139J-143D01*
G01X1244527Y321354D01*
X1244542Y321332D01*
Y284370D01*
G02X1244534Y284314I-200J0D01*
G02X1244528Y284296I-193J54D01*
G01X1244513Y284260D01*
X1220880Y260626D01*
G02X1220830Y260590I-140J142D01*
G02X1220739Y260568I-91J178D01*
G01X1202662D01*
G03X1202238Y260497I-6J-1267D01*
G01X1202237Y260496D01*
X1202234Y260495D01*
X1202227Y260492D01*
X1202224Y260491D01*
X1202215Y260487D01*
G03X1202144Y260458I443J-1186D01*
G01X1201768Y260196D01*
G03X1201741Y260173I116J-163D01*
G01X1201176Y259608D01*
X1201156Y259596D01*
G03X1200923Y259411I691J-1109D01*
G01X1199282Y257770D01*
X1199240Y257745D01*
X1199217Y257738D01*
G03X1198194Y256615I447J-1434D01*
G03X1198169Y256147I1469J-313D01*
G01X1198173Y256105D01*
X1198161Y256066D01*
G02X1198129Y256005I-190J61D01*
G01X1197947Y255800D01*
X1197917Y255766D01*
G02X1197838Y255716I-144J139D01*
G01X1197796Y255704D01*
X1195728D01*
G02X1195672Y255712I0J200D01*
G02X1195654Y255718I54J193D01*
G01X1195618Y255733D01*
X1192537Y258815D01*
G03X1191722Y259183I-896J-897D01*
G01X1191705Y259185D01*
G03X1191482Y259222I-325J-1266D01*
G03X1191381Y259226I-102J-1302D01*
G01X1177830D01*
G02X1177737Y259249I0J200D01*
G03X1177038Y259421I-698J-1332D01*
G01X1177035D01*
G03Y256417I0J-1502D01*
G01X1177039D01*
G03X1177737Y256589I0J1504D01*
G02X1177830Y256612I93J-177D01*
G01X1190757D01*
G02X1190795Y256608I-2J-200D01*
G02X1190897Y256555I-37J-196D01*
G01X1194053Y253399D01*
G03X1194673Y253052I924J924D01*
G01X1194674D01*
X1194702Y253045D01*
X1194724Y253033D01*
G02X1194769Y252999I-97J-175D01*
G01X1196837Y250931D01*
X1196840Y250927D01*
G03X1197410Y250584I916J877D01*
G01X1197421Y250582D01*
X1197432Y250579D01*
G03X1197754Y250536I327J1225D01*
G01X1206174D01*
G02X1206280Y250503I-4J-200D01*
G01X1206307Y250484D01*
G02X1206325Y250468I-124J-157D01*
G02X1206376Y250379I-142J-141D01*
G01X1206390Y250328D01*
X1206407Y250287D01*
X1206425Y250240D01*
G03X1206462Y250180I186J74D01*
G01X1206466Y250175D01*
G02X1206511Y250077I-152J-129D01*
G01X1206515Y250050D01*
X1206512Y250023D01*
G02X1206496Y249967I-198J26D01*
G01X1206462Y249891D01*
Y249889D01*
X1206444Y249848D01*
X1206418Y249821D01*
G03X1206417Y249820I1062J-1063D01*
G03X1206415Y249818I140J-142D01*
G03X1205985Y248773I1072J-1052D01*
G01Y248741D01*
G03X1207431Y247264I1502J24D01*
G01X1207432D01*
G03X1207487Y247263I55J1501D01*
G01X1207489D01*
G03X1208423Y247590I-1J1501D01*
G01X1208449Y247610D01*
X1208493Y247625D01*
G02X1208546Y247633I56J-192D01*
G01X1208632D01*
G03X1208688Y247641I0J200D01*
G01X1208702Y247644D01*
X1208914D01*
G02X1209039Y247600I0J-200D01*
G01X1209040Y247599D01*
G03X1209043Y247597I835J1249D01*
G03X1209061Y247583I931J1178D01*
G02X1209071Y247575I-120J-160D01*
G03X1209074Y247572I1062J1059D01*
G03X1209120Y247539I898J1204D01*
G02X1209122Y247537I-140J-142D01*
G03X1209160Y247511I867J1226D01*
G03X1209162Y247509I142J140D01*
G03X1209484Y247349I824J1255D01*
G03X1209487Y247348I64J186D01*
G01X1209502Y247343D01*
G03X1209846Y247269I486J1422D01*
G01X1209848D01*
G03X1209905Y247265I134J1496D01*
G01X1209908D01*
G03X1209923Y247264I107J1497D01*
G01X1209989Y247261D01*
X1210038Y247264D01*
G03X1210921Y247589I-51J1501D01*
G01X1210922Y247590D01*
X1210934Y247600D01*
G02X1211040Y247633I110J-167D01*
G01X1211132D01*
G03X1211215Y247651I0J200D01*
G01X1211269Y247676D01*
G02X1211347Y247695I85J-181D01*
G02X1211381Y247693I5J-200D01*
G02X1211485Y247645I-28J-198D01*
G01X1211486Y247644D01*
G03X1212485Y247263I1000J1122D01*
G01X1212487D01*
G03X1213989Y248765I0J1502D01*
G03X1213556Y249820I-1502J0D01*
G01X1213555Y249821D01*
X1213531Y249846D01*
X1213497Y249919D01*
G02X1213494Y249930I191J58D01*
G01X1213479Y249997D01*
G02X1213487Y250089I198J29D01*
G01X1213562Y250273D01*
Y250275D01*
X1213623Y250421D01*
G02X1213650Y250464I182J-84D01*
G02X1213804Y250536I154J-128D01*
G01X1218508D01*
G02X1218622Y250482I-24J-198D01*
G01X1218926Y250178D01*
G02X1218944Y250157I-142J-140D01*
G01Y229061D01*
G02X1218922Y228970I-200J0D01*
G02X1218886Y228920I-178J90D01*
G01X1217618Y227652D01*
G03X1217333Y227216I895J-896D01*
G02X1217310Y227173I-186J72D01*
G02X1217306Y227167I-168J108D01*
G03X1217044Y226382I1045J-785D01*
G01Y222748D01*
G02X1216964Y222685I-160J120D01*
G01X1216600Y222552D01*
G02X1216480Y222546I-70J187D01*
G01X1216451Y222554D01*
X1216399Y222587D01*
X1216379Y222611D01*
G03X1215230Y223144I-1149J-972D01*
G03Y220140I0J-1502D01*
G03X1216357Y220648I0J1504D01*
G01X1216380Y220674D01*
X1216442Y220715D01*
G02X1216599Y220733I99J-174D01*
G01X1216822Y220652D01*
X1216953Y220604D01*
G02X1217044Y220536I-69J-188D01*
G01Y216982D01*
G03X1217427Y216058I1306J0D01*
G01X1225002Y208483D01*
X1225027Y208441D01*
X1225034Y208418D01*
G03X1227904I1435J446D01*
G01X1227911Y208441D01*
X1227936Y208483D01*
X1229625Y210172D01*
G03X1229810Y210405I-924J924D01*
G01X1229822Y210425D01*
X1230549Y211152D01*
G03X1230920Y212048I-896J896D01*
G01Y216195D01*
G02X1230987Y216344I200J0D01*
G01X1231049Y216399D01*
X1231218Y216549D01*
G02X1231278Y216582I125J-156D01*
G01X1231319Y216596D01*
X1231350Y216592D01*
G03X1231518Y216583I164J1493D01*
G01X1231527D01*
G03X1232597Y217040I-9J1502D01*
G01X1232625Y217069D01*
X1232740Y217119D01*
G02X1232808Y217133I74J-186D01*
G01X1233023D01*
X1233062Y217126D01*
X1233100Y217118D01*
X1233211Y217069D01*
X1233238Y217041D01*
G03X1234318Y216583I1080J1044D01*
G03Y219587I0J1502D01*
G03X1233239Y219130I0J-1502D01*
G01X1233211Y219101D01*
X1233096Y219051D01*
G02X1233028Y219037I-74J186D01*
G01X1232835D01*
G02X1232795Y219041I0J200D01*
G01X1232752Y219050D01*
X1232730Y219054D01*
X1232625Y219101D01*
X1232598Y219130D01*
G03X1232116Y219463I-1079J-1046D01*
G01X1232085Y219477D01*
X1232062Y219497D01*
G02X1232028Y219537I134J149D01*
G01X1231977Y219626D01*
Y219627D01*
X1231966Y219646D01*
G02X1231940Y219763I173J100D01*
G01X1231941Y219781D01*
G03X1231944Y219875I-1265J87D01*
G01Y263260D01*
G02X1231948Y263297I200J-3D01*
G01Y263299D01*
G02X1232001Y263400I196J-39D01*
G01X1238921Y270320D01*
G02X1239022Y270373I140J-143D01*
G01X1239024D01*
G02X1239061Y270377I40J-196D01*
G01X1251445D01*
Y270341D01*
X1253837Y267949D01*
G02X1253890Y267848I-143J-140D01*
G01Y267846D01*
G02X1253894Y267809I-196J-40D01*
G01Y248709D01*
G02X1253892Y248681I-200J0D01*
G01X1253886Y248637D01*
G02X1253832Y248549I-192J57D01*
G01X1253782Y248512D01*
X1253544Y248335D01*
G02X1253388Y248308I-109J167D01*
G01X1253378Y248311D01*
G03X1252941Y248376I-437J-1436D01*
G03X1251439Y246874I0J-1502D01*
G03X1252934Y245372I1502J0D01*
G01X1252943D01*
G03X1253039Y245375I1J1502D01*
G01X1253042D01*
X1253049Y245376D01*
X1253055D01*
G03X1253553Y245502I-114J1498D01*
G03X1253598Y245523I-613J1372D01*
G01X1253600Y245524D01*
X1253625Y245536D01*
X1253670Y245546D01*
X1253694D01*
G02X1253894Y245346I0J-200D01*
G01Y245165D01*
G02X1253887Y245113I-200J0D01*
G01X1253882Y245093D01*
X1253866Y245067D01*
G03X1253659Y244321I1296J-761D01*
G01Y244284D01*
G03X1255148Y242795I1502J13D01*
G01X1255184D01*
G03X1255867Y242967I-15J1503D01*
G02X1255960Y242990I93J-177D01*
G01X1256541D01*
G02X1256579Y242986I-2J-200D01*
G02X1256681Y242933I-37J-196D01*
G01X1258774Y240840D01*
G02X1258776Y240811I-198J-28D01*
G01Y231775D01*
G02X1258775Y231754I-200J-1D01*
G02X1258687Y231609I-199J22D01*
G01X1258557Y231533D01*
X1258382Y231431D01*
G02X1258244Y231412I-95J176D01*
G01X1258181Y231427D01*
X1258159Y231439D01*
G03X1257446Y231619I-713J-1322D01*
G01X1257444D01*
G03Y228615I0J-1502D01*
G01X1257447D01*
G03X1258169Y228800I0J1503D01*
G03X1258176Y228804I-96J176D01*
G01X1258213Y228826D01*
X1258255Y228831D01*
X1258257D01*
G02X1258334Y228825I23J-199D01*
G01X1258366Y228815D01*
X1258392Y228798D01*
X1258677Y228631D01*
G02X1258776Y228459I-101J-173D01*
G01Y215997D01*
G02X1258757Y215917I-200J5D01*
G01X1258735Y215908D01*
X1258653Y215874D01*
G02X1258435Y215916I-78J184D01*
G01X1245325Y229027D01*
X1245300Y229069D01*
X1245293Y229092D01*
G03X1243858Y230148I-1435J-447D01*
G03X1242356Y228646I0J-1502D01*
G01X1242355D01*
G03X1243412Y227211I1503J0D01*
G01X1243413D01*
G02X1243495Y227161I-60J-191D01*
G01X1257348Y213309D01*
G02X1257398Y213224I-142J-141D01*
G02X1257406Y213168I-192J-56D01*
G01Y182727D01*
G02X1257384Y182636I-200J0D01*
G02X1257348Y182586I-178J90D01*
G01X1233496Y158734D01*
G02X1233446Y158698I-140J142D01*
G02X1233355Y158676I-91J178D01*
G01X1223098D01*
X1223081Y158685D01*
G03X1222355Y158872I-726J-1317D01*
G01X1222353D01*
G03Y155868I0J-1502D01*
G01X1222354D01*
G03X1223085Y156058I-1J1504D01*
G01X1223096Y156064D01*
X1233261D01*
G02X1233446Y155940I0J-200D01*
G01X1233491Y155831D01*
X1233486Y155806D01*
X1232844Y155165D01*
X1220239Y142561D01*
G02X1220230Y142554I-127J154D01*
G01X1216293D01*
G02X1216258Y142586I117J163D01*
G01X1216130Y142763D01*
X1216065Y142854D01*
G02X1216032Y142960I167J110D01*
G01Y143039D01*
X1216041Y143069D01*
G03X1216110Y143518I-1433J450D01*
G03X1214608Y145020I-1502J0D01*
G03X1213106Y143529I0J-1502D01*
G01Y143515D01*
G03X1213175Y143066I1502J1D01*
G01X1213178Y143056D01*
X1213184Y143037D01*
X1213190Y142986D01*
G02X1213159Y142864I-199J-14D01*
G01X1213084Y142759D01*
X1212962Y142590D01*
G02X1212925Y142554I-157J124D01*
G01X1210916D01*
G02X1210823Y142577I0J200D01*
G03X1210124Y142749I-698J-1332D01*
G01X1210121D01*
G03Y139745I0J-1502D01*
G01X1210125D01*
G03X1210823Y139917I0J1504D01*
G02X1210916Y139940I93J-177D01*
G01X1219384D01*
G02X1219559Y139835I-1J-200D01*
G01X1219567Y139815D01*
G02X1219579Y139699I-184J-78D01*
G01X1219574Y139673D01*
X1219546Y139621D01*
X1210040Y130115D01*
G03X1209658Y129193I924J-923D01*
G01Y116980D01*
G03X1210040Y116058I1306J1D01*
G01X1212368Y113730D01*
G02X1212418Y113533I-142J-141D01*
G01X1212409Y113512D01*
G02X1212336Y113422I-185J76D01*
G01X1212314Y113407D01*
X1212257Y113390D01*
X1203083D01*
G03X1202159Y113007I0J-1306D01*
G01X1198128Y108975D01*
G02X1198016Y108920I-140J143D01*
G02X1197988Y108918I-28J198D01*
G01X1192651D01*
G03X1191729Y108536I1J-1306D01*
G01X1187980Y104786D01*
G02X1187724Y104766I-140J143D01*
G02X1187556Y105091I232J326D01*
G01Y107649D01*
G03X1183950I-1803J0D01*
G01Y104249D01*
G03X1185144Y102551I1804J0D01*
G01X1185185Y102536D01*
X1185245Y102478D01*
X1185258Y102463D01*
G02X1185295Y102394I-155J-127D01*
G01X1185306Y102345D01*
Y102343D01*
X1185370Y102061D01*
G02X1185348Y101931I-197J-33D01*
G01X1185328Y101900D01*
X1183772Y100344D01*
G02X1183752Y100327I-139J144D01*
G01X1183585Y100209D01*
X1183153Y99905D01*
G02X1183038Y99868I-116J163D01*
G01X1176791D01*
X1176778D01*
G02X1176651Y99925I13J200D01*
G01X1176360Y100217D01*
X1176235Y100342D01*
X1176210Y100384D01*
X1176203Y100407D01*
G03X1174768Y101463I-1435J-447D01*
G03X1173266Y99961I0J-1502D01*
G01X1173265D01*
G03X1174322Y98526I1503J0D01*
G01X1174323D01*
G02X1174405Y98476I-60J-191D01*
G01X1174572Y98309D01*
G02Y98252I-198J-29D01*
G01X1173187Y96867D01*
G03X1172544Y95624I1631J-1631D01*
G01X1172528Y95527D01*
G02X1172455Y95482I-139J144D01*
G01X1172191Y95398D01*
X1172189D01*
X1172141Y95383D01*
G02X1172107Y95376I-57J192D01*
G02X1172081Y95374I-28J198D01*
G01X1172059D01*
X1172023Y95389D01*
G02X1171958Y95432I76J185D01*
G01X1171230Y96160D01*
G03X1170308Y96542I-923J-924D01*
G01X1165630D01*
X1165613Y96551D01*
G03X1164887Y96738I-726J-1317D01*
G01X1164885D01*
G03Y93734I0J-1502D01*
G01X1164886D01*
G03X1165617Y93924I-1J1504D01*
G01X1165628Y93930D01*
X1169682D01*
X1169695D01*
G02X1169822Y93873I-13J-200D01*
G01X1170137Y93557D01*
X1170291Y93403D01*
G02X1170292Y93349I-198J-31D01*
G02X1170284Y93314I-198J27D01*
G01X1170247Y93203D01*
Y93201D01*
X1170163Y92928D01*
X1170134Y92902D01*
X1170037Y92885D01*
G03X1168292Y91437I410J-2270D01*
G01X1168259Y91351D01*
G02X1168190Y91322I-111J166D01*
G01X1167996Y91281D01*
X1167994D01*
X1167853Y91251D01*
G02X1167797Y91252I-24J199D01*
G01X1166767Y92282D01*
G03X1165135Y92958I-1632J-1632D01*
G03X1162827Y90650I0J-2308D01*
G03X1163503Y89018I2308J0D01*
G01X1165443Y87078D01*
G03X1167075Y86402I1632J1632D01*
G03X1167159Y86404I-13J2308D01*
G01X1182161D01*
G02X1182167Y86395I-163J-115D01*
G01X1182171Y86389D01*
X1182291Y86191D01*
Y86189D01*
X1182352Y86087D01*
G02X1182371Y86040I-174J-98D01*
G02X1182377Y85994I-194J-49D01*
G01X1182378Y85948D01*
X1182356Y85901D01*
X1182354Y85897D01*
G03X1182180Y85197I1328J-702D01*
G01Y85180D01*
G03X1182586Y84166I1502J13D01*
G01X1182613Y84138D01*
X1182627Y84103D01*
G02X1182637Y84067I-187J-71D01*
G02X1182640Y84032I-197J-35D01*
G01Y83755D01*
G02X1182630Y83691I-200J-1D01*
G02X1182627Y83684I-185J75D01*
G01X1182614Y83650D01*
X1182586Y83620D01*
G03Y81566I1096J-1027D01*
G01X1182614Y81536D01*
X1182627Y81502D01*
G02X1182630Y81495I-182J-82D01*
G02X1182640Y81431I-190J-63D01*
G01Y81155D01*
G02X1182630Y81091I-200J-1D01*
G02X1182627Y81084I-185J75D01*
G01X1182614Y81050D01*
X1182586Y81020D01*
G03Y78966I1096J-1027D01*
G01X1182614Y78936D01*
X1182627Y78902D01*
G02X1182630Y78895I-182J-82D01*
G02X1182640Y78831I-190J-63D01*
G01Y78555D01*
G02X1182630Y78491I-200J-1D01*
G02X1182627Y78484I-185J75D01*
G01X1182614Y78450D01*
X1182586Y78420D01*
G03Y76366I1096J-1027D01*
G01X1182614Y76336D01*
X1182627Y76302D01*
G02X1182630Y76295I-182J-82D01*
G02X1182640Y76231I-190J-63D01*
G01Y75955D01*
G02X1182630Y75891I-200J-1D01*
G02X1182627Y75884I-185J75D01*
G01X1182614Y75850D01*
X1182586Y75820D01*
G03X1182180Y74793I1096J-1027D01*
G03X1185184I1502J0D01*
G03X1184778Y75820I-1502J0D01*
G01X1184750Y75850D01*
X1184737Y75884D01*
G02X1184734Y75891I182J82D01*
G02X1184724Y75955I190J63D01*
G01Y76231D01*
G02X1184734Y76295I200J1D01*
G02X1184737Y76302I185J-75D01*
G01X1184750Y76336D01*
X1184778Y76366D01*
G03Y78420I-1096J1027D01*
G01X1184750Y78450D01*
X1184737Y78484D01*
G02X1184734Y78491I182J82D01*
G02X1184724Y78555I190J63D01*
G01Y78831D01*
G02X1184734Y78895I200J1D01*
G02X1184737Y78902I185J-75D01*
G01X1184750Y78936D01*
X1184778Y78966D01*
G03Y81020I-1096J1027D01*
G01X1184750Y81050D01*
X1184737Y81084D01*
G02X1184734Y81091I182J82D01*
G02X1184724Y81155I190J63D01*
G01Y81431D01*
G02X1184734Y81495I200J1D01*
G02X1184737Y81502I185J-75D01*
G01X1184750Y81536D01*
X1184778Y81566D01*
G03Y83620I-1096J1027D01*
G01X1184750Y83650D01*
X1184737Y83684D01*
G02X1184734Y83691I182J82D01*
G02X1184724Y83755I190J63D01*
G01Y84032D01*
G02X1184727Y84067I200J0D01*
G02X1184737Y84103I197J-35D01*
G01X1184751Y84138D01*
X1184780Y84168D01*
G03X1185184Y85179I-1098J1025D01*
G01Y85195D01*
G03X1185010Y85897I-1502J0D01*
G01X1185004Y85908D01*
G02X1184987Y85993I183J81D01*
G01X1184988Y86046D01*
X1185073Y86189D01*
Y86191D01*
X1185193Y86388D01*
G02X1185204Y86404I170J-105D01*
G01X1202569D01*
G02X1202683Y86369I1J-200D01*
G02X1202699Y86356I-118J-162D01*
G01X1204050Y85005D01*
G02X1204052Y84976I-198J-28D01*
G01Y84913D01*
X1204040Y84867D01*
X1204023Y84834D01*
G03X1203853Y84143I1332J-694D01*
G01Y84110D01*
G03X1205355Y82638I1502J30D01*
G01X1205356D01*
G03X1205419Y82639I8J1502D01*
G01X1205461Y82641D01*
X1205497Y82627D01*
G02X1205560Y82589I-70J-187D01*
G01X1205614Y82538D01*
G02X1205616Y82536I-140J-142D01*
G01X1205781Y82377D01*
G02X1205796Y82359I-146J-137D01*
G01Y76586D01*
G03X1206587Y74849I2307J2D01*
G01X1206629Y74812D01*
X1206637Y74795D01*
G02X1206655Y74717I-182J-83D01*
G01X1206661Y74497D01*
Y74494D01*
X1206663Y74437D01*
X1206472Y74247D01*
G03X1205972Y73498I1632J-1631D01*
G03X1205796Y72622I2131J-884D01*
G01Y72615D01*
G03X1208103Y70308I2307J0D01*
G01X1208140D01*
G03X1208986Y70484I-39J2307D01*
G03X1209735Y70984I-882J2132D01*
G01X1211037Y72287D01*
X1211973Y73223D01*
G03X1212648Y74853I-1631J1630D01*
G01Y84546D01*
G02X1212703Y84596I160J-120D01*
G01X1212726Y84610D01*
X1213070Y84754D01*
G02X1213179Y84767I77J-184D01*
G01X1215499Y82447D01*
G02Y82387I-198J-30D01*
G01Y82384D01*
X1215478Y82254D01*
X1215447Y82059D01*
G02X1215342Y81922I-196J41D01*
G01X1215315Y81908D01*
G03X1214519Y80581I708J-1327D01*
G03X1216021Y79079I1502J0D01*
G03X1217523Y80572I0J1502D01*
G01Y80582D01*
G03X1217447Y81054I-1502J0D01*
G01X1217441Y81072D01*
X1217436Y81108D01*
Y81109D01*
X1217430Y81147D01*
X1217439Y81185D01*
G02X1217471Y81255I194J-47D01*
G01X1217554Y81372D01*
G02X1217588Y81409I163J-116D01*
G02X1217707Y81456I129J-153D01*
G01X1223782D01*
G03X1225412Y82131I0J2306D01*
G01X1226366Y83085D01*
X1227696Y84414D01*
G03X1228372Y86045I-1631J1632D01*
G01Y86102D01*
X1228371Y86125D01*
G03X1226065Y88352I-2305J-79D01*
G03X1224434Y87677I-1J-2306D01*
G01X1224155Y87398D01*
G02X1224116Y87396I-30J198D01*
G01X1223995Y87497D01*
G03X1222511Y88038I-1484J-1765D01*
G01X1221890D01*
G02X1221854Y88073I120J160D01*
G01X1221781Y88164D01*
X1221651Y88325D01*
G02X1221641Y88341I165J114D01*
G02X1221626Y88377I176J95D01*
G01X1221610Y88439D01*
X1221620Y88484D01*
G03X1221653Y88791I-1469J313D01*
G03Y88793I-1502J1D01*
G01Y88816D01*
G03X1220327Y90293I-1502J-15D01*
G01X1220271Y90299D01*
G03X1220140Y90304I-123J-1498D01*
G01X1220132D01*
G03X1219220Y89980I20J-1502D01*
G03X1219154Y89925I928J-1181D01*
G01X1219148Y89920D01*
X1219141Y89914D01*
X1219109Y89893D01*
G02X1218931Y89878I-104J170D01*
G01X1218837Y89919D01*
X1218835D01*
X1218595Y90026D01*
G02X1218587Y90030I85J181D01*
G01X1218533Y90057D01*
X1218514Y90088D01*
Y102018D01*
G02X1218525Y102083I200J0D01*
G01X1218535Y102112D01*
X1218553Y102136D01*
X1218655Y102167D01*
G03X1219310Y102576I-452J1453D01*
G03X1219672Y103218I-1105J1046D01*
G01X1219681Y103250D01*
X1223479Y107048D01*
G03X1223862Y107972I-923J924D01*
G01Y118821D01*
G03X1223479Y119745I-1306J0D01*
G01X1219568Y123655D01*
G02X1219513Y123761I142J141D01*
G02X1219510Y123796I197J35D01*
G01Y125567D01*
G02X1219521Y125632I200J0D01*
G02X1219568Y125708I189J-65D01*
G01X1242493Y148632D01*
X1242525Y148622D01*
X1242590Y148602D01*
X1242623Y148592D01*
G02X1242699Y148543I-68J-188D01*
G01X1242737Y148500D01*
X1242739Y148498D01*
X1242771Y148463D01*
G02X1242796Y148425I-154J-128D01*
G01X1242809Y148400D01*
X1242813Y148384D01*
X1242815Y148374D01*
G03X1244278Y147215I1463J344D01*
G03X1245780Y148717I0J1502D01*
G03X1244621Y150180I-1503J0D01*
G01X1244620D01*
X1244592Y150187D01*
X1244551Y150208D01*
X1244524Y150232D01*
X1244523Y150233D01*
X1244497Y150256D01*
X1244495Y150258D01*
X1244452Y150296D01*
G02X1244403Y150372I139J144D01*
G01X1244393Y150405D01*
X1244373Y150470D01*
X1244363Y150502D01*
X1268517Y174656D01*
G02X1268542Y174644I-160J-366D01*
G02X1268591Y174608I-93J-177D01*
G01X1268672Y174527D01*
G02X1268677Y174522I-139J-144D01*
G02X1268708Y174479I-145J-138D01*
G02X1268754Y174292I-354J-186D01*
G01Y174009D01*
G02X1268752Y173982I-200J1D01*
G01X1249493Y154723D01*
G03X1249110Y153799I923J-924D01*
G01Y144624D01*
G02X1249109Y144609I-200J6D01*
G02X1249097Y144554I-199J15D01*
G02X1249083Y144523I-189J67D01*
G03X1249011Y144386I1292J-766D01*
G01Y144384D01*
G03X1248971Y144290I1361J-635D01*
G01X1248966Y144275D01*
X1248955Y144243D01*
X1248954Y144241D01*
X1248951Y144231D01*
X1248950Y144228D01*
G03X1248947Y144219I1423J-479D01*
G02X1248945Y144213I-191J60D01*
G03X1248942Y144205I1404J-531D01*
G01X1248938Y144193D01*
G02X1248933Y144181I-187J71D01*
G02X1248894Y144126I-180J87D01*
G01X1243026Y138258D01*
G03X1242644Y137336I924J-923D01*
G01Y127603D01*
G02X1242611Y127568I-161J119D01*
G01X1242470Y127452D01*
X1242468Y127450D01*
X1242376Y127375D01*
G02X1242327Y127345I-128J154D01*
G01X1242243Y127363D01*
G03X1241764Y127414I-482J-2256D01*
G01X1241580D01*
Y127407D01*
G03X1239458Y125109I184J-2299D01*
G01Y121166D01*
G02X1239447Y121153I-158J123D01*
G01X1239429Y121133D01*
X1239416Y121125D01*
X1239378Y121102D01*
X1239376Y121101D01*
X1239112Y120938D01*
G02X1239006Y120908I-105J170D01*
G01X1238958Y120909D01*
X1238915Y120931D01*
X1238889Y120944D01*
X1238870Y120961D01*
G03X1238821Y120993I-133J-150D01*
G03X1238804Y121000I-85J-181D01*
G02X1238796Y121003I66J189D01*
G03X1238230Y121113I-567J-1409D01*
G03X1236711Y119594I0J-1519D01*
G03X1237267Y118421I1515J0D01*
G01X1237269Y118419D01*
X1237291Y118400D01*
X1237307Y118387D01*
X1237321Y118371D01*
G02X1237344Y118336I-155J-127D01*
G01X1237370Y118280D01*
G02X1237384Y118207I-186J-74D01*
G01Y117983D01*
G02X1237366Y117900I-200J0D01*
G01X1237353Y117873D01*
Y117871D01*
X1237326Y117817D01*
G02X1237293Y117772I-176J95D01*
G01X1237274Y117753D01*
X1237267Y117747D01*
G03X1236728Y116594I964J-1153D01*
G03X1238230Y115092I1502J0D01*
G03X1239307Y115547I0J1502D01*
G01X1239334Y115575D01*
X1239474Y115637D01*
X1239531Y115635D01*
G02X1239694Y115525I-16J-200D01*
G01X1239695Y115523D01*
G03X1240133Y114911I2069J1018D01*
G01X1249733Y105311D01*
G02X1249786Y105209I-143J-139D01*
G02X1249790Y105171I-196J-40D01*
G01Y95111D01*
G03X1254404I2307J0D01*
G01Y105213D01*
G02X1254445Y105254I160J-119D01*
G01X1255605D01*
X1255615D01*
G02X1255696Y105232I-11J-200D01*
G03X1255789Y105182I773J1327D01*
G01X1255812Y105171D01*
X1255814Y105170D01*
X1255849Y105140D01*
X1255864Y105119D01*
G02X1255818Y104840I-163J-116D01*
G01X1255795Y104824D01*
X1255771Y104815D01*
G03X1254805Y103411I537J-1404D01*
G03X1257809I1502J0D01*
G03X1257230Y104596I-1502J0D01*
G01X1257212Y104610D01*
X1257175Y104655D01*
G02X1257145Y104704I154J128D01*
G01Y104706D01*
G02X1257129Y104793I184J79D01*
G01X1257134Y104897D01*
Y104899D01*
X1257145Y105081D01*
G02X1257157Y105126I198J-29D01*
G01X1257185Y105177D01*
G02X1257210Y105210I171J-104D01*
G01X1257227Y105228D01*
X1257235Y105233D01*
X1257252Y105243D01*
G03X1258001Y106561I-785J1318D01*
G03X1256466Y108096I-1535J0D01*
G01X1256465D01*
G03X1255703Y107894I0J-1537D01*
G01X1255680Y107881D01*
X1255656Y107875D01*
G02X1255605Y107868I-52J193D01*
G01X1255114D01*
G02X1254973Y107926I0J200D01*
G01X1248858Y114039D01*
X1245275Y117623D01*
G02X1245256Y117645I141J141D01*
G01Y136710D01*
G02X1245258Y136740I200J2D01*
G02X1245313Y136850I198J-30D01*
G01X1248975Y140511D01*
X1250777Y142313D01*
X1250803Y142321D01*
G03X1251880Y143749I-425J1441D01*
G01Y143776D01*
G03X1251853Y144050I-1502J-10D01*
G01X1251848Y144074D01*
G03X1251741Y144397I-1471J-308D01*
G01X1251724Y144434D01*
Y153175D01*
G02X1251728Y153213I200J-2D01*
G02X1251781Y153315I196J-37D01*
G01X1271106Y172640D01*
G03X1271488Y173562I-924J923D01*
G01Y256882D01*
G02X1271492Y256923I200J1D01*
G02X1271546Y257023I196J-41D01*
G01X1277317Y262793D01*
G03X1277318Y262794I-923J924D01*
G03X1277562Y263134I-926J922D01*
G01X1277585Y263180D01*
X1277610Y263198D01*
X1277614Y263200D01*
X1277627Y263209D01*
G02X1277677Y263234I114J-165D01*
G01X1277701Y263242D01*
X1277874Y263263D01*
G02X1277898Y263264I20J-199D01*
G01X1278036D01*
G02X1278118Y263246I-1J-200D01*
G01X1278157Y263229D01*
X1278186Y263195D01*
G03X1279320Y262678I1134J985D01*
G01X1279321D01*
G03X1279379Y262679I3J1502D01*
G01X1279392D01*
G03X1279468Y262685I-80J1500D01*
G01X1279469D01*
G03X1279512Y262690I-152J1494D01*
G01X1279513D01*
G03X1279542Y262694I-191J1490D01*
G01X1279544D01*
G03X1279643Y262713I-233J1484D01*
G01X1279645D01*
G03X1279932Y262807I-322J1467D01*
G01X1279964Y262822D01*
G03X1280014Y262847I-647J1356D01*
G03X1280257Y263004I-690J1335D01*
G02X1280382Y263048I125J-156D01*
G01X1280466D01*
G03X1280549Y263066I0J200D01*
G01X1280603Y263091D01*
G02X1280681Y263110I85J-181D01*
G02X1280715Y263108I5J-200D01*
G02X1280819Y263060I-28J-198D01*
G01X1280820Y263059D01*
G03X1281819Y262678I1000J1122D01*
G01X1281821D01*
G03Y265682I0J1502D01*
G03X1280887Y265356I0J-1502D01*
G01X1280886Y265355D01*
X1280874Y265345D01*
G02X1280768Y265312I-110J167D01*
G01X1280676D01*
G03X1280593Y265294I0J-200D01*
G01X1280539Y265269D01*
G02X1280461Y265250I-85J181D01*
G02X1280427Y265252I-5J200D01*
G02X1280323Y265300I28J198D01*
G01X1280322Y265301D01*
G03X1279322Y265682I-1000J-1122D01*
G01X1279284D01*
G03X1278871Y265613I39J-1502D01*
G03X1278324Y265304I449J-1433D01*
G02X1278218Y265255I-133J149D01*
G01X1278217D01*
G02X1278112Y265269I-27J198D01*
G02X1278108Y265271I87J180D01*
G01X1277863Y265383D01*
X1277861D01*
X1277781Y265419D01*
X1277775Y265422D01*
G02X1277700Y265483I85J181D01*
G01Y350727D01*
G02X1277704Y350765I200J-2D01*
G02X1277757Y350867I196J-37D01*
G01X1284800Y357910D01*
X1284842Y357935D01*
X1284865Y357942D01*
G03X1285921Y359377I-447J1435D01*
G03X1284419Y360879I-1502J0D01*
G01Y360880D01*
G03X1282984Y359823I0J-1503D01*
G01Y359822D01*
G02X1282934Y359740I-191J60D01*
G01X1275469Y352275D01*
G03X1275086Y351351I923J-924D01*
G01Y321863D01*
G02X1274981Y321688I-200J1D01*
G01X1274961Y321680D01*
G02X1274845Y321668I-78J184D01*
G01X1274819Y321673D01*
X1274767Y321701D01*
X1267550Y328918D01*
G03X1266628Y329300I-923J-924D01*
G01X1264001D01*
G02X1263948Y329359I119J161D01*
G01X1263778Y329665D01*
G02X1263756Y329757I178J91D01*
G01X1263757Y329812D01*
X1263771Y329837D01*
X1263780Y329868D01*
X1263793Y329890D01*
G03X1264002Y330654I-1293J764D01*
G01Y330675D01*
G03X1263998Y330769I-1502J-17D01*
G01X1263997Y330777D01*
Y330783D01*
X1263994Y330813D01*
G03X1263981Y330908I-1494J-156D01*
G03X1263927Y331125I-1481J-253D01*
G01Y331126D01*
G03X1263921Y331143I-1419J-491D01*
G03X1263917Y331154I-1414J-508D01*
G01X1263916Y331156D01*
G03X1263909Y331175I-1413J-510D01*
G01Y331176D01*
G02X1263898Y331269I187J69D01*
G01X1263903Y331314D01*
X1264098Y331608D01*
X1264113Y331622D01*
X1264146Y331655D01*
G02X1264208Y331697I141J-142D01*
G01X1264243Y331712D01*
X1264280Y331714D01*
G03X1265428Y332329I-65J1501D01*
G01X1265442Y332346D01*
G03X1265456Y332366I-157J125D01*
G01X1265457Y332368D01*
X1265479Y332402D01*
G03X1264883Y334573I-1259J822D01*
G01X1264861Y334584D01*
G02X1264781Y334688I110J167D01*
G01X1264707Y334979D01*
Y334981D01*
X1264697Y335017D01*
X1264702Y335056D01*
G02X1264725Y335126I198J-26D01*
G01X1264733Y335141D01*
X1264741Y335152D01*
X1264743Y335154D01*
X1264744Y335156D01*
X1264746Y335159D01*
X1264755Y335173D01*
G03X1265003Y335994I-1255J827D01*
G01Y336009D01*
X1265001Y336056D01*
G03X1263504Y337502I-1501J-56D01*
G01X1263500D01*
G03X1262299Y336902I0J-1502D01*
G03X1262264Y336854I1196J-909D01*
G03X1262832Y334642I1231J-863D01*
G01X1262854Y334631D01*
G02X1262934Y334527I-110J-167D01*
G01X1263008Y334236D01*
Y334234D01*
X1263018Y334198D01*
X1263013Y334159D01*
G02X1262990Y334089I-198J26D01*
G01X1262982Y334074D01*
X1262973Y334062D01*
X1262972Y334061D01*
X1262971Y334059D01*
X1262969Y334056D01*
X1262960Y334042D01*
G03X1262712Y333218I1255J-827D01*
G01Y333182D01*
X1262715Y333128D01*
Y333127D01*
G03X1262722Y333043I1500J83D01*
G03X1262783Y332758I1493J171D01*
G01X1262794Y332725D01*
G03X1262796Y332720I187J72D01*
G01X1262799Y332713D01*
X1262807Y332691D01*
G02X1262793Y332527I-189J-66D01*
G02X1262785Y332515I-170J105D01*
G01X1262617Y332262D01*
X1262602Y332248D01*
X1262569Y332215D01*
G02X1262518Y332178I-142J141D01*
G01X1262470Y332158D01*
X1262434Y332156D01*
G03X1260998Y330655I66J-1501D01*
G01Y330632D01*
G03X1261013Y330441I1502J22D01*
G03X1261020Y330397I1487J214D01*
G01Y330395D01*
G03X1261028Y330355I1477J275D01*
G03X1261054Y330248I1472J301D01*
G03X1261156Y329984I1446J407D01*
G03X1261206Y329892I1344J671D01*
G01X1261212Y329882D01*
X1261219Y329870D01*
X1261237Y329808D01*
G02X1261218Y329657I-193J-52D01*
G01X1261054Y329363D01*
X1261053Y329362D01*
G02X1260999Y329300I-175J98D01*
G01X1258130D01*
G02X1258039Y329322I0J200D01*
G02X1257989Y329358I90J178D01*
G01X1255364Y331983D01*
G02X1255328Y332033I142J140D01*
G02X1255306Y332124I178J91D01*
G01Y332261D01*
G02X1255390Y332328I162J-117D01*
G01X1255728Y332472D01*
G02X1255755Y332481I77J-185D01*
G02X1255844Y332484I51J-194D01*
G01X1255873Y332479D01*
X1255923Y332452D01*
X1255947Y332429D01*
G03X1257000Y331998I1053J1071D01*
G03Y335002I0J1502D01*
G03X1255974Y334597I0J-1502D01*
G01X1255947Y334571D01*
X1255853Y334533D01*
G02X1255711Y334536I-67J188D01*
G02X1255708Y334537I62J190D01*
G01X1255390Y334671D01*
G02X1255306Y334738I78J184D01*
G01Y336245D01*
G02X1255339Y336281I163J-116D01*
G01X1255569Y336474D01*
X1255570Y336475D01*
X1255578Y336481D01*
G02X1255696Y336521I120J-160D01*
G01X1255717D01*
X1255733Y336518D01*
G03X1255979Y336498I244J1484D01*
G01X1255980D01*
G03X1255983I2J1503D01*
G01X1256011D01*
G03X1257502Y338000I-11J1502D01*
G03X1257176Y338934I-1502J0D01*
G01X1257175Y338935D01*
X1257165Y338947D01*
G02X1257132Y339053I167J110D01*
G01Y339145D01*
G03X1257114Y339228I-200J0D01*
G01X1257089Y339282D01*
G02X1257070Y339360I181J85D01*
G02X1257072Y339394I200J5D01*
G02X1257120Y339498I198J-28D01*
G01X1257121Y339499D01*
G03X1257502Y340498I-1122J1000D01*
G01Y340500D01*
G03X1256000Y342002I-1502J0D01*
G01X1255999D01*
G03X1255267Y341811I1J-1502D01*
G01X1255257Y341806D01*
X1254498D01*
G03X1253576Y341424I1J-1306D01*
G01X1253076Y340924D01*
G03X1252694Y340002I924J-923D01*
G01Y331636D01*
G02X1252581Y331456I-200J0D01*
G01X1252569Y331451D01*
G02X1252451Y331440I-77J185D01*
G01X1252425Y331445D01*
X1252375Y331472D01*
X1248662Y335184D01*
G02X1248607Y335290I142J141D01*
G02X1248604Y335325I197J35D01*
G01Y449399D01*
G02X1248663Y449541I200J0D01*
G01X1265553Y466432D01*
G03X1265612Y466574I-141J142D01*
G01Y492152D01*
G02X1265616Y492189I200J-3D01*
G01Y492191D01*
G02X1265669Y492292I196J-39D01*
G01X1278443Y505065D01*
G03X1278814Y505961I-896J896D01*
G01Y506183D01*
X1278819Y506206D01*
G03X1278840Y506312I-1270J307D01*
G01Y506314D01*
G03X1278854Y506503I-1293J191D01*
G01Y520779D01*
G02X1278858Y520821I200J2D01*
G02X1278911Y520919I196J-42D01*
G01X1296729Y538738D01*
G02X1296809Y538787I142J-141D01*
G02X1296870Y538796I59J-191D01*
G01X1326090D01*
G03X1327012Y539178I-1J1306D01*
G01X1327658Y539824D01*
G02X1327760Y539877I139J-143D01*
G02X1327798Y539881I40J-196D01*
G01X1350945D01*
G02X1350977Y539878I-3J-200D01*
G01X1350979D01*
G02X1351085Y539824I-34J-197D01*
G01X1357043Y533865D01*
X1357167Y533741D01*
G02X1357216Y533657I-143J-140D01*
G02X1357224Y533601I-192J-56D01*
G01Y498820D01*
G03X1357469Y498058I1307J0D01*
G01X1357475Y498050D01*
X1357495Y498021D01*
G03X1357501Y497996I1234J283D01*
G01X1357503Y497987D01*
X1357504Y497978D01*
G03X1357520Y497923I1224J326D01*
G01X1357521Y497920D01*
X1357523Y497913D01*
G03X1357527Y497901I192J57D01*
G03X1357533Y497885I1189J437D01*
G02X1357537Y497873I-188J-69D01*
G03X1357540Y497863I1215J359D01*
G03X1357542Y497859I178J87D01*
G03X1357573Y497780I1194J423D01*
G01X1357577Y497771D01*
G03X1357582Y497760I1155J518D01*
G01X1357583Y497759D01*
X1357598Y497729D01*
G03X1357836Y497397I1135J562D01*
G01X1372773Y482460D01*
G02X1372792Y482438I-141J-141D01*
G02X1372832Y482318I-160J-120D01*
G01Y452452D01*
G03X1373214Y451530I1306J1D01*
G01X1382876Y441868D01*
G02X1382929Y441766I-143J-139D01*
G02X1382933Y441728I-196J-40D01*
G01Y426780D01*
G02X1382925Y426724I-200J0D01*
G02X1382919Y426706I-193J54D01*
G01X1382904Y426670D01*
X1382388Y426154D01*
G02X1382338Y426118I-140J142D01*
G02X1382247Y426096I-91J178D01*
G01X1375820D01*
X1375782Y426113D01*
G03X1375174Y426243I-611J-1371D01*
G01X1375135D01*
G03X1373736Y425187I36J-1502D01*
G01X1373729Y425164D01*
X1373704Y425122D01*
X1372021Y423439D01*
G03X1371638Y422515I923J-924D01*
G01Y418793D01*
G03X1372021Y417869I1306J0D01*
G01X1378101Y411789D01*
G02X1378103Y411760I-198J-28D01*
G01Y399488D01*
G02X1378095Y399432I-200J0D01*
G02X1378089Y399414I-193J54D01*
G01X1378074Y399378D01*
X1378041Y399345D01*
G02X1378017Y399325I-140J143D01*
G01X1377872Y399226D01*
X1377743Y399138D01*
X1377731Y399130D01*
G02X1377713Y399121I-98J174D01*
G02X1377559Y399117I-82J183D01*
G01X1377526Y399129D01*
G03X1377026Y399215I-501J-1416D01*
G01X1377024D01*
G03Y396211I0J-1502D01*
G01X1377026D01*
G03X1377529Y396298I-1J1502D01*
G01X1377562Y396310D01*
X1377652D01*
X1377662D01*
G02X1377757Y396280I-11J-200D01*
G01X1377859Y396209D01*
X1378024Y396095D01*
G02X1378039Y396082I-123J-157D01*
G03X1378041Y396080I142J140D01*
G02X1378071Y396044I-138J-145D01*
G01X1378081Y396026D01*
G02X1378103Y395949I-178J-92D01*
G01Y375966D01*
G03X1378162Y375824I200J0D01*
G01X1381664Y372322D01*
G03X1381806Y372263I142J141D01*
G01X1383355D01*
G02X1383383Y372261I0J-200D01*
G01X1387161Y368483D01*
G02X1387163Y368443I-198J-30D01*
G01X1387148Y368310D01*
Y368308D01*
X1387129Y368151D01*
G02X1387117Y368111I-196J37D01*
G01X1387107Y368091D01*
X1387068Y368022D01*
G02X1387059Y368010I-164J114D01*
G01X1387032Y367979D01*
X1387010Y367965D01*
G03X1386339Y366710I838J-1255D01*
G01Y366702D01*
G03X1386506Y366017I1509J5D01*
G01X1386516Y365997D01*
X1386534Y365929D01*
G02X1386540Y365879I-194J-49D01*
G01Y363814D01*
G03X1386923Y362890I1306J0D01*
G01X1387763Y362050D01*
G02X1387816Y361948I-143J-139D01*
G02X1387820Y361910I-196J-40D01*
G01Y327698D01*
G02X1387620Y327498I-200J0D01*
G01X1385158D01*
X1385143Y327504D01*
G03X1384265Y327678I-879J-2133D01*
G03X1383857Y327641I4J-2307D01*
G01X1383840Y327638D01*
X1379188D01*
G03X1378532Y327540I3J-2267D01*
G01X1378518Y327536D01*
X1374928D01*
G02X1374872Y327544I0J200D01*
G02X1374854Y327550I54J193D01*
G01X1374818Y327565D01*
X1373557Y328826D01*
G02X1373538Y328848I141J141D01*
G01Y355493D01*
G02X1373577Y355532I160J-121D01*
G01X1373604Y355552D01*
X1373742Y355619D01*
X1373933Y355712D01*
G02X1374047Y355731I88J-179D01*
G01X1374076Y355727D01*
X1374129Y355703D01*
X1374151Y355684D01*
G03X1374161Y355676I130J153D01*
G02X1374166Y355673I-100J-173D01*
G03X1375063Y355368I908J1198D01*
G01X1375074D01*
G03X1375121Y355369I-8J1503D01*
G01X1375130Y355370D01*
X1375137D01*
G03X1376575Y356871I-64J1501D01*
G03X1375073Y358373I-1502J0D01*
G03X1374146Y358053I0J-1503D01*
G01X1374143Y358050D01*
X1374142D01*
X1374133Y358044D01*
G02X1373944Y358026I-111J166D01*
G01X1373640Y358172D01*
X1373638Y358174D01*
X1373611Y358187D01*
G02X1373538Y358247I87J180D01*
G01Y359993D01*
G02X1373577Y360032I160J-121D01*
G01X1373604Y360052D01*
X1373742Y360119D01*
X1373933Y360212D01*
G02X1374047Y360231I88J-179D01*
G01X1374076Y360227D01*
X1374129Y360203D01*
X1374151Y360184D01*
G03X1374161Y360176I130J153D01*
G02X1374166Y360173I-100J-173D01*
G03X1375063Y359868I908J1198D01*
G01X1375074D01*
G03X1375121Y359869I-8J1503D01*
G01X1375130Y359870D01*
X1375137D01*
G03X1376575Y361371I-64J1501D01*
G03X1375073Y362873I-1502J0D01*
G03X1373951Y362370I0J-1503D01*
G01X1373924Y362339D01*
X1373806Y362282D01*
X1373760Y362270D01*
X1373513Y362262D01*
X1373470D01*
G02X1373398Y362276I2J200D01*
G01X1373362Y362291D01*
X1373328Y362325D01*
G02X1373324Y362329I139J143D01*
G03X1372232Y362800I-1092J-1030D01*
G03X1370730Y361298I0J-1502D01*
G01Y361297D01*
G03X1370920Y360566I1504J1D01*
G01X1370926Y360555D01*
Y327260D01*
G02X1370914Y327192I-200J0D01*
G02X1370868Y327119I-188J68D01*
G01X1343218Y299470D01*
G03X1342836Y298548I924J-923D01*
G01Y294551D01*
G02X1342814Y294460I-200J0D01*
G02X1342778Y294410I-178J90D01*
G01X1330267Y281899D01*
G03X1329896Y281003I896J-896D01*
G01Y267596D01*
G02X1329888Y267540I-200J0D01*
G02X1329882Y267522I-193J54D01*
G01X1329867Y267486D01*
X1329837Y267456D01*
X1326546Y264164D01*
X1323254Y260872D01*
G02X1323204Y260836I-140J142D01*
G02X1323113Y260814I-91J178D01*
G01X1305270D01*
G03X1304846Y260743I-6J-1267D01*
G01X1304845Y260742D01*
X1304842Y260741D01*
X1304835Y260738D01*
X1304832Y260737D01*
X1304823Y260733D01*
G03X1304752Y260704I443J-1186D01*
G01X1304376Y260442D01*
G03X1304349Y260419I116J-163D01*
G01X1303493Y259563D01*
X1303473Y259551D01*
G03X1303240Y259366I691J-1109D01*
G01X1301644Y257770D01*
X1301602Y257745D01*
X1301579Y257738D01*
G03X1300556Y256615I447J-1434D01*
G03X1300531Y256147I1469J-313D01*
G01X1300535Y256105D01*
X1300523Y256066D01*
G02X1300491Y256005I-190J61D01*
G01X1300309Y255800D01*
X1300279Y255766D01*
G02X1300200Y255716I-144J139D01*
G01X1300158Y255704D01*
X1298091D01*
G02X1298035Y255712I0J200D01*
G02X1298017Y255718I54J193D01*
G01X1297981Y255733D01*
X1293938Y259776D01*
G03X1293475Y260071I-896J-896D01*
G01X1293433Y260085D01*
X1293403Y260096D01*
G03X1293375Y260104I-69J-188D01*
G01X1293368Y260105D01*
X1293356Y260108D01*
X1293351Y260109D01*
G03X1293130Y260144I-308J-1229D01*
G01X1293103Y260148D01*
G03X1292786Y260186I-313J-1268D01*
G01X1279991D01*
X1279974Y260195D01*
G03X1279248Y260382I-726J-1317D01*
G01X1279246D01*
G03Y257378I0J-1502D01*
G01X1279247D01*
G03X1279978Y257568I-1J1504D01*
G01X1279989Y257574D01*
X1292162D01*
G02X1292198Y257571I1J-200D01*
G02X1292303Y257516I-36J-197D01*
G01X1296397Y253421D01*
G03X1297014Y253075I924J924D01*
G01X1297042Y253068D01*
X1297064Y253056D01*
G02X1297109Y253022I-97J-175D01*
G01X1299199Y250931D01*
X1299202Y250927D01*
G03X1299772Y250584I916J877D01*
G01X1299783Y250582D01*
X1299794Y250579D01*
G03X1300116Y250536I327J1225D01*
G01X1308536D01*
G02X1308642Y250503I-4J-200D01*
G01X1308669Y250484D01*
G02X1308687Y250468I-124J-157D01*
G02X1308738Y250379I-142J-141D01*
G01X1308752Y250328D01*
X1308769Y250287D01*
X1308787Y250240D01*
G03X1308824Y250180I186J74D01*
G01X1308828Y250175D01*
G02X1308873Y250077I-152J-129D01*
G01X1308877Y250050D01*
X1308874Y250023D01*
G02X1308858Y249967I-198J26D01*
G01X1308824Y249891D01*
Y249889D01*
X1308806Y249848D01*
X1308780Y249821D01*
G03X1308779Y249820I1062J-1063D01*
G03X1308777Y249818I140J-142D01*
G03X1308347Y248773I1072J-1052D01*
G01Y248741D01*
G03X1309793Y247264I1502J24D01*
G01X1309794D01*
G03X1309849Y247263I55J1501D01*
G01X1309851D01*
G03X1310785Y247590I-1J1501D01*
G01X1310811Y247610D01*
X1310855Y247625D01*
G02X1310908Y247633I56J-192D01*
G01X1310994D01*
G03X1311077Y247651I0J200D01*
G01X1311131Y247676D01*
G02X1311209Y247695I85J-181D01*
G02X1311243Y247693I5J-200D01*
G02X1311347Y247645I-28J-198D01*
G01X1311348Y247644D01*
G03X1311690Y247415I999J1123D01*
G03X1311748Y247388I663J1348D01*
G01X1311766Y247380D01*
G03X1312344Y247263I581J1385D01*
G01X1312370D01*
G03X1312830Y247342I-21J1502D01*
G03X1313283Y247589I-482J1423D01*
G01X1313284Y247590D01*
X1313296Y247600D01*
G02X1313402Y247633I110J-167D01*
G01X1313494D01*
G03X1313577Y247651I0J200D01*
G01X1313631Y247676D01*
G02X1313709Y247695I85J-181D01*
G02X1313743Y247693I5J-200D01*
G02X1313847Y247645I-28J-198D01*
G01X1313848Y247644D01*
G03X1314847Y247263I1000J1122D01*
G01X1314849D01*
G03X1316351Y248765I0J1502D01*
G03X1315918Y249820I-1502J0D01*
G01X1315917Y249821D01*
X1315893Y249846D01*
X1315859Y249919D01*
G02X1315856Y249930I191J58D01*
G01X1315841Y249997D01*
G02X1315849Y250089I198J29D01*
G01X1315924Y250273D01*
Y250275D01*
X1315985Y250421D01*
G02X1316012Y250464I182J-84D01*
G02X1316166Y250536I154J-128D01*
G01X1320870D01*
G02X1320984Y250482I-24J-198D01*
G01X1321288Y250178D01*
G02X1321306Y250157I-142J-140D01*
G01Y229061D01*
G02X1321284Y228970I-200J0D01*
G02X1321248Y228920I-178J90D01*
G01X1319980Y227652D01*
G03X1319695Y227216I895J-896D01*
G02X1319672Y227173I-186J72D01*
G02X1319668Y227167I-168J108D01*
G03X1319406Y226382I1045J-785D01*
G01Y222748D01*
G02X1319326Y222685I-160J120D01*
G01X1318962Y222552D01*
G02X1318842Y222546I-70J187D01*
G01X1318813Y222554D01*
X1318761Y222587D01*
X1318741Y222611D01*
G03X1317592Y223144I-1149J-972D01*
G03Y220140I0J-1502D01*
G03X1318719Y220648I0J1504D01*
G01X1318742Y220674D01*
X1318804Y220715D01*
G02X1318961Y220733I99J-174D01*
G01X1319184Y220652D01*
X1319315Y220604D01*
G02X1319406Y220536I-69J-188D01*
G01Y216982D01*
G03X1319789Y216058I1306J0D01*
G01X1327364Y208483D01*
X1327389Y208441D01*
X1327396Y208418D01*
G03X1328831Y207362I1435J447D01*
G03X1330333Y208864I0J1502D01*
G01X1330334D01*
G03X1329277Y210299I-1503J0D01*
G01X1329276D01*
G02X1329194Y210349I60J191D01*
G01X1322144Y217399D01*
G02X1322142Y217427I198J28D01*
G01Y222778D01*
G02X1322255Y222953I200J-5D01*
G02X1322277Y222962I87J-180D01*
G01X1322355Y222988D01*
G03X1322411Y223017I-63J190D01*
G01X1322450Y223046D01*
X1322479Y223068D01*
G02X1322628Y223105I119J-161D01*
G01X1322660Y223100D01*
X1322673Y223096D01*
G03X1323100Y223034I427J1440D01*
G01X1323101D01*
G03X1323116I7J1502D01*
G01X1323125D01*
G03X1323164Y223035I-19J1502D01*
G01X1323183Y223036D01*
X1323184D01*
G03X1324555Y224160I-83J1500D01*
G01X1324562Y224187D01*
X1324575Y224209D01*
G02X1324606Y224250I174J-99D01*
G01X1328313Y227956D01*
G03X1328684Y228852I-896J896D01*
G01Y230365D01*
X1328688Y230378D01*
G03X1328998Y231222I-996J845D01*
G01Y255016D01*
G02X1329020Y255107I200J0D01*
G02X1329056Y255157I178J-90D01*
G01X1332759Y258860D01*
X1332760Y258861D01*
G02X1332962Y258909I141J-143D01*
G01X1333086Y258857D01*
X1333100Y258836D01*
Y164075D01*
G02X1333078Y163984I-200J0D01*
G02X1333042Y163934I-178J90D01*
G01X1312295Y143187D01*
G03X1311912Y142263I923J-924D01*
G01Y117222D01*
G03X1312295Y116298I1306J0D01*
G01X1314863Y113730D01*
G02X1314913Y113533I-142J-141D01*
G01X1314904Y113512D01*
G02X1314831Y113422I-185J76D01*
G01X1314809Y113407D01*
X1314752Y113390D01*
X1305046D01*
G03X1304122Y113007I0J-1306D01*
G01X1301774Y110659D01*
G03X1301746Y110630I926J-922D01*
G01X1301744Y110628D01*
X1300094Y108977D01*
G02X1299972Y108919I-142J141D01*
G02X1299952Y108918I-20J199D01*
G01X1295013D01*
G03X1294091Y108536I1J-1306D01*
G01X1290342Y104786D01*
G02X1290086Y104766I-140J143D01*
G02X1289918Y105091I232J326D01*
G01Y107649D01*
G03X1286312I-1803J0D01*
G01Y104249D01*
G03X1287506Y102551I1804J0D01*
G01X1287547Y102536D01*
X1287607Y102478D01*
X1287620Y102463D01*
G02X1287657Y102394I-155J-127D01*
G01X1287668Y102345D01*
Y102343D01*
X1287732Y102061D01*
G02X1287710Y101931I-197J-33D01*
G01X1287690Y101900D01*
X1286134Y100344D01*
G02X1286114Y100327I-139J144D01*
G01X1285947Y100209D01*
X1285515Y99905D01*
G02X1285400Y99868I-116J163D01*
G01X1279153D01*
X1279140D01*
G02X1279013Y99925I13J200D01*
G01X1278722Y100217D01*
X1278597Y100342D01*
X1278572Y100384D01*
X1278565Y100407D01*
G03X1277130Y101463I-1435J-447D01*
G03X1275628Y99961I0J-1502D01*
G01X1275627D01*
G03X1276684Y98526I1503J0D01*
G01X1276685D01*
G02X1276767Y98476I-60J-191D01*
G01X1276934Y98309D01*
G02Y98252I-198J-29D01*
G01X1275549Y96867D01*
G03X1274906Y95624I1631J-1631D01*
G01X1274890Y95527D01*
G02X1274817Y95482I-139J144D01*
G01X1274553Y95398D01*
X1274551D01*
X1274503Y95383D01*
G02X1274469Y95376I-57J192D01*
G02X1274443Y95374I-28J198D01*
G01X1274421D01*
X1274385Y95389D01*
G02X1274320Y95432I76J185D01*
G01X1273592Y96160D01*
G03X1272670Y96542I-923J-924D01*
G01X1267992D01*
X1267975Y96551D01*
G03X1267249Y96738I-726J-1317D01*
G01X1267247D01*
G03Y93734I0J-1502D01*
G01X1267248D01*
G03X1267979Y93924I-1J1504D01*
G01X1267990Y93930D01*
X1272044D01*
X1272057D01*
G02X1272184Y93873I-13J-200D01*
G01X1272499Y93557D01*
X1272653Y93403D01*
G02X1272654Y93349I-198J-31D01*
G02X1272646Y93314I-198J27D01*
G01X1272609Y93203D01*
Y93201D01*
X1272525Y92928D01*
X1272496Y92902D01*
X1272399Y92885D01*
G03X1270654Y91437I410J-2270D01*
G01X1270621Y91351D01*
G02X1270552Y91322I-111J166D01*
G01X1270358Y91281D01*
X1270356D01*
X1270215Y91251D01*
G02X1270159Y91252I-24J199D01*
G01X1269129Y92282D01*
G03X1267497Y92958I-1632J-1632D01*
G03X1265189Y90650I0J-2308D01*
G03X1265865Y89018I2308J0D01*
G01X1267860Y87023D01*
G03X1269491Y86347I1632J1632D01*
G01X1269493D01*
G03X1269548Y86348I-14J2308D01*
G01X1284322D01*
G02X1284482Y86268I0J-200D01*
G01X1284540Y86191D01*
X1284577Y86142D01*
G02X1284610Y86062I-164J-114D01*
G01X1284619Y86017D01*
X1284605Y85970D01*
Y85968D01*
G03X1284542Y85539I1439J-430D01*
G03X1284948Y84512I1502J0D01*
G01X1284976Y84482D01*
X1284989Y84448D01*
G02X1284992Y84441I-182J-82D01*
G02X1285002Y84377I-190J-63D01*
G01Y84101D01*
G02X1284992Y84037I-200J-1D01*
G02X1284989Y84030I-185J75D01*
G01X1284976Y83996D01*
X1284948Y83966D01*
G03Y81912I1096J-1027D01*
G01X1284976Y81882D01*
X1284989Y81848D01*
G02X1284992Y81841I-182J-82D01*
G02X1285002Y81777I-190J-63D01*
G01Y81501D01*
G02X1284992Y81437I-200J-1D01*
G02X1284989Y81430I-185J75D01*
G01X1284976Y81396D01*
X1284948Y81366D01*
G03Y79312I1096J-1027D01*
G01X1284976Y79282D01*
X1284989Y79248D01*
G02X1284992Y79241I-182J-82D01*
G02X1285002Y79177I-190J-63D01*
G01Y78901D01*
G02X1284992Y78837I-200J-1D01*
G02X1284989Y78830I-185J75D01*
G01X1284976Y78796D01*
X1284948Y78766D01*
G03Y76712I1096J-1027D01*
G01X1284976Y76682D01*
X1284989Y76648D01*
G02X1284992Y76641I-182J-82D01*
G02X1285002Y76577I-190J-63D01*
G01Y76301D01*
G02X1284992Y76237I-200J-1D01*
G02X1284989Y76230I-185J75D01*
G01X1284976Y76196D01*
X1284948Y76166D01*
G03X1284542Y75139I1096J-1027D01*
G03X1287546I1502J0D01*
G03X1287140Y76166I-1502J0D01*
G01X1287112Y76196D01*
X1287099Y76230D01*
G02X1287096Y76237I182J82D01*
G02X1287086Y76301I190J63D01*
G01Y76577D01*
G02X1287096Y76641I200J1D01*
G02X1287099Y76648I185J-75D01*
G01X1287112Y76682D01*
X1287140Y76712D01*
G03Y78766I-1096J1027D01*
G01X1287112Y78796D01*
X1287099Y78830D01*
G02X1287096Y78837I182J82D01*
G02X1287086Y78901I190J63D01*
G01Y79177D01*
G02X1287096Y79241I200J1D01*
G02X1287099Y79248I185J-75D01*
G01X1287112Y79282D01*
X1287140Y79312D01*
G03Y81366I-1096J1027D01*
G01X1287112Y81396D01*
X1287099Y81430D01*
G02X1287096Y81437I182J82D01*
G02X1287086Y81501I190J63D01*
G01Y81777D01*
G02X1287096Y81841I200J1D01*
G02X1287099Y81848I185J-75D01*
G01X1287112Y81882D01*
X1287140Y81912D01*
G03Y83966I-1096J1027D01*
G01X1287112Y83996D01*
X1287099Y84030D01*
G02X1287096Y84037I182J82D01*
G02X1287086Y84101I190J63D01*
G01Y84377D01*
G02X1287096Y84441I200J1D01*
G02X1287099Y84448I185J-75D01*
G01X1287112Y84482D01*
X1287140Y84512D01*
G03X1287546Y85539I-1096J1027D01*
G03X1287483Y85969I-1502J0D01*
G01Y85970D01*
G02X1287478Y86063I192J57D01*
G01X1287486Y86108D01*
X1287548Y86191D01*
X1287606Y86268D01*
G02X1287766Y86348I160J-120D01*
G01X1304986D01*
G02X1305024Y86344I-2J-200D01*
G02X1305126Y86291I-37J-196D01*
G01X1306412Y85005D01*
G02X1306414Y84976I-198J-28D01*
G01Y84913D01*
X1306402Y84867D01*
X1306385Y84834D01*
G03X1306215Y84143I1332J-694D01*
G01Y84110D01*
G03X1307717Y82638I1502J30D01*
G01X1307718D01*
G03X1307781Y82639I8J1502D01*
G01X1307823Y82641D01*
X1307859Y82628D01*
G02X1307928Y82584I-71J-187D01*
G01X1308136Y82384D01*
G02X1308158Y82359I-139J-144D01*
G01Y44328D01*
G03X1308834Y42697I2307J1D01*
G01X1310861Y40670D01*
G03X1312492Y39994I1632J1631D01*
G01X1315713D01*
G03X1317344Y40670I-1J2307D01*
G01X1320490Y43816D01*
G03X1321166Y45447I-1631J1632D01*
G01Y45504D01*
X1321165Y45527D01*
G03X1318859Y47754I-2305J-79D01*
G03X1317228Y47079I-1J-2306D01*
G01X1317040Y46891D01*
G02X1317030Y46889I-44J195D01*
G01X1316702Y46898D01*
G02X1316680Y46901I16J199D01*
G01X1316625Y46964D01*
G03X1316518Y47079I-1741J-1513D01*
G01X1315058Y48539D01*
G02X1315045Y48555I149J134D01*
G02X1315010Y48669I165J113D01*
G01Y53717D01*
Y53718D01*
G02X1315031Y53805I200J-2D01*
G02X1315051Y53838I180J-87D01*
G02X1315197Y53957I319J-242D01*
G02X1315205Y53961I93J-177D01*
G02X1315225Y53969I159J-367D01*
G01X1315227D01*
G02X1315439Y53924I71J-187D01*
G01X1323613Y45750D01*
G02X1323666Y45648I-143J-139D01*
G02X1323670Y45610I-196J-40D01*
G01Y39185D01*
G02X1323648Y39094I-200J0D01*
G01X1323626Y39051D01*
X1323623Y39049D01*
X1323526Y38980D01*
G02X1323385Y38945I-115J163D01*
G01X1323374Y38947D01*
X1323348Y38956D01*
G03X1322855Y39039I-494J-1426D01*
G01X1322853D01*
G03Y36021I0J-1509D01*
G01X1322856D01*
G03X1323348Y36104I-2J1509D01*
G01X1323386Y36117D01*
X1323393Y36118D01*
G02X1323516Y36088I16J-200D01*
G01X1323585Y36039D01*
G02X1323640Y35981I-115J-164D01*
G02X1323670Y35875I-170J-105D01*
G01Y29673D01*
G03X1324346Y28042I2307J1D01*
G01X1326686Y25702D01*
G03X1328318Y25026I1632J1632D01*
G03X1330624Y27333I0J2306D01*
G03X1329949Y28964I-2306J1D01*
G01X1328991Y29922D01*
G02X1328989Y29962I198J30D01*
G01X1329020Y30197D01*
Y30199D01*
X1329031Y30279D01*
G02X1329054Y30348I198J-28D01*
G01X1329127Y30389D01*
G03X1330206Y31720I-1124J2014D01*
G01Y31721D01*
X1330218Y31760D01*
X1330231Y31799D01*
X1330254Y31812D01*
X1330497Y31940D01*
G02X1330620Y31961I93J-176D01*
G01X1330651Y31957D01*
X1330663Y31954D01*
G03X1331072Y31898I406J1447D01*
G01X1331079D01*
G03X1331131Y31899I-3J1502D01*
G01X1331156D01*
X1331163Y31900D01*
X1331216Y31905D01*
G03X1332575Y33400I-143J1495D01*
G03X1331078Y34902I-1502J0D01*
G01X1331071D01*
G03X1330754Y34868I1J-1502D01*
G01X1330711Y34859D01*
X1330667Y34869D01*
G02X1330585Y34909I44J195D01*
G01X1330436Y35030D01*
X1330345Y35103D01*
G02X1330310Y35139I125J156D01*
G01Y47183D01*
G03X1329634Y48814I-2307J-1D01*
G01X1320934Y57513D01*
G02X1320898Y57563I142J140D01*
G02X1320876Y57654I178J91D01*
G01Y102018D01*
G02X1320887Y102083I200J0D01*
G01X1320897Y102112D01*
X1320915Y102136D01*
X1321017Y102167D01*
G03X1321672Y102576I-452J1453D01*
G03X1322034Y103218I-1105J1046D01*
G01X1322043Y103250D01*
X1325752Y106959D01*
G03X1326134Y107881I-924J923D01*
G01Y118801D01*
G03X1325752Y119723I-1306J-1D01*
G01X1321890Y123585D01*
G02X1321854Y123635I142J140D01*
G02X1321832Y123726I178J91D01*
G01Y138705D01*
G02X1321836Y138743I200J-2D01*
G02X1321889Y138845I196J-37D01*
G01X1343034Y159990D01*
G03X1343416Y160912I-924J923D01*
G01Y263845D01*
G02X1343418Y263877I200J4D01*
G02X1343473Y263985I198J-33D01*
G01X1348548Y269059D01*
X1351044Y271555D01*
G03X1351048Y271559I-922J926D01*
G03X1351232Y271791I-925J923D01*
G01X1351244Y271811D01*
X1351541Y272108D01*
G03X1351600Y272250I-141J142D01*
G01Y294417D01*
G02X1351659Y294559I200J0D01*
G01X1372723Y315623D01*
G02X1372865Y315682I142J-141D01*
G01X1391306D01*
G02X1391344Y315686I40J-196D01*
G01X1394465D01*
G02X1394496Y315683I-4J-200D01*
G01X1418659Y291520D01*
G02X1418712Y291418I-143J-139D01*
G02X1418716Y291380I-196J-40D01*
G01Y174028D01*
G02X1418694Y173937I-200J0D01*
G02X1418658Y173887I-178J90D01*
G01X1399494Y154723D01*
G03X1399112Y153801I924J-923D01*
G01Y144651D01*
G02X1399104Y144596I-200J1D01*
G01X1399084Y144524D01*
X1399076Y144509D01*
G03X1399034Y144433I1293J-764D01*
G01Y144431D01*
G03X1398943Y144207I1342J-676D01*
G01X1398936Y144184D01*
X1398911Y144142D01*
X1393027Y138258D01*
G03X1392644Y137334I923J-924D01*
G01Y127601D01*
G02X1392627Y127581I-161J119D01*
G01X1392420Y127411D01*
X1392376Y127375D01*
G02X1392327Y127345I-128J154D01*
G01X1392244Y127363D01*
G03X1391765Y127414I-482J-2256D01*
G03X1389458Y125107I0J-2307D01*
G01Y121166D01*
G02X1389414Y121123I-160J120D01*
G01X1389277Y121039D01*
X1389129Y120948D01*
G02X1389088Y120929I-104J171D01*
G01X1389079Y120926D01*
G02X1388934Y120940I-55J192D01*
G01X1388933D01*
X1388891Y120961D01*
G03X1388232Y121112I-660J-1367D01*
G01X1388231D01*
G03X1386713Y119594I0J-1518D01*
G03X1387289Y118404I1517J0D01*
G02X1387345Y118335I-124J-157D01*
G01X1387363Y118298D01*
X1387364Y118296D01*
G02X1387385Y118207I-179J-89D01*
G01Y117983D01*
G02X1387367Y117900I-200J0D01*
G01X1387354Y117873D01*
Y117871D01*
X1387327Y117817D01*
G02X1387294Y117772I-176J95D01*
G01X1387275Y117753D01*
X1387268Y117747D01*
G03X1386729Y116594I964J-1153D01*
G03X1388231Y115092I1502J0D01*
G03X1389308Y115547I0J1502D01*
G01X1389335Y115575D01*
X1389475Y115637D01*
X1389524Y115635D01*
X1389525D01*
X1389571Y115604D01*
G02X1389642Y115518I-113J-165D01*
G01X1389671Y115452D01*
G03X1389676Y115442I181J84D01*
G01X1389704Y115386D01*
G03X1390134Y114791I2061J1036D01*
G01X1399744Y105181D01*
G02X1399757Y105165I-149J-134D01*
G02X1399792Y105051I-165J-113D01*
G01Y95111D01*
G03X1404404I2306J0D01*
G01Y105214D01*
G02X1404423Y105236I160J-119D01*
G02X1404445Y105254I137J-145D01*
G01X1405662D01*
G02X1405750Y105234I1J-200D01*
G03X1405767Y105225I714J1329D01*
G01X1405770Y105223D01*
X1405827Y105152D01*
G02X1405853Y105109I-157J-124D01*
G01X1405862Y105090D01*
X1405838Y104983D01*
X1405836Y104974D01*
G02X1405795Y104892I-195J46D01*
G01X1405725Y104806D01*
X1405695Y104782D01*
X1405671Y104771D01*
G03X1404806Y103411I637J-1360D01*
G03X1407810I1502J0D01*
G03X1407231Y104596I-1502J0D01*
G01X1407213Y104610D01*
X1407176Y104656D01*
G02X1407130Y104783I154J128D01*
G01Y104793D01*
X1407136Y104914D01*
Y104916D01*
X1407146Y105071D01*
G02X1407147Y105082I200J-13D01*
G02X1407173Y105159I199J-24D01*
G01X1407189Y105186D01*
X1407209Y105218D01*
G02X1407238Y105255I171J-104D01*
G01X1407260Y105277D01*
X1407278Y105288D01*
G03X1407976Y106561I-812J1273D01*
G03X1406467Y108070I-1509J0D01*
G01X1406466D01*
G03X1405765Y107897I1J-1509D01*
G01X1405755Y107892D01*
X1405685Y107874D01*
G02X1405636Y107868I-49J194D01*
G01X1405033D01*
X1405014Y107888D01*
G03X1405007Y107894I-134J-149D01*
G01X1405002Y107898D01*
X1395265Y117635D01*
G02X1395258Y117644I154J127D01*
G01Y136710D01*
G02X1395262Y136748I200J-2D01*
G02X1395315Y136850I196J-37D01*
G01X1400778Y142313D01*
X1400804Y142321D01*
G03X1401881Y143749I-425J1441D01*
G01Y143776D01*
G03X1401831Y144148I-1502J-13D01*
G03X1401786Y144290I-1453J-382D01*
G01X1401774Y144322D01*
X1401752Y144375D01*
G03X1401744Y144393I-1378J-601D01*
G01X1401740Y144402D01*
X1401733Y144416D01*
X1401724Y144456D01*
Y153175D01*
G02X1401734Y153237I200J0D01*
G02X1401782Y153316I190J-62D01*
G01X1420947Y172480D01*
G03X1421330Y173404I-923J924D01*
G01Y261216D01*
G02X1421435Y261391I200J-1D01*
G01X1421455Y261399D01*
G02X1421571Y261411I78J-184D01*
G01X1421597Y261406D01*
X1421649Y261378D01*
X1425071Y257956D01*
G03X1425993Y257574I923J924D01*
G01X1428504D01*
X1428515Y257568D01*
G03X1429979I732J1313D01*
G01X1429990Y257574D01*
X1442011D01*
G02X1442052Y257570I1J-200D01*
G02X1442152Y257516I-41J-196D01*
G01X1447651Y252016D01*
X1447768Y251899D01*
G03X1448545Y251525I923J924D01*
G01X1448579Y251521D01*
X1448609Y251507D01*
G02X1448663Y251468I-89J-179D01*
G01X1449223Y250908D01*
G03X1449687Y250613I895J896D01*
G01X1449692D01*
X1449757Y250588D01*
X1449765Y250585D01*
X1449779Y250581D01*
G03X1449803Y250576I53J194D01*
G01X1449806D01*
X1449824Y250573D01*
X1449829Y250572D01*
X1449832Y250571D01*
X1449834D01*
G03X1449982Y250545I293J1232D01*
G01X1449983D01*
X1449993Y250544D01*
G03X1450119Y250538I123J1260D01*
G01X1458532D01*
G02X1458558Y250536I-2J-200D01*
G01X1458560D01*
G02X1458695Y250455I-27J-198D01*
G02X1458717Y250414I-164J-114D01*
G01X1458763Y250303D01*
Y250301D01*
X1458788Y250240D01*
G03X1458824Y250182I185J75D01*
G01X1458831Y250174D01*
G02X1458870Y250097I-155J-127D01*
G01X1458878Y250051D01*
X1458875Y250027D01*
G02X1458860Y249970I-199J22D01*
G01X1458808Y249848D01*
X1458781Y249821D01*
G03X1458348Y248800I1069J-1056D01*
G01Y248742D01*
G03X1459794Y247264I1502J23D01*
G01X1459795D01*
G03X1459850Y247263I55J1501D01*
G01X1459852D01*
G03X1460786Y247590I-1J1501D01*
G01X1460812Y247610D01*
X1460856Y247625D01*
G02X1460909Y247633I56J-192D01*
G01X1460995D01*
G03X1461078Y247651I0J200D01*
G01X1461132Y247676D01*
G02X1461210Y247695I85J-181D01*
G02X1461244Y247693I5J-200D01*
G02X1461348Y247645I-28J-198D01*
G01X1461349Y247644D01*
G03X1461691Y247415I999J1123D01*
G03X1461749Y247388I663J1348D01*
G01X1461767Y247380D01*
G03X1462345Y247263I581J1385D01*
G01X1462371D01*
G03X1462831Y247342I-21J1502D01*
G03X1463284Y247589I-482J1423D01*
G01X1463285Y247590D01*
X1463297Y247600D01*
G02X1463403Y247633I110J-167D01*
G01X1463495D01*
G03X1463578Y247651I0J200D01*
G01X1463632Y247676D01*
G02X1463710Y247695I85J-181D01*
G02X1463744Y247693I5J-200D01*
G02X1463848Y247645I-28J-198D01*
G01X1463849Y247644D01*
G03X1464848Y247263I1000J1122D01*
G01X1464850D01*
G03X1466352Y248765I0J1502D01*
G03X1465919Y249820I-1502J0D01*
G01X1465918Y249821D01*
X1465893Y249847D01*
X1465869Y249900D01*
X1465861Y249918D01*
G02X1465856Y249933I187J71D01*
G01X1465842Y250002D01*
G02X1465851Y250088I199J23D01*
G01X1465937Y250301D01*
Y250303D01*
X1465982Y250413D01*
G02X1466116Y250531I185J-75D01*
G01X1466148Y250540D01*
X1466181Y250538D01*
X1468860D01*
G02X1468892Y250535I-3J-200D01*
G01X1468894D01*
G02X1469000Y250481I-34J-197D01*
G01X1469924Y249557D01*
G02X1469977Y249456I-143J-140D01*
G01Y249454D01*
G02X1469981Y249417I-196J-40D01*
G01Y227782D01*
G02X1469979Y227755I-200J1D01*
G01X1469971Y227711D01*
G02X1469960Y227674I-197J38D01*
G01X1469944Y227634D01*
X1469937Y227617D01*
G02X1469911Y227574I-183J81D01*
G01X1469903Y227565D01*
X1469894Y227553D01*
X1469893Y227552D01*
X1469891Y227549D01*
G03X1469708Y227247I982J-801D01*
G01Y227245D01*
G03X1469695Y227213I1167J-493D01*
G02X1469685Y227192I-185J75D01*
G02X1469668Y227165I-177J93D01*
G01Y227164D01*
G03X1469408Y226383I1046J-782D01*
G01Y222748D01*
G02X1469317Y222680I-160J120D01*
G01X1469146Y222617D01*
X1468964Y222550D01*
G02X1468934Y222542I-66J189D01*
G02X1468843Y222545I-39J196D01*
G01X1468814Y222553D01*
X1468762Y222586D01*
X1468742Y222610D01*
G03X1467593Y223144I-1149J-969D01*
G03Y220140I0J-1502D01*
G03X1468720Y220648I0J1504D01*
G01X1468743Y220674D01*
X1468795Y220709D01*
G02X1468821Y220722I102J-172D01*
G03X1468823Y220724I-140J142D01*
G02X1468970Y220731I82J-182D01*
G01X1468973Y220730D01*
X1469317Y220604D01*
G02X1469408Y220537I-68J-188D01*
G01Y216980D01*
G03X1469790Y216058I1306J1D01*
G01X1477365Y208483D01*
X1477390Y208441D01*
X1477397Y208418D01*
G03X1478832Y207362I1435J447D01*
G03X1480334Y208864I0J1502D01*
G01X1480335D01*
G03X1479278Y210299I-1503J0D01*
G01X1479277D01*
G02X1479195Y210349I60J191D01*
G01X1472146Y217398D01*
G02X1472144Y217427I198J28D01*
G01Y222719D01*
G02X1472225Y222879I200J-1D01*
G01X1472480Y223068D01*
G02X1472634Y223105I120J-160D01*
G01X1472661Y223100D01*
X1472674Y223096D01*
G03X1473101Y223034I427J1440D01*
G01X1473102D01*
G03X1473117I7J1502D01*
G01X1473126D01*
G03X1473165Y223035I-19J1502D01*
G01X1473184Y223036D01*
X1473185D01*
G03X1474556Y224160I-83J1500D01*
G01X1474563Y224187D01*
X1474576Y224209D01*
G02X1474604Y224247I174J-99D01*
G01X1474856Y224498D01*
X1474860Y224503D01*
X1476179Y225822D01*
G03X1476238Y225964I-141J142D01*
G01Y227546D01*
G02X1476250Y227613I200J-1D01*
G01X1476281Y227701D01*
X1476300Y227726D01*
G03X1476536Y228185I-1198J906D01*
G01X1476543Y228208D01*
X1476568Y228250D01*
X1478342Y230024D01*
G03X1478724Y230946I-924J923D01*
G01Y247158D01*
G02X1478729Y247202I200J0D01*
G02X1478838Y247338I195J-45D01*
G02X1478856Y247346I90J-178D01*
G01X1479212Y247474D01*
G02X1479332Y247478I66J-189D01*
G01X1479361Y247470D01*
X1479412Y247437D01*
X1479432Y247413D01*
G03X1480589Y246869I1157J958D01*
G03Y249873I0J1502D01*
G03X1479432Y249329I0J-1502D01*
G01X1479431Y249328D01*
G02X1479331Y249263I-154J128D01*
G01X1479302Y249255D01*
X1479241Y249258D01*
X1478856Y249396D01*
G02X1478838Y249404I72J186D01*
G02X1478729Y249540I86J181D01*
G02X1478724Y249584I195J44D01*
G01Y302547D01*
G03X1478342Y303469I-1306J-1D01*
G01X1465580Y316230D01*
G02X1465530Y316316I142J140D01*
G02X1465522Y316371I192J56D01*
G01Y364525D01*
G02X1465540Y364546I160J-119D01*
G01X1466291Y365297D01*
G02X1466392Y365350I140J-143D01*
G01X1466394D01*
G02X1466431Y365354I40J-196D01*
G01X1471419D01*
G02X1471446Y365352I-1J-200D01*
G01X1476563Y360235D01*
G02X1476565Y360215I-198J-30D01*
G01X1476564Y360064D01*
X1476563Y359962D01*
G02X1476547Y359884I-200J0D01*
G01X1476502Y359779D01*
X1476476Y359752D01*
X1476475Y359751D01*
G03X1476047Y358700I1076J-1051D01*
G03X1477549Y357198I1502J0D01*
G01X1477559D01*
G03X1477561I1J1502D01*
G01X1477566D01*
G03X1477606Y357199I-18J1502D01*
G02X1477661Y357189I-8J-200D01*
G01X1477670Y357186D01*
G02X1477736Y357145I-71J-187D01*
G01X1477825Y357063D01*
G02X1477850Y357035I-136J-146D01*
G01Y355864D01*
G02X1477825Y355836I-161J119D01*
G01X1477734Y355753D01*
G02X1477599Y355701I-135J148D01*
G01X1477594D01*
G03X1477561Y355702I-62J-1500D01*
G01X1477549D01*
G03Y352698I0J-1502D01*
G01X1477559D01*
G03X1477561I1J1502D01*
G01X1477566D01*
G03X1477606Y352699I-18J1502D01*
G02X1477661Y352689I-8J-200D01*
G01X1477670Y352686D01*
G02X1477736Y352645I-71J-187D01*
G01X1477825Y352563D01*
G02X1477850Y352535I-136J-146D01*
G01Y351364D01*
G02X1477824Y351336I-159J121D01*
G01X1477709Y351232D01*
X1477704Y351227D01*
X1477633Y351200D01*
X1477595Y351201D01*
X1477593D01*
G03X1477573Y351202I-85J-1499D01*
G01X1477558D01*
G03X1477556I-1J-1502D01*
G01X1477544D01*
G03X1476047Y349705I5J-1502D01*
G01Y349669D01*
G03X1477401Y348205I1502J31D01*
G01X1477402D01*
X1477412Y348204D01*
G03X1477434Y348202I147J1495D01*
G01X1477435D01*
X1477462Y348200D01*
G03X1477505Y348198I91J1500D01*
G01X1477532D01*
G03X1477548I8J1502D01*
G01X1477550D01*
G03X1478608Y348634I0J1502D01*
G03X1478793Y348857I-1059J1067D01*
G01X1478803Y348873D01*
X1478859Y348929D01*
G02X1478950Y348962I112J-166D01*
G01X1479114Y348978D01*
X1479116D01*
X1479169Y348984D01*
X1479171D01*
X1479255Y348993D01*
X1479300Y348998D01*
X1484729Y343569D01*
G03X1486359Y342894I1630J1631D01*
G01X1486360D01*
G03X1488666Y345200I0J2306D01*
G01Y345201D01*
G03X1487991Y346831I-2306J0D01*
G01X1487506Y347315D01*
G02X1487505Y347366I198J29D01*
G01X1487515Y347463D01*
Y347465D01*
X1487535Y347641D01*
G02X1487560Y347709I197J-34D01*
G01X1487579Y347741D01*
X1487622Y347769D01*
G03X1488666Y349700I-1262J1930D01*
G03X1487991Y351331I-2306J1D01*
G01X1485162Y354160D01*
G02X1485126Y354210I142J140D01*
G02X1485104Y354301I178J91D01*
G01Y359824D01*
G03X1484428Y361455I-2307J-1D01*
G01X1478187Y367695D01*
G02X1478151Y367745I142J140D01*
G02X1478129Y367836I178J91D01*
G01Y371693D01*
G02X1478133Y371730I200J-3D01*
G01Y371732D01*
G02X1478186Y371833I196J-39D01*
G01X1478559Y372206D01*
G02X1478660Y372259I140J-143D01*
G01X1478662D01*
G02X1478699Y372263I40J-196D01*
G01X1483999D01*
G02X1484136Y372208I-1J-200D01*
G01X1485996Y370349D01*
G02X1486004Y370340I-145J-137D01*
G01X1486009Y370335D01*
G02X1486039Y370134I-155J-126D01*
G01X1486017Y370084D01*
X1486008Y370061D01*
G02X1485984Y370023I-180J87D01*
G01X1485980Y370017D01*
G02X1485978Y370015I-142J140D01*
G01X1485962Y369995D01*
X1485937Y369978D01*
G03X1485195Y368576I954J-1402D01*
G03X1486890Y366881I1695J0D01*
G03X1488296Y367628I0J1697D01*
G01X1488306Y367644D01*
X1488365Y367703D01*
G02X1488373Y367708I110J-167D01*
G01X1488393Y367720D01*
X1488438Y367733D01*
X1488483Y367736D01*
X1488514Y367738D01*
G02X1488646Y367696I9J-200D01*
G02X1488664Y367680I-124J-157D01*
G01X1491538Y364806D01*
G02X1491556Y364785I-142J-140D01*
G01Y305653D01*
G02X1491555Y305632I-200J-1D01*
G02X1491500Y305514I-199J21D01*
G01X1489690Y303705D01*
G03X1489308Y302783I924J-923D01*
G01Y269322D01*
G03X1489690Y268400I1306J1D01*
G01X1499626Y258464D01*
G02X1499611Y258353I-198J-30D01*
G01X1499535Y258183D01*
X1499453Y258000D01*
G02X1499380Y257922I-177J93D01*
G01X1499354Y257906D01*
X1499295Y257891D01*
X1499273Y257892D01*
X1499264Y257893D01*
G03X1499171Y257896I-95J-1499D01*
G03X1500673Y256394I0J-1502D01*
G03X1500670Y256494I-1502J5D01*
G01X1500669Y256510D01*
X1500674Y256537D01*
G02X1500679Y256558I197J-36D01*
G01X1500684Y256571D01*
G02X1500778Y256677I187J-71D01*
G01X1501136Y256838D01*
G02X1501240Y256850I74J-186D01*
G01X1502863Y255227D01*
X1506160Y251931D01*
G02X1506214Y251829I-142J-141D01*
G02X1506218Y251790I-196J-40D01*
G01Y248568D01*
X1506216Y248563D01*
X1506177Y248534D01*
X1506176D01*
X1505990Y248394D01*
X1505917Y248339D01*
G02X1505911Y248335I-114J165D01*
G01X1505889Y248323D01*
G02X1505788Y248303I-88J180D01*
G01X1505759Y248307D01*
X1505741Y248312D01*
G03X1505306Y248376I-434J-1438D01*
G01X1505304D01*
G03X1503802Y246874I0J-1502D01*
G03X1505302Y245372I1502J0D01*
G01X1505310D01*
G03X1505875Y245485I-7J1502D01*
G01X1505893Y245492D01*
X1505932Y245500D01*
G02X1506054Y245487I41J-196D01*
G01X1506055Y245486D01*
X1506072Y245478D01*
G02X1506146Y245406I-98J-175D01*
G02X1506157Y245382I-176J-95D01*
G01X1506202Y245277D01*
G02X1506217Y245219I-184J-79D01*
G02X1506218Y245199I-199J-20D01*
G01Y245040D01*
X1506207Y245019D01*
G03X1506101Y244777I1317J-721D01*
G03X1506022Y244307I1423J-481D01*
G01Y244280D01*
G03X1507511Y242795I1502J17D01*
G01X1507547D01*
G03X1508230Y242967I-15J1503D01*
G02X1508323Y242990I93J-177D01*
G01X1508904D01*
G02X1508942Y242986I-2J-200D01*
G02X1509044Y242933I-37J-196D01*
G01X1511134Y240843D01*
G02X1511136Y240814I-198J-28D01*
G01Y231774D01*
G02X1511037Y231602I-200J1D01*
G01X1510750Y231434D01*
G02X1510657Y231409I-97J175D01*
G01X1510604D01*
X1510557Y231436D01*
G03X1509807Y231635I-751J-1319D01*
G03Y228599I0J-1518D01*
G01X1509808D01*
G03X1510558Y228797I1J1517D01*
G01X1510574Y228806D01*
G02X1510661Y228824I83J-182D01*
G01X1510712Y228823D01*
X1510803Y228769D01*
X1510805D01*
X1511038Y228631D01*
G02X1511062Y228614I-103J-171D01*
G02X1511136Y228459I-126J-155D01*
G01Y215978D01*
G02X1511120Y215921I-198J25D01*
G01X1510998Y215870D01*
G02X1510824Y215895I-61J191D01*
G02X1510795Y215919I112J165D01*
G01X1497688Y229027D01*
X1497663Y229069D01*
X1497656Y229092D01*
G03X1496221Y230148I-1435J-447D01*
G03X1494719Y228646I0J-1502D01*
G01X1494718D01*
G03X1495775Y227211I1503J0D01*
G01X1495776D01*
G02X1495858Y227161I-60J-191D01*
G01X1509711Y213308D01*
G02X1509764Y213206I-143J-139D01*
G02X1509768Y213168I-196J-40D01*
G01Y181860D01*
G02X1509709Y181718I-200J0D01*
G01X1486726Y158734D01*
G02X1486650Y158687I-141J142D01*
G02X1486585Y158676I-65J189D01*
G01X1475461D01*
X1475444Y158685D01*
G03X1474718Y158872I-726J-1317D01*
G01X1474716D01*
G03Y155868I0J-1502D01*
G01X1474717D01*
G03X1475448Y156058I-1J1504D01*
G01X1475459Y156064D01*
X1485567D01*
G02X1485747Y155951I0J-200D01*
G01X1485752Y155939D01*
G02X1485763Y155821I-185J-77D01*
G01X1485758Y155795D01*
X1485731Y155745D01*
X1472598Y142612D01*
G02X1472548Y142576I-140J142D01*
G02X1472457Y142554I-91J178D01*
G01X1468654D01*
G02X1468616Y142592I121J159D01*
G01X1468493Y142763D01*
X1468428Y142854D01*
G02X1468395Y142960I167J110D01*
G01Y143039D01*
X1468404Y143069D01*
G03X1468473Y143518I-1433J450D01*
G03X1466971Y145020I-1502J0D01*
G03X1465469Y143529I0J-1502D01*
G01Y143515D01*
G03X1465538Y143066I1502J1D01*
G01X1465541Y143056D01*
X1465547Y143037D01*
X1465553Y142986D01*
G02X1465522Y142864I-199J-14D01*
G01X1465447Y142759D01*
X1465325Y142590D01*
G02X1465288Y142554I-157J124D01*
G01X1463279D01*
G02X1463186Y142577I0J200D01*
G03X1462487Y142749I-698J-1332D01*
G01X1462484D01*
G03Y139745I0J-1502D01*
G01X1462488D01*
G03X1463186Y139917I0J1504D01*
G02X1463279Y139940I93J-177D01*
G01X1471440D01*
G02X1471615Y139835I-1J-200D01*
G01X1471623Y139815D01*
G02X1471635Y139699I-184J-78D01*
G01X1471630Y139673D01*
X1471602Y139621D01*
X1462376Y130395D01*
G03X1461994Y129473I924J-923D01*
G01Y117197D01*
G03X1462376Y116275I1306J1D01*
G01X1464914Y113738D01*
G02X1464970Y113626I-142J-141D01*
G02X1464972Y113597I-198J-28D01*
G01Y113430D01*
G02X1464953Y113408I-160J119D01*
G02X1464931Y113390I-137J145D01*
G01X1454962D01*
G03X1454038Y113007I0J-1306D01*
G01X1450007Y108975D01*
G02X1449895Y108920I-140J143D01*
G02X1449867Y108918I-28J198D01*
G01X1445024D01*
G03X1444102Y108536I1J-1306D01*
G01X1440262Y104696D01*
G02X1440101Y104756I56J396D01*
G02X1439918Y105091I217J336D01*
G01Y107649D01*
G03X1436314I-1802J0D01*
G01Y105267D01*
X1436313Y104249D01*
G03X1437526Y102545I1803J0D01*
G01X1437544Y102539D01*
G02X1437654Y102408I-84J-182D01*
G01X1437658Y102394D01*
X1437686Y102269D01*
Y102267D01*
X1437689Y102254D01*
G02X1437635Y102069I-195J-43D01*
G01X1435494Y99927D01*
G02X1435355Y99868I-142J141D01*
G01X1429154D01*
X1429141D01*
G02X1429014Y99925I13J200D01*
G01X1428723Y100217D01*
X1428598Y100342D01*
X1428573Y100384D01*
X1428566Y100407D01*
G03X1427131Y101463I-1435J-447D01*
G03X1425629Y99961I0J-1502D01*
G01X1425628D01*
G03X1426685Y98526I1503J0D01*
G01X1426686D01*
G02X1426768Y98476I-60J-191D01*
G01X1426935Y98309D01*
G02Y98252I-198J-29D01*
G01X1425550Y96867D01*
G03X1424907Y95623I1631J-1631D01*
G01X1424890Y95526D01*
G02X1424816Y95481I-139J144D01*
G01X1424780Y95469D01*
X1424510Y95385D01*
X1424472Y95373D01*
G02X1424386Y95367I-57J192D01*
G01X1423593Y96160D01*
G03X1422671Y96542I-923J-924D01*
G01X1417993D01*
X1417976Y96551D01*
G03X1417250Y96738I-726J-1317D01*
G01X1417248D01*
G03Y93734I0J-1502D01*
G01X1417249D01*
G03X1417980Y93924I-1J1504D01*
G01X1417991Y93930D01*
X1422045D01*
X1422058D01*
G02X1422185Y93873I-13J-200D01*
G01X1422500Y93557D01*
X1422654Y93403D01*
G02X1422655Y93349I-198J-31D01*
G02X1422647Y93314I-198J27D01*
G01X1422610Y93203D01*
Y93201D01*
X1422526Y92928D01*
X1422497Y92902D01*
X1422400Y92885D01*
G03X1420655Y91437I410J-2270D01*
G01X1420622Y91351D01*
G02X1420553Y91322I-111J166D01*
G01X1420359Y91281D01*
X1420357D01*
X1420216Y91251D01*
G02X1420160Y91252I-24J199D01*
G01X1419130Y92282D01*
G03X1417498Y92958I-1632J-1632D01*
G03X1415190Y90650I0J-2308D01*
G03X1415866Y89018I2308J0D01*
G01X1417806Y87078D01*
G03X1419438Y86402I1632J1632D01*
G03X1419522Y86404I-13J2308D01*
G01X1434524D01*
G02X1434530Y86395I-163J-115D01*
G01X1434534Y86389D01*
X1434654Y86191D01*
Y86189D01*
X1434715Y86087D01*
G02X1434734Y86040I-174J-98D01*
G02X1434740Y85994I-194J-49D01*
G01X1434741Y85948D01*
X1434719Y85901D01*
X1434717Y85897D01*
G03X1434543Y85197I1328J-702D01*
G01Y85180D01*
G03X1434949Y84166I1502J13D01*
G01X1434976Y84138D01*
X1434990Y84103D01*
G02X1435000Y84067I-187J-71D01*
G02X1435003Y84032I-197J-35D01*
G01Y83755D01*
G02X1434993Y83691I-200J-1D01*
G02X1434990Y83684I-185J75D01*
G01X1434977Y83650D01*
X1434949Y83620D01*
G03Y81566I1096J-1027D01*
G01X1434977Y81536D01*
X1434990Y81502D01*
G02X1434993Y81495I-182J-82D01*
G02X1435003Y81431I-190J-63D01*
G01Y81155D01*
G02X1434993Y81091I-200J-1D01*
G02X1434990Y81084I-185J75D01*
G01X1434977Y81050D01*
X1434949Y81020D01*
G03Y78966I1096J-1027D01*
G01X1434977Y78936D01*
X1434990Y78902D01*
G02X1434993Y78895I-182J-82D01*
G02X1435003Y78831I-190J-63D01*
G01Y78555D01*
G02X1434993Y78491I-200J-1D01*
G02X1434990Y78484I-185J75D01*
G01X1434977Y78450D01*
X1434949Y78420D01*
G03Y76366I1096J-1027D01*
G01X1434977Y76336D01*
X1434990Y76302D01*
G02X1434993Y76295I-182J-82D01*
G02X1435003Y76231I-190J-63D01*
G01Y75955D01*
G02X1434993Y75891I-200J-1D01*
G02X1434990Y75884I-185J75D01*
G01X1434977Y75850D01*
X1434949Y75820D01*
G03X1434543Y74793I1096J-1027D01*
G03X1437547I1502J0D01*
G03X1437141Y75820I-1502J0D01*
G01X1437113Y75850D01*
X1437100Y75884D01*
G02X1437097Y75891I182J82D01*
G02X1437087Y75955I190J63D01*
G01Y76231D01*
G02X1437097Y76295I200J1D01*
G02X1437100Y76302I185J-75D01*
G01X1437113Y76336D01*
X1437141Y76366D01*
G03Y78420I-1096J1027D01*
G01X1437113Y78450D01*
X1437100Y78484D01*
G02X1437097Y78491I182J82D01*
G02X1437087Y78555I190J63D01*
G01Y78831D01*
G02X1437097Y78895I200J1D01*
G02X1437100Y78902I185J-75D01*
G01X1437113Y78936D01*
X1437141Y78966D01*
G03Y81020I-1096J1027D01*
G01X1437113Y81050D01*
X1437100Y81084D01*
G02X1437097Y81091I182J82D01*
G02X1437087Y81155I190J63D01*
G01Y81431D01*
G02X1437097Y81495I200J1D01*
G02X1437100Y81502I185J-75D01*
G01X1437113Y81536D01*
X1437141Y81566D01*
G03Y83620I-1096J1027D01*
G01X1437113Y83650D01*
X1437100Y83684D01*
G02X1437097Y83691I182J82D01*
G02X1437087Y83755I190J63D01*
G01Y84032D01*
G02X1437090Y84067I200J0D01*
G02X1437100Y84103I197J-35D01*
G01X1437114Y84138D01*
X1437143Y84168D01*
G03X1437547Y85179I-1098J1025D01*
G01Y85195D01*
G03X1437373Y85897I-1502J0D01*
G01X1437367Y85908D01*
G02X1437350Y85993I183J81D01*
G01X1437351Y86046D01*
X1437436Y86189D01*
Y86191D01*
X1437556Y86388D01*
G02X1437567Y86404I170J-105D01*
G01X1454932D01*
G02X1455046Y86369I1J-200D01*
G02X1455062Y86356I-118J-162D01*
G01X1456413Y85005D01*
G02X1456415Y84976I-198J-28D01*
G01Y84913D01*
X1456403Y84867D01*
X1456386Y84834D01*
G03X1456216Y84143I1332J-694D01*
G01Y84110D01*
G03X1457718Y82638I1502J30D01*
G01X1457733D01*
G03X1457768Y82639I-25J1502D01*
G01X1457788Y82640D01*
X1457834Y82631D01*
G02X1457911Y82599I-37J-197D01*
G02X1457937Y82578I-112J-165D01*
G01X1458138Y82384D01*
G02X1458160Y82359I-139J-144D01*
G01Y78752D01*
X1458159Y76587D01*
G03X1458949Y74849I2307J0D01*
G01X1458992Y74812D01*
X1459000Y74795D01*
G02X1459018Y74717I-182J-83D01*
G01X1459024Y74497D01*
Y74494D01*
X1459026Y74437D01*
X1458835Y74246D01*
G03X1458160Y72615I1631J-1630D01*
G01X1458159Y72567D01*
G03X1460466Y70308I2307J49D01*
G01X1460502D01*
G03X1461359Y70488I-37J2307D01*
G03X1462098Y70984I-892J2127D01*
G01X1464336Y73222D01*
G03X1465012Y74853I-1631J1632D01*
G01Y84548D01*
G02X1465082Y84606I159J-121D01*
G01X1465365Y84726D01*
X1465367D01*
X1465436Y84754D01*
G02X1465542Y84767I76J-185D01*
G01X1467862Y82447D01*
G02X1467864Y82400I-197J-32D01*
G01X1467809Y82055D01*
G02X1467775Y81980I-196J43D01*
G01X1467755Y81953D01*
X1467733Y81942D01*
G03X1466875Y80581I650J-1361D01*
G03X1469893I1509J0D01*
G01Y80584D01*
G03X1469810Y81076I-1509J-2D01*
G01X1469797Y81114D01*
X1469796Y81121D01*
G02X1469828Y81247I200J16D01*
G01X1469833Y81254D01*
X1470020Y81516D01*
G02X1470023Y81520I162J-118D01*
G01X1476209D01*
G03X1477839Y82195I0J2306D01*
G01X1480059Y84415D01*
G03X1480734Y86045I-1631J1630D01*
G01Y86046D01*
G03X1478428Y88352I-2306J0D01*
G01X1478427D01*
G03X1476797Y87677I0J-2306D01*
G01X1476519Y87398D01*
G02X1476478Y87396I-30J198D01*
G01X1476358Y87497D01*
G03X1474874Y88038I-1484J-1765D01*
G01X1474253D01*
G02X1474217Y88073I120J160D01*
G01X1474144Y88164D01*
X1474014Y88325D01*
G02X1474004Y88341I165J114D01*
G02X1473986Y88388I176J94D01*
G01X1473973Y88438D01*
X1473975Y88445D01*
X1473983Y88485D01*
G03X1474016Y88791I-1469J313D01*
G03Y88793I-1502J1D01*
G01Y88816D01*
G03X1472690Y90293I-1502J-15D01*
G01X1472634Y90299D01*
G03X1472514Y90304I-123J-1498D01*
G03X1471504Y89914I0J-1503D01*
G01X1471502Y89912D01*
G02X1471402Y89864I-133J149D01*
G01X1471374Y89860D01*
X1471346Y89863D01*
G02X1471290Y89879I26J198D01*
G01X1471222Y89909D01*
X1470951Y90029D01*
G02X1470876Y90090I85J181D01*
G01Y102105D01*
G02X1470960Y102170I160J-120D01*
G01X1470992Y102180D01*
G03X1471732Y102672I-425J1441D01*
G03X1472001Y103173I-1165J948D01*
G02X1472003Y103177I178J-86D01*
G01X1472004Y103181D01*
G02X1472052Y103258I189J-65D01*
G01X1475736Y106942D01*
G03X1476118Y107864I-924J923D01*
G01Y118801D01*
G03X1475736Y119723I-1306J-1D01*
G01X1472012Y123447D01*
G02X1471976Y123497I142J140D01*
G02X1471954Y123588I178J91D01*
G01Y125954D01*
G02X1471997Y126078I200J0D01*
G01X1494607Y148689D01*
G02X1494680Y148685I26J-198D01*
G01X1494799Y148649D01*
X1494801D01*
X1494988Y148591D01*
G02X1495021Y148575I-70J-187D01*
G02X1495062Y148543I-102J-173D01*
G01X1495100Y148500D01*
X1495102Y148498D01*
X1495134Y148463D01*
G02X1495159Y148425I-154J-128D01*
G01X1495172Y148400D01*
X1495176Y148384D01*
X1495178Y148374D01*
G03X1496641Y147215I1463J344D01*
G03X1498143Y148717I0J1502D01*
G03X1496984Y150180I-1503J0D01*
G01X1496983D01*
X1496955Y150187D01*
X1496914Y150208D01*
X1496887Y150232D01*
X1496886Y150233D01*
X1496860Y150256D01*
X1496858Y150258D01*
X1496815Y150296D01*
G02X1496783Y150337I141J143D01*
G02X1496767Y150370I171J103D01*
G01X1496709Y150557D01*
Y150559D01*
X1496673Y150678D01*
G02X1496669Y150751I194J47D01*
G01X1520561Y174643D01*
G02X1520662Y174688I129J-153D01*
G02X1521118Y174293I56J-396D01*
G01Y174068D01*
G02X1521096Y173977I-200J0D01*
G02X1521060Y173927I-178J90D01*
G01X1501856Y154723D01*
G03X1501474Y153801I924J-923D01*
G01Y144651D01*
G02X1501466Y144596I-200J1D01*
G01X1501446Y144524D01*
X1501438Y144509D01*
G03X1501396Y144433I1293J-764D01*
G01Y144431D01*
G03X1501305Y144207I1342J-676D01*
G01X1501298Y144184D01*
X1501273Y144142D01*
X1495389Y138258D01*
G03X1495006Y137334I923J-924D01*
G01Y127601D01*
G02X1494989Y127581I-161J119D01*
G01X1494782Y127411D01*
X1494738Y127375D01*
G02X1494689Y127345I-128J154D01*
G01X1494606Y127363D01*
G03X1494127Y127414I-482J-2256D01*
G03X1491820Y125107I0J-2307D01*
G01Y121166D01*
G02X1491776Y121123I-160J120D01*
G01X1491639Y121039D01*
X1491491Y120948D01*
G02X1491450Y120929I-104J171D01*
G01X1491441Y120926D01*
G02X1491296Y120940I-55J192D01*
G01X1491295D01*
X1491253Y120961D01*
G03X1490594Y121112I-660J-1367D01*
G01X1490593D01*
G03X1489075Y119594I0J-1518D01*
G03X1489651Y118404I1517J0D01*
G02X1489707Y118335I-124J-157D01*
G01X1489725Y118298D01*
X1489726Y118296D01*
G02X1489747Y118207I-179J-89D01*
G01Y117983D01*
G02X1489729Y117900I-200J0D01*
G01X1489716Y117873D01*
Y117871D01*
X1489689Y117817D01*
G02X1489656Y117772I-176J95D01*
G01X1489637Y117753D01*
X1489630Y117747D01*
G03X1489091Y116594I964J-1153D01*
G03X1490593Y115092I1502J0D01*
G03X1491670Y115547I0J1502D01*
G01X1491697Y115575D01*
X1491837Y115637D01*
X1491894Y115635D01*
G02X1492057Y115525I-16J-200D01*
G01X1492058Y115523D01*
G03X1492496Y114911I2069J1018D01*
G01X1502106Y105301D01*
G02X1502119Y105285I-149J-134D01*
G02X1502154Y105171I-165J-113D01*
G01Y95111D01*
G03X1506766I2306J0D01*
G01Y105214D01*
G02X1506785Y105236I160J-119D01*
G02X1506807Y105254I137J-145D01*
G01X1508024D01*
G02X1508112Y105234I1J-200D01*
G03X1508129Y105225I714J1329D01*
G01X1508132Y105223D01*
X1508189Y105152D01*
G02X1508215Y105109I-157J-124D01*
G01X1508224Y105090D01*
X1508200Y104983D01*
X1508198Y104974D01*
G02X1508157Y104892I-195J46D01*
G01X1508087Y104806D01*
X1508057Y104782D01*
X1508033Y104771D01*
G03X1507168Y103411I637J-1360D01*
G03X1510172I1502J0D01*
G03X1509593Y104596I-1502J0D01*
G01X1509575Y104610D01*
X1509538Y104656D01*
G02X1509492Y104783I154J128D01*
G01Y104793D01*
X1509498Y104914D01*
Y104916D01*
X1509508Y105071D01*
G02X1509509Y105082I200J-13D01*
G02X1509535Y105159I199J-24D01*
G01X1509551Y105186D01*
X1509571Y105218D01*
G02X1509600Y105255I171J-104D01*
G01X1509622Y105277D01*
X1509640Y105288D01*
G03X1510338Y106561I-812J1273D01*
G03X1508829Y108070I-1509J0D01*
G01X1508828D01*
G03X1508127Y107897I1J-1509D01*
G01X1508117Y107892D01*
X1508047Y107874D01*
G02X1507998Y107868I-49J194D01*
G01X1507395D01*
X1507376Y107888D01*
G03X1507369Y107894I-134J-149D01*
G01X1507364Y107898D01*
X1497627Y117635D01*
G02X1497620Y117644I154J127D01*
G01Y136710D01*
G02X1497624Y136748I200J-2D01*
G02X1497677Y136850I196J-37D01*
G01X1503140Y142313D01*
X1503166Y142321D01*
G03X1504243Y143749I-425J1441D01*
G01Y143776D01*
G03X1504193Y144148I-1502J-13D01*
G03X1504148Y144290I-1453J-382D01*
G01X1504136Y144322D01*
X1504114Y144375D01*
G03X1504106Y144393I-1378J-601D01*
G01X1504102Y144402D01*
X1504095Y144416D01*
X1504086Y144456D01*
Y153175D01*
G02X1504096Y153237I200J0D01*
G02X1504144Y153316I190J-62D01*
G01X1523549Y172720D01*
G03X1523932Y173644I-923J924D01*
G01Y256180D01*
X1523933Y256185D01*
G02X1523946Y256242I199J-15D01*
G02X1523991Y256312I187J-71D01*
G01X1525234Y257555D01*
G02X1525256Y257574I141J-141D01*
G01X1530866D01*
X1530877Y257568D01*
G03X1532341I732J1313D01*
G01X1532352Y257574D01*
X1544605D01*
G02X1544648Y257569I-1J-200D01*
G02X1544746Y257516I-42J-195D01*
G01X1551362Y250899D01*
G03X1552286Y250516I924J923D01*
G01X1560986D01*
G02X1561074Y250425I-92J-177D01*
G01X1561125Y250303D01*
Y250301D01*
X1561150Y250240D01*
Y250239D01*
G03X1561167Y250206I186J75D01*
G01X1561172Y250198D01*
G02X1561195Y250135I-174J-99D01*
G01X1561196Y250129D01*
X1561212Y250027D01*
G02X1561199Y249915I-197J-34D01*
G01X1561170Y249848D01*
X1561143Y249821D01*
G03X1560710Y248800I1069J-1056D01*
G01Y248742D01*
G03X1562156Y247264I1502J23D01*
G01X1562157D01*
G03X1562212Y247263I55J1501D01*
G01X1562214D01*
G03X1563148Y247590I-1J1501D01*
G01X1563174Y247610D01*
X1563218Y247625D01*
G02X1563271Y247633I56J-192D01*
G01X1563357D01*
G03X1563440Y247651I0J200D01*
G01X1563494Y247676D01*
G02X1563572Y247695I85J-181D01*
G02X1563606Y247693I5J-200D01*
G02X1563710Y247645I-28J-198D01*
G01X1563711Y247644D01*
G03X1564053Y247415I999J1123D01*
G03X1564111Y247388I663J1348D01*
G01X1564129Y247380D01*
G03X1564707Y247263I581J1385D01*
G01X1564733D01*
G03X1565193Y247342I-21J1502D01*
G03X1565646Y247589I-482J1423D01*
G01X1565647Y247590D01*
X1565659Y247600D01*
G02X1565765Y247633I110J-167D01*
G01X1565857D01*
G03X1565940Y247651I0J200D01*
G01X1565994Y247676D01*
G02X1566072Y247695I85J-181D01*
G02X1566106Y247693I5J-200D01*
G02X1566210Y247645I-28J-198D01*
G01X1566211Y247644D01*
G03X1567210Y247263I1000J1122D01*
G01X1567212D01*
G03X1568714Y248765I0J1502D01*
G03X1568281Y249820I-1502J0D01*
G01X1568280Y249821D01*
X1568255Y249847D01*
X1568231Y249900D01*
X1568223Y249918D01*
G02X1568218Y249933I187J71D01*
G01X1568204Y250002D01*
G02X1568213Y250088I199J23D01*
G01X1568299Y250301D01*
Y250303D01*
X1568344Y250413D01*
G02X1568439Y250516I185J-75D01*
G01X1570078D01*
G02X1570128Y250481I-88J-179D01*
G01X1571751Y248858D01*
G02X1571770Y248836I-141J-141D01*
G01Y222748D01*
G02X1571679Y222680I-160J120D01*
G01X1571508Y222617D01*
X1571326Y222550D01*
G02X1571296Y222542I-66J189D01*
G02X1571205Y222545I-39J196D01*
G01X1571176Y222553D01*
X1571124Y222586D01*
X1571104Y222610D01*
G03X1569955Y223144I-1149J-969D01*
G03Y220140I0J-1502D01*
G03X1571082Y220648I0J1504D01*
G01X1571105Y220674D01*
X1571157Y220709D01*
G02X1571183Y220722I102J-172D01*
G03X1571185Y220724I-140J142D01*
G02X1571332Y220731I82J-182D01*
G01X1571335Y220730D01*
X1571679Y220604D01*
G02X1571770Y220537I-68J-188D01*
G01Y216980D01*
G03X1572152Y216058I1306J1D01*
G01X1579727Y208483D01*
X1579752Y208441D01*
X1579759Y208418D01*
G03X1581194Y207362I1435J447D01*
G03X1582696Y208864I0J1502D01*
G01X1582697D01*
G03X1581640Y210299I-1503J0D01*
G01X1581639D01*
G02X1581557Y210349I60J191D01*
G01X1574508Y217398D01*
G02X1574506Y217427I198J28D01*
G01Y222719D01*
G02X1574587Y222879I200J-1D01*
G01X1574842Y223068D01*
G02X1574996Y223105I120J-160D01*
G01X1575023Y223100D01*
X1575036Y223096D01*
G03X1575463Y223034I427J1440D01*
G01X1575464D01*
G03X1575479I8J1502D01*
G01X1575488D01*
G03X1575527Y223035I-19J1502D01*
G01X1575546Y223036D01*
X1575547D01*
G03X1575726Y223057I-85J1500D01*
G03X1576918Y224158I-262J1479D01*
G01X1576925Y224187D01*
X1576938Y224209D01*
G02X1576968Y224249I174J-99D01*
G01X1577771Y225051D01*
G03X1577830Y225193I-141J142D01*
G01Y227027D01*
G02X1577867Y227143I200J0D01*
G01X1577884Y227168D01*
X1577932Y227204D01*
X1577963Y227215D01*
G03X1578899Y228191I-500J1416D01*
G01X1578912Y228232D01*
X1580073Y229393D01*
G03X1580456Y230317I-923J924D01*
G01Y250272D01*
G03X1580073Y251196I-1306J0D01*
G01X1575033Y256236D01*
G03X1574111Y256618I-923J-924D01*
G01X1563830D01*
G02X1563797Y256621I2J200D01*
G02X1563689Y256676I32J197D01*
G01X1560194Y260172D01*
G03X1559272Y260554I-923J-924D01*
G01X1556320D01*
G02X1556294Y260556I2J200D01*
G02X1556179Y260612I25J198D01*
G01X1554236Y262556D01*
G03X1553314Y262938I-923J-924D01*
G01X1535750D01*
G02X1535699Y262994I120J160D01*
G01X1535610Y263140D01*
Y263142D01*
X1535539Y263261D01*
G02X1535515Y263356I176J95D01*
G01Y263459D01*
X1535525Y263503D01*
X1535535Y263523D01*
G03X1535686Y264162I-1351J657D01*
G01Y264184D01*
G03X1534184Y265682I-1502J-4D01*
G03X1533250Y265356I0J-1502D01*
G01X1533249Y265355D01*
X1533237Y265345D01*
G02X1533131Y265312I-110J167D01*
G01X1533039D01*
G03X1532956Y265294I0J-200D01*
G01X1532902Y265269D01*
G02X1532824Y265250I-85J181D01*
G02X1532790Y265252I-5J200D01*
G02X1532686Y265300I28J198D01*
G01X1532685Y265301D01*
G03X1531686Y265682I-1000J-1122D01*
G01X1531684D01*
G03X1530182Y264207I0J-1502D01*
G01Y264205D01*
X1530181Y264179D01*
Y264178D01*
G03X1530453Y263317I1503J1D01*
G01X1530454Y263315D01*
G02X1530490Y263219I-163J-116D01*
G01X1530495Y263171D01*
X1530480Y263137D01*
X1530476Y263128D01*
X1530472Y263120D01*
X1530425Y263016D01*
G02X1530363Y262938I-183J82D01*
G01X1529929D01*
X1529910Y262958D01*
G03X1529903Y262964I-134J-149D01*
G01X1529894Y262971D01*
X1528512Y264353D01*
G03X1528370Y264412I-142J-141D01*
G01X1523093D01*
G02X1523002Y264434I0J200D01*
G02X1522952Y264470I90J178D01*
G01X1515006Y272416D01*
G02X1515004Y272444I198J28D01*
G01Y346173D01*
G02X1515016Y346240I200J-1D01*
G02X1515061Y346312I188J-68D01*
G01X1515072Y346323D01*
G02X1515119Y346355I135J-148D01*
G01X1515309Y346426D01*
X1515485Y346491D01*
G02X1515603Y346498I70J-187D01*
G01X1515632Y346491D01*
X1515682Y346460D01*
X1515704Y346435D01*
G03X1516838Y345920I1134J991D01*
G03X1518340Y347422I0J1502D01*
G03X1517014Y348914I-1502J0D01*
G01X1516954Y348921D01*
G03X1516838Y348925I-110J-1499D01*
G01X1516837D01*
G03X1515708Y348415I0J-1505D01*
G01X1515704Y348410D01*
X1515685Y348391D01*
G02X1515601Y348347I-132J150D01*
G01X1515573Y348340D01*
X1515546Y348341D01*
G02X1515486Y348354I12J200D01*
G01X1515229Y348449D01*
X1515134Y348484D01*
G02X1515004Y348671I70J187D01*
G01Y352767D01*
G02X1515082Y352925I200J0D01*
G01X1515098Y352937D01*
X1515342Y353123D01*
G02X1515408Y353153I115J-164D01*
G02X1515482Y353157I48J-194D01*
G01X1515504Y353154D01*
X1515520Y353150D01*
G03X1515899Y353099I388J1451D01*
G01X1515912D01*
G03X1517411Y354601I-3J1502D01*
G03X1515919Y356103I-1502J0D01*
G01X1515908D01*
G03X1515523Y356053I-1J-1502D01*
G01X1515522D01*
X1515520Y356052D01*
X1515504Y356048D01*
X1515483Y356045D01*
X1515482D01*
G02X1515417Y356048I-23J198D01*
G01X1515401Y356052D01*
G02X1515363Y356067I54J192D01*
G01X1515362D01*
X1515348Y356075D01*
X1515189Y356196D01*
X1515077Y356281D01*
G02X1515004Y356435I127J154D01*
G01Y365566D01*
G03X1514945Y365708I-200J0D01*
G01X1483033Y397621D01*
G02X1483015Y397642I143J140D01*
G02X1482982Y397712I161J119D01*
G02X1482976Y397761I194J49D01*
G01Y420383D01*
G03X1482917Y420525I-200J0D01*
G01X1479585Y423857D01*
G02X1479549Y423907I142J140D01*
G02X1479527Y423998I178J91D01*
G01Y440257D01*
G02X1479531Y440294I200J-3D01*
G01Y440296D01*
G02X1479584Y440397I196J-39D01*
G01X1481329Y442142D01*
G02X1481430Y442195I140J-143D01*
G01X1481432D01*
G02X1481469Y442199I40J-196D01*
G01X1485556D01*
G03X1485647Y442221I0J200D01*
G01X1485710Y442253D01*
X1485751D01*
X1485783Y442256D01*
X1498187D01*
G02X1498378Y442115I0J-200D01*
G01X1498791Y440775D01*
G03X1498984Y440274I3719J1145D01*
G01X1500293Y437469D01*
G02X1500295Y437465I-178J-91D01*
G01X1500511Y436806D01*
X1500686Y436275D01*
G03X1501607Y434758I3730J1227D01*
G01X1503471Y432850D01*
G03X1503504Y432817I2793J2760D01*
G03X1504802Y431956I2776J2777D01*
G01X1507910Y430692D01*
G02X1507912Y430642I-198J-33D01*
G01X1507910Y430619D01*
X1507865Y430500D01*
G03X1507829Y430396I1685J-641D01*
G03X1507819Y430365I1710J-569D01*
G01Y430361D01*
G03X1507816Y430352I1705J-573D01*
G01X1507812Y430340D01*
G03X1507795Y430272I1740J-471D01*
G03X1507748Y429860I1755J-409D01*
G01Y426460D01*
G03X1511352I1802J0D01*
G01Y428420D01*
G02X1511475Y428604I200J-1D01*
G01X1511568D01*
G02X1511600Y428601I-3J-200D01*
G01X1511602D01*
G02X1511708Y428547I-34J-197D01*
G01X1512179Y428076D01*
G03X1512769Y427591I2754J2749D01*
G01X1518249Y423929D01*
X1518281Y423907D01*
X1518302Y423877D01*
G02X1518334Y423806I-163J-116D01*
G01X1518341Y423775D01*
Y423773D01*
X1518362Y423687D01*
Y423639D01*
X1518356Y423615D01*
X1518354Y423606D01*
X1518341Y423558D01*
X1518333Y423541D01*
X1518329Y423531D01*
G03X1518314Y423500I1614J-800D01*
G01X1518313Y423499D01*
G03X1518305Y423480I1656J-708D01*
G01X1518303Y423477D01*
X1518300Y423470D01*
X1518290Y423446D01*
X1518289Y423444D01*
X1518283Y423429D01*
X1518277Y423413D01*
X1518276Y423411D01*
G03X1518150Y422747I1676J-662D01*
G01Y419347D01*
G03X1521754I1802J0D01*
G01Y421207D01*
G02X1521829Y421363I200J0D01*
G01X1521864Y421387D01*
G02X1522070Y421378I96J-176D01*
G01X1522115Y421348D01*
X1522515Y421082D01*
X1522523Y421077D01*
X1545173Y403035D01*
X1545175Y403033D01*
G03X1545923Y402546I2484J2997D01*
G01X1548020Y401501D01*
X1548047Y401479D01*
G02X1548056Y401470I-137J-146D01*
G01X1557651Y391875D01*
G03X1557793Y391816I142J141D01*
G01X1567385D01*
G02X1567447Y391806I0J-200D01*
G01X1572975Y389042D01*
G02X1573031Y388990I-106J-170D01*
G01X1573048Y388966D01*
X1573056Y388918D01*
G03X1574539Y387651I1484J235D01*
G01X1574541D01*
G03X1574675Y387658I-11J1502D01*
G01X1574717Y387662D01*
G03X1575669Y388162I-177J1494D01*
G02X1575738Y388213I151J-132D01*
G01X1575740Y388214D01*
X1580640D01*
G02X1580698Y388174I-83J-182D01*
G01X1580705Y388167D01*
X1580709Y388162D01*
G03X1581840Y387650I1131J993D01*
G03X1581959Y387655I-4J1503D01*
G01X1582016Y387661D01*
G03X1582095Y387673I-186J1490D01*
G01X1582136Y387680D01*
G03X1584240Y387068I2105J3315D01*
G01X1584270D01*
G03X1586344Y387680I-31J3927D01*
G01X1586382Y387673D01*
G03X1586638Y387651I256J1480D01*
G01X1586640D01*
G03X1588142Y389153I0J1502D01*
G01Y389156D01*
G03X1587996Y389803I-1502J1D01*
G01X1587990Y389831D01*
G03X1588166Y390991I-3750J1162D01*
G01Y390995D01*
G03X1587814Y392621I-3928J1D01*
G02Y392769I186J74D01*
G03X1588166Y394395I-3576J1625D01*
G01Y394397D01*
G03X1587990Y395559I-3926J0D01*
G01X1587992Y395570D01*
X1588006Y395607D01*
G03X1588009Y395616I-1421J479D01*
G01X1588011Y395619D01*
G02X1588012Y395621I179J-88D01*
G03X1588142Y396238I-1373J612D01*
G03X1587229Y397622I-1502J2D01*
G01X1587203Y397633D01*
X1587152Y397675D01*
G02X1587079Y397829I127J155D01*
G01Y401590D01*
G02X1587117Y401700I200J-8D01*
G01X1587159Y401749D01*
X1587163Y401754D01*
X1587166Y401757D01*
G03X1587179Y401773I-149J134D01*
G01X1587197Y401800D01*
X1587209Y401849D01*
X1587220Y401896D01*
X1587246Y401929D01*
G02X1587311Y401982I156J-125D01*
G01X1587314Y401984D01*
G03X1587321Y401987I-587J1379D01*
G01X1587322Y401988D01*
X1587335Y401994D01*
G03X1588142Y403326I-696J1332D01*
G01Y403329D01*
G03X1587996Y403976I-1502J1D01*
G01X1587990Y404004D01*
G03X1588166Y405164I-3750J1162D01*
G01Y405168D01*
G03X1587814Y406794I-3928J1D01*
G02Y406942I186J74D01*
G03X1588166Y408568I-3576J1625D01*
G01Y408570D01*
G03X1587990Y409732I-3926J0D01*
G01X1587992Y409743D01*
X1588006Y409780D01*
G03X1588009Y409789I-1421J479D01*
G01X1588011Y409792D01*
G02X1588012Y409794I179J-88D01*
G03X1588142Y410411I-1373J612D01*
G03X1587229Y411795I-1502J2D01*
G01X1587203Y411806D01*
X1587152Y411848D01*
G02X1587079Y412002I127J155D01*
G01Y415763D01*
G02X1587117Y415873I200J-8D01*
G01X1587159Y415922D01*
X1587163Y415927D01*
X1587166Y415930D01*
G03X1587179Y415946I-149J134D01*
G01X1587197Y415973D01*
X1587209Y416022D01*
X1587220Y416069D01*
X1587246Y416102D01*
G02X1587311Y416155I156J-125D01*
G01X1587314Y416157D01*
G03X1587321Y416160I-587J1379D01*
G01X1587322Y416161D01*
X1587335Y416167D01*
G03X1588142Y417499I-696J1332D01*
G01Y417502D01*
G03X1587996Y418149I-1502J1D01*
G01X1587990Y418177D01*
G03X1588166Y419337I-3750J1162D01*
G01Y419341D01*
G03X1587814Y420967I-3928J1D01*
G02Y421115I186J74D01*
G03X1588166Y422741I-3576J1625D01*
G01Y422743D01*
G03X1587990Y423905I-3926J0D01*
G01X1587992Y423916D01*
X1588006Y423953D01*
G03X1588009Y423962I-1421J479D01*
G01X1588011Y423965D01*
G02X1588012Y423967I179J-88D01*
G03X1588142Y424584I-1373J612D01*
G03X1587229Y425968I-1502J2D01*
G01X1587203Y425979D01*
X1587152Y426021D01*
G02X1587079Y426175I127J155D01*
G01Y429937D01*
G02X1587117Y430047I200J-8D01*
G01X1587159Y430096D01*
X1587163Y430101D01*
X1587166Y430104D01*
G03X1587179Y430120I-149J134D01*
G01X1587197Y430147D01*
X1587209Y430196D01*
X1587220Y430243D01*
X1587246Y430276D01*
G02X1587311Y430329I156J-125D01*
G01X1587314Y430331D01*
G03X1587321Y430334I-587J1379D01*
G01X1587322Y430335D01*
X1587335Y430341D01*
G03X1588142Y431673I-696J1332D01*
G01Y431676D01*
G03X1587996Y432323I-1502J1D01*
G01X1587990Y432351D01*
G03X1588166Y433511I-3750J1162D01*
G01Y433515D01*
G03X1587814Y435141I-3928J1D01*
G02Y435289I186J74D01*
G03X1588166Y436915I-3576J1625D01*
G01Y436917D01*
G03X1587990Y438079I-3926J0D01*
G01X1587992Y438090D01*
X1588006Y438127D01*
G03X1588009Y438136I-1421J479D01*
G01X1588011Y438139D01*
G02X1588012Y438141I179J-88D01*
G03X1588142Y438758I-1373J612D01*
G03X1587229Y440142I-1502J2D01*
G01X1587203Y440153D01*
X1587152Y440195D01*
G02X1587079Y440349I127J155D01*
G01Y465803D01*
G02X1587117Y465913I200J-8D01*
G01X1587159Y465962D01*
X1587163Y465967D01*
X1587166Y465970D01*
G03X1587179Y465986I-149J134D01*
G01X1587197Y466013D01*
X1587211Y466072D01*
G02X1587230Y466117I192J-55D01*
G02X1587314Y466196I173J-100D01*
G01X1587336Y466207D01*
G03X1588143Y467533I-696J1332D01*
G01X1588142Y467584D01*
G03X1587996Y468189I-1502J-42D01*
G01X1587990Y468217D01*
G03X1588166Y469377I-3750J1162D01*
G01Y469381D01*
G03X1587814Y471007I-3928J1D01*
G02Y471155I186J74D01*
G03X1588166Y472781I-3576J1625D01*
G01Y472783D01*
G03X1587990Y473945I-3926J0D01*
G01X1587992Y473956D01*
X1588006Y473993D01*
G03X1588009Y474002I-1421J479D01*
G01X1588011Y474005D01*
G02X1588012Y474007I179J-88D01*
G03X1588142Y474624I-1373J612D01*
G03X1587229Y476008I-1502J2D01*
G01X1587203Y476019D01*
X1587152Y476061D01*
G02X1587079Y476215I127J155D01*
G01Y479976D01*
G02X1587117Y480086I200J-8D01*
G01X1587159Y480135D01*
X1587163Y480140D01*
X1587166Y480143D01*
G03X1587179Y480159I-149J134D01*
G01X1587197Y480186D01*
X1587209Y480235D01*
X1587220Y480282D01*
X1587246Y480315D01*
G02X1587311Y480368I156J-125D01*
G01X1587314Y480370D01*
G03X1587321Y480373I-587J1379D01*
G01X1587322Y480374D01*
X1587335Y480380D01*
G03X1588142Y481712I-696J1332D01*
G01Y481715D01*
G03X1587996Y482362I-1502J1D01*
G01X1587990Y482390D01*
G03X1588166Y483550I-3750J1162D01*
G01Y483554D01*
G03X1587814Y485180I-3928J1D01*
G02Y485328I186J74D01*
G03X1588166Y486954I-3576J1625D01*
G01Y486956D01*
G03X1587990Y488118I-3926J0D01*
G01X1587992Y488129D01*
X1588006Y488166D01*
G03X1588009Y488175I-1421J479D01*
G01X1588011Y488178D01*
G02X1588012Y488180I179J-88D01*
G03X1588142Y488797I-1373J612D01*
G03X1587229Y490181I-1502J2D01*
G01X1587203Y490192D01*
X1587152Y490234D01*
G02X1587079Y490388I127J155D01*
G01Y509937D01*
G02X1587117Y510047I200J-8D01*
G01X1587159Y510096D01*
X1587163Y510101D01*
X1587166Y510104D01*
G03X1587179Y510120I-149J134D01*
G01X1587197Y510147D01*
X1587209Y510196D01*
X1587220Y510243D01*
X1587246Y510276D01*
G02X1587311Y510329I156J-125D01*
G01X1587314Y510331D01*
G03X1587321Y510334I-587J1379D01*
G01X1587322Y510335D01*
X1587335Y510341D01*
G03X1588142Y511673I-696J1332D01*
G01Y511676D01*
G03X1587996Y512323I-1502J1D01*
G01X1587990Y512351D01*
G03X1588166Y513511I-3750J1162D01*
G01Y513515D01*
G03X1587814Y515141I-3928J1D01*
G02Y515289I186J74D01*
G03X1588166Y516915I-3576J1625D01*
G01Y516917D01*
G03X1587990Y518079I-3926J0D01*
G01X1587992Y518090D01*
X1588006Y518127D01*
G03X1588009Y518136I-1421J479D01*
G01X1588011Y518139D01*
G02X1588012Y518141I179J-88D01*
G03X1588142Y518758I-1373J612D01*
G03X1587229Y520142I-1502J2D01*
G01X1587203Y520153D01*
X1587152Y520195D01*
G02X1587079Y520349I127J155D01*
G01Y524110D01*
G02X1587117Y524220I200J-8D01*
G01X1587159Y524269D01*
X1587163Y524274D01*
X1587166Y524277D01*
G03X1587179Y524293I-149J134D01*
G01X1587197Y524320D01*
X1587211Y524379D01*
G02X1587230Y524424I192J-55D01*
G02X1587314Y524503I173J-100D01*
G01X1587336Y524514D01*
G03X1588143Y525840I-696J1332D01*
G01X1588142Y525891D01*
G03X1587996Y526496I-1502J-42D01*
G01X1587990Y526524D01*
G03X1588166Y527684I-3750J1162D01*
G01Y527688D01*
G03X1587814Y529314I-3928J1D01*
G02Y529462I186J74D01*
G03X1588166Y531088I-3576J1625D01*
G01Y531090D01*
G03X1587990Y532252I-3926J0D01*
G01X1587992Y532263D01*
X1588006Y532300D01*
G03X1588009Y532309I-1422J479D01*
G01X1588011Y532312D01*
G02X1588012Y532314I179J-88D01*
G03X1588142Y532931I-1373J612D01*
G03X1587229Y534315I-1502J2D01*
G01X1587203Y534326D01*
X1587152Y534368D01*
G02X1587079Y534522I127J155D01*
G01Y552573D01*
G03X1587020Y552715I-200J0D01*
G01X1573331Y566404D01*
X1573301Y566433D01*
X1573267Y566518D01*
G03X1572151Y568029I-3596J-1488D01*
G01X1572127Y568049D01*
X1571371Y569897D01*
G03X1570491Y571209I-3634J-1487D01*
G01X1570253Y571443D01*
X1570238Y571486D01*
G03X1569812Y572331I-3664J-1317D01*
G03X1569551Y572678I-3237J-2163D01*
G02X1569543Y572688I152J130D01*
G01X1569495Y572756D01*
G03X1569489Y572764I-163J-116D01*
G01X1569453Y572810D01*
G02X1569451Y572812I139J141D01*
G03X1569096Y573213I-3111J-2396D01*
G01X1567706Y574581D01*
G03X1566680Y575308I-2754J-2799D01*
G01X1566668Y575314D01*
G03X1566651Y575322I-1680J-3549D01*
G01X1566582Y575389D01*
G02X1566544Y575441I141J143D01*
G03X1566468Y575582I-3463J-1775D01*
G03X1566348Y575779I-3382J-1925D01*
G03X1566313Y575832I-3265J-2118D01*
G01X1566307Y575841D01*
G03X1566301Y575850I-3241J-2154D01*
G01X1566300Y575851D01*
X1566242Y575936D01*
X1566231Y575947D01*
X1566221Y575961D01*
G03X1566196Y575996I-3179J-2244D01*
G01X1566195Y575997D01*
Y575998D01*
X1566194Y575999D01*
G02X1566159Y576139I163J115D01*
G01X1566194Y576425D01*
X1566217Y576460D01*
X1566246Y576512D01*
G02X1566285Y576563I177J-95D01*
G01X1566292Y576569D01*
G03X1566825Y577716I-968J1147D01*
G03X1565323Y579218I-1502J0D01*
G03X1564061Y578532I0J-1504D01*
G01X1564041Y578501D01*
X1564012Y578480D01*
G02X1563952Y578450I-118J161D01*
G01X1563758Y578395D01*
G02X1563744Y578393I-35J197D01*
G01X1563671Y578441D01*
X1563669D01*
G03X1563606Y578483I-2209J-3246D01*
G01X1563604D01*
G03X1563092Y578752I-2077J-3332D01*
G02X1563033Y578791I79J184D01*
G02X1562997Y578837I138J145D01*
G03X1562356Y579680I-3390J-1912D01*
G01X1561126Y580910D01*
G03X1559778Y581788I-2752J-2752D01*
G01X1559738Y581803D01*
X1556764Y584777D01*
G02X1556716Y584854I141J142D01*
G02X1556707Y584892I189J65D01*
G01X1556608Y586101D01*
X1556622Y586141D01*
G03X1556675Y586303I-3671J1291D01*
G03X1556757Y586627I-3752J1122D01*
G03X1556838Y587417I-3810J790D01*
G01Y587421D01*
G03X1556826Y587736I-3891J9D01*
G01X1556685Y589471D01*
G03X1556225Y591016I-3879J-314D01*
G01X1556224Y591017D01*
X1556204Y591055D01*
X1556200Y591104D01*
X1556192Y591207D01*
X1556171Y591484D01*
Y591485D01*
X1556170Y591494D01*
Y594739D01*
X1556172Y594754D01*
G03X1556218Y595354I-3880J599D01*
G03X1556205Y595674I-3926J1D01*
G01X1556172Y596092D01*
X1556170Y596110D01*
Y626518D01*
G02X1556199Y626621I200J-1D01*
G01X1556261Y626715D01*
G02X1556297Y626755I165J-113D01*
G01X1556319Y626773D01*
X1556330Y626778D01*
X1556347Y626785D01*
G03X1558257Y628419I-1652J3864D01*
G03X1558870Y630166I-3562J2231D01*
G01X1558878Y630242D01*
X1558879Y630255D01*
Y630259D01*
G03X1558883Y630297I-4177J459D01*
G01X1558884Y630311D01*
G03X1556308Y634531I-4189J339D01*
G01X1556285Y634540D01*
X1556251Y634565D01*
G02X1556218Y634596I120J160D01*
G02X1556203Y634616I152J130D01*
G02X1556171Y634710I167J109D01*
G01Y634714D01*
G02X1556170Y634726I198J23D01*
G01Y641743D01*
G02X1556177Y641794I200J-1D01*
G01X1558838Y651793D01*
X1562079Y663964D01*
G02X1562123Y664046I193J-51D01*
G01X1562148Y664074D01*
X1562186Y664093D01*
G02X1562190Y664095I91J-178D01*
G03X1563054Y665455I-638J1360D01*
G03X1562780Y666320I-1502J0D01*
G02X1562746Y666401I163J116D01*
G01X1562739Y666443D01*
X1563013Y667472D01*
G02X1563177Y667619I194J-51D01*
G01X1563579Y667652D01*
G02X1563754Y667554I3J-200D01*
G01X1563763Y667534D01*
G03X1565132Y666651I1369J620D01*
G03Y669655I0J1502D01*
G01X1565130D01*
G03X1564252Y669371I1J-1503D01*
G02X1564025Y669366I-117J162D01*
G01X1563859Y669481D01*
X1563712Y669582D01*
G02X1563630Y669788I114J165D01*
G01X1564567Y673311D01*
X1565348Y676243D01*
G02X1565401Y676334I193J-52D01*
G01X1565419Y676352D01*
X1565466Y676379D01*
X1565493Y676385D01*
G03X1566624Y677667I-361J1458D01*
G01X1566630Y677721D01*
G03X1566149Y678950I-1498J122D01*
G01X1566130Y678969D01*
X1566116Y679020D01*
G02X1566115Y679126I192J55D01*
G01X1566566Y680818D01*
X1567763Y685314D01*
G02X1567867Y685441I193J-52D01*
G01X1567984Y685499D01*
X1568138Y685576D01*
G02X1568220Y685597I90J-179D01*
G01X1568259Y685598D01*
X1568293Y685584D01*
G03X1568869Y685469I577J1388D01*
G01X1568876D01*
G03X1568953Y685471I0J1502D01*
G03X1568997Y685474I-80J1500D01*
G03X1569181Y685501I-126J1497D01*
G03X1569887Y685864I-309J1470D01*
G03X1569992Y685970I-1013J1109D01*
G03X1570374Y686971I-1121J1001D01*
G03X1568874Y688473I-1502J0D01*
G01X1568838D01*
X1568813Y688480D01*
X1568807Y688482D01*
G02X1568671Y688725I57J191D01*
G01X1571963Y701093D01*
X1573386Y706437D01*
G02X1573507Y706567I192J-57D01*
G02X1573532Y706574I66J-189D01*
G01X1573874Y706655D01*
G02X1574061Y706604I47J-194D01*
G01X1574070Y706593D01*
G03X1575192Y706090I1122J1000D01*
G03Y709094I0J1502D01*
G03X1574715Y709016I1J-1502D01*
G01X1574714D01*
G02X1574514Y709060I-63J190D01*
G01X1574257Y709301D01*
G02X1574201Y709498I137J145D01*
G01X1638412Y950689D01*
G02X1638446Y950758I193J-52D01*
G01X1638470Y950790D01*
X1638506Y950810D01*
G03X1639273Y952120I-735J1310D01*
G01Y952173D01*
G03X1639060Y952892I-1502J-54D01*
G01X1639039Y952928D01*
X1639034Y952966D01*
G02X1639038Y953045I198J30D01*
G01X1640177Y957322D01*
X1646194Y979921D01*
G02X1646300Y980039I189J-63D01*
G01X1646606Y980164D01*
G02X1646699Y980178I75J-185D01*
G01X1646742Y980174D01*
X1646783Y980149D01*
X1646785D01*
G03X1647565Y979930I781J1283D01*
G03Y982934I0J1502D01*
G01X1647526D01*
X1647479Y982933D01*
X1647436Y982953D01*
G02X1647363Y983011I85J181D01*
G01X1647161Y983268D01*
G02X1647130Y983436I162J117D01*
G01Y983437D01*
X1649548Y992521D01*
X1650705Y996868D01*
G02X1650886Y997006I190J-62D01*
G01X1658340D01*
G02X1658483Y996945I-1J-200D01*
G01X1658494Y996933D01*
X1658514Y996912D01*
X1658528Y996874D01*
G02X1658539Y996792I-189J-67D01*
G01X1633614Y641715D01*
G02X1633613Y641701I-200J7D01*
G01X1631988Y630167D01*
X1631712Y628214D01*
G02X1631700Y628168I-198J27D01*
G01X1631692Y628147D01*
X1631678Y628127D01*
G03X1631005Y626419I3216J-2254D01*
G01X1630733Y624487D01*
G03X1630694Y623940I3888J-552D01*
G03X1630707Y623626I3927J5D01*
G01X1630708Y623617D01*
G03X1630709Y623604I3915J295D01*
G01X1630680Y623398D01*
G03X1630642Y622852I3888J-545D01*
G01Y622850D01*
G03X1630643Y622739I3926J-20D01*
G02X1630640Y622728I-194J47D01*
G02X1630632Y622707I-191J61D01*
G03X1630510Y622397I3590J-1592D01*
G01X1630495Y622353D01*
X1626131Y617989D01*
X1626105Y617975D01*
G03X1625860Y617832I1856J-3461D01*
G01X1625854Y617833D01*
G03X1625570Y617861I-289J-1474D01*
G01X1625561D01*
G03X1624063Y616359I4J-1502D01*
G01Y616355D01*
G03X1624198Y615733I1502J0D01*
G01X1624208Y615711D01*
X1624214Y615681D01*
Y615679D01*
G03X1624038Y614557I3751J-1163D01*
G01Y614495D01*
G03X1624043Y614310I3927J14D01*
G03X1624379Y612917I3921J209D01*
G02X1624391Y612879I-184J-79D01*
G01X1624405Y612819D01*
G02Y612815I-200J-2D01*
G01X1624391Y612755D01*
G02X1624379Y612717I-196J41D01*
G03X1624038Y611117I3586J-1601D01*
G01Y611115D01*
G03X1624071Y610608I3927J1D01*
G03X1624144Y610211I3893J511D01*
G03X1624215Y609953I3819J912D01*
G01X1624209Y609922D01*
X1624200Y609902D01*
G03X1624063Y609277I1365J-627D01*
G01Y609272D01*
G03X1625565Y607770I1502J0D01*
G01X1625568D01*
G03X1625850Y607797I-2J1502D01*
G01X1625864Y607800D01*
G03X1626173Y607623I2104J3315D01*
G01X1626175D01*
X1626222Y607598D01*
G02X1626235Y607580I-155J-126D01*
G01X1626272Y607519D01*
G02X1626301Y607416I-171J-104D01*
G01Y604014D01*
G02X1626294Y603961I-200J-1D01*
G01X1626274Y603888D01*
G03X1625860Y603659I1690J-3544D01*
G01X1625854Y603660D01*
G03X1625570Y603688I-289J-1474D01*
G01X1625561D01*
G03X1624063Y602186I4J-1502D01*
G01Y602182D01*
G03X1624198Y601560I1502J0D01*
G01X1624208Y601538D01*
X1624214Y601508D01*
Y601506D01*
G03X1624038Y600344I3751J-1162D01*
G03X1624379Y598744I3927J1D01*
G02X1624391Y598706I-184J-79D01*
G01X1624405Y598646D01*
G02Y598642I-200J-2D01*
G01X1624391Y598582D01*
G02X1624379Y598544I-196J41D01*
G03X1624038Y596944I3586J-1601D01*
G01Y596942D01*
G03X1624071Y596435I3927J1D01*
G03X1624144Y596038I3893J511D01*
G03X1624215Y595780I3819J912D01*
G01X1624209Y595749D01*
X1624200Y595729D01*
G03X1624063Y595104I1365J-627D01*
G01Y595099D01*
G03X1625565Y593597I1502J0D01*
G01X1625568D01*
G03X1625850Y593624I-2J1502D01*
G01X1625864Y593627D01*
G03X1626173Y593450I2104J3315D01*
G01X1626175D01*
X1626222Y593425D01*
G02X1626235Y593407I-155J-126D01*
G01X1626272Y593346D01*
G02X1626301Y593243I-171J-104D01*
G01Y589841D01*
G02X1626294Y589788I-200J-1D01*
G01X1626274Y589715D01*
G03X1625860Y589486I1690J-3544D01*
G01X1625854Y589487D01*
G03X1625570Y589515I-289J-1474D01*
G01X1625561D01*
G03X1624063Y588013I4J-1502D01*
G01Y588009D01*
G03X1624198Y587387I1502J0D01*
G01X1624208Y587365D01*
X1624214Y587335D01*
Y587333D01*
G03X1624038Y586171I3751J-1162D01*
G03X1624379Y584571I3927J1D01*
G02X1624391Y584533I-184J-79D01*
G01X1624405Y584473D01*
G02Y584469I-200J-2D01*
G01X1624391Y584409D01*
G02X1624379Y584371I-196J41D01*
G03X1624038Y582771I3586J-1601D01*
G01Y582769D01*
G03X1624071Y582262I3927J1D01*
G03X1624144Y581865I3893J511D01*
G03X1624215Y581607I3819J912D01*
G01X1624209Y581576D01*
X1624200Y581556D01*
G03X1624063Y580931I1365J-627D01*
G01Y580926D01*
G03X1625565Y579424I1502J0D01*
G01X1625568D01*
G03X1625850Y579451I-2J1502D01*
G01X1625864Y579454D01*
G03X1626173Y579277I2104J3315D01*
G01X1626175D01*
X1626222Y579252D01*
G02X1626235Y579234I-155J-126D01*
G01X1626272Y579173D01*
G02X1626301Y579070I-171J-104D01*
G01Y575667D01*
G02X1626294Y575614I-200J-1D01*
G01X1626274Y575541D01*
G03X1625860Y575312I1690J-3544D01*
G01X1625854Y575313D01*
G03X1625570Y575341I-289J-1474D01*
G01X1625561D01*
G03X1624063Y573839I4J-1502D01*
G01Y573835D01*
G03X1624198Y573213I1502J0D01*
G01X1624208Y573191D01*
X1624214Y573161D01*
Y573159D01*
G03X1624038Y571997I3751J-1162D01*
G03X1624379Y570397I3927J1D01*
G02X1624391Y570359I-184J-79D01*
G01X1624405Y570299D01*
G02Y570295I-200J-2D01*
G01X1624391Y570235D01*
G02X1624379Y570197I-196J41D01*
G03X1624038Y568597I3586J-1601D01*
G01Y568595D01*
G03X1624071Y568088I3927J1D01*
G03X1624144Y567691I3893J511D01*
G03X1624215Y567433I3819J912D01*
G01X1624209Y567402D01*
X1624200Y567382D01*
G03X1624063Y566757I1365J-627D01*
G01Y566752D01*
G03X1625565Y565250I1502J0D01*
G01X1625568D01*
G03X1625850Y565277I-2J1502D01*
G01X1625864Y565280D01*
G03X1626173Y565103I2104J3315D01*
G01X1626175D01*
X1626222Y565078D01*
G02X1626235Y565060I-155J-126D01*
G01X1626272Y564999D01*
G02X1626301Y564896I-171J-104D01*
G01Y539801D01*
G02X1626294Y539748I-200J-1D01*
G01X1626274Y539675D01*
G03X1625860Y539446I1690J-3544D01*
G01X1625854Y539447D01*
G03X1625570Y539475I-289J-1474D01*
G01X1625561D01*
G03X1624063Y537973I4J-1502D01*
G01Y537969D01*
G03X1624198Y537347I1502J0D01*
G01X1624208Y537325D01*
X1624214Y537295D01*
Y537293D01*
G03X1624038Y536131I3751J-1162D01*
G03X1624379Y534531I3927J1D01*
G02X1624391Y534493I-184J-79D01*
G01X1624405Y534433D01*
G02Y534429I-200J-2D01*
G01X1624391Y534369D01*
G02X1624379Y534331I-196J41D01*
G03X1624038Y532731I3586J-1601D01*
G01Y532729D01*
G03X1624071Y532222I3927J1D01*
G03X1624144Y531825I3893J511D01*
G03X1624215Y531567I3819J912D01*
G01X1624209Y531536D01*
X1624200Y531516D01*
G03X1624063Y530891I1365J-627D01*
G01Y530886D01*
G03X1625565Y529384I1502J0D01*
G01X1625568D01*
G03X1625850Y529411I-2J1502D01*
G01X1625864Y529414D01*
G03X1626173Y529237I2104J3315D01*
G01X1626175D01*
X1626222Y529212D01*
G02X1626235Y529194I-155J-126D01*
G01X1626272Y529133D01*
G02X1626301Y529030I-171J-104D01*
G01Y525628D01*
G02X1626294Y525575I-200J-1D01*
G01X1626274Y525502D01*
G03X1625860Y525273I1690J-3544D01*
G01X1625854Y525274D01*
G03X1625570Y525302I-289J-1474D01*
G01X1625561D01*
G03X1624063Y523800I4J-1502D01*
G01Y523796D01*
G03X1624198Y523174I1502J0D01*
G01X1624208Y523152D01*
X1624214Y523122D01*
Y523120D01*
G03X1624038Y521958I3751J-1162D01*
G03X1624379Y520358I3927J1D01*
G02X1624391Y520320I-184J-79D01*
G01X1624405Y520260D01*
G02Y520256I-200J-2D01*
G01X1624387Y520177D01*
X1624380Y520161D01*
G03X1624038Y518558I3585J-1603D01*
G03X1624046Y518304I3927J-3D01*
G03X1624120Y517763I3918J260D01*
G03X1624215Y517394I3846J793D01*
G01X1624209Y517363D01*
X1624200Y517343D01*
G03X1624063Y516718I1365J-627D01*
G01Y516713D01*
G03X1625565Y515211I1502J0D01*
G01X1625568D01*
G03X1625850Y515238I-2J1502D01*
G01X1625864Y515241D01*
G03X1626173Y515064I2104J3315D01*
G01X1626175D01*
X1626222Y515039D01*
G02X1626235Y515021I-155J-126D01*
G01X1626272Y514960D01*
G02X1626301Y514857I-171J-104D01*
G01Y495667D01*
G02X1626294Y495614I-200J-1D01*
G01X1626274Y495541D01*
G03X1625860Y495312I1690J-3544D01*
G01X1625854Y495313D01*
G03X1625570Y495341I-289J-1474D01*
G01X1625561D01*
G03X1624063Y493839I4J-1502D01*
G01Y493835D01*
G03X1624198Y493213I1502J0D01*
G01X1624208Y493191D01*
X1624214Y493161D01*
Y493159D01*
G03X1624038Y491997I3751J-1162D01*
G03X1624379Y490397I3927J1D01*
G02X1624391Y490359I-184J-79D01*
G01X1624405Y490299D01*
G02Y490295I-200J-2D01*
G01X1624387Y490216D01*
X1624380Y490200D01*
G03X1624038Y488597I3585J-1603D01*
G03X1624046Y488343I3927J-3D01*
G03X1624120Y487802I3918J260D01*
G03X1624215Y487433I3846J793D01*
G01X1624209Y487402D01*
X1624200Y487382D01*
G03X1624063Y486757I1365J-627D01*
G01Y486752D01*
G03X1625565Y485250I1502J0D01*
G01X1625568D01*
G03X1625850Y485277I-2J1502D01*
G01X1625864Y485280D01*
G03X1626173Y485103I2104J3315D01*
G01X1626175D01*
X1626222Y485078D01*
G02X1626235Y485060I-155J-126D01*
G01X1626272Y484999D01*
G02X1626301Y484896I-171J-104D01*
G01Y481494D01*
G02X1626294Y481441I-200J-1D01*
G01X1626274Y481368D01*
G03X1625860Y481139I1690J-3544D01*
G01X1625854Y481140D01*
G03X1625570Y481168I-289J-1474D01*
G01X1625561D01*
G03X1624063Y479666I4J-1502D01*
G01Y479662D01*
G03X1624198Y479040I1502J0D01*
G01X1624208Y479018D01*
X1624214Y478988D01*
Y478986D01*
G03X1624038Y477824I3751J-1162D01*
G03X1624379Y476224I3927J1D01*
G02X1624391Y476186I-184J-79D01*
G01X1624405Y476126D01*
G02Y476122I-200J-2D01*
G01X1624387Y476043D01*
X1624380Y476027D01*
G03X1624038Y474424I3585J-1603D01*
G03X1624046Y474170I3927J-3D01*
G03X1624120Y473629I3918J260D01*
G03X1624215Y473260I3846J793D01*
G01X1624209Y473229D01*
X1624200Y473209D01*
G03X1624063Y472584I1365J-627D01*
G01Y472579D01*
G03X1625565Y471077I1502J0D01*
G01X1625568D01*
G03X1625850Y471104I-2J1502D01*
G01X1625864Y471107D01*
G03X1626173Y470930I2104J3315D01*
G01X1626175D01*
X1626222Y470905D01*
G02X1626235Y470887I-155J-126D01*
G01X1626272Y470826D01*
G02X1626301Y470723I-171J-104D01*
G01Y464972D01*
G03X1626501Y464772I200J0D01*
G01X1631395D01*
X1631439Y464765D01*
G02X1631500Y464744I-34J-197D01*
G01X1631545Y464715D01*
X1631565Y464702D01*
X1631623Y464647D01*
X1631635Y464630D01*
G03X1632865Y463990I1230J862D01*
G03X1633010Y463997I0J1502D01*
G01X1633041Y464000D01*
G03X1633059Y464003I-238J1482D01*
G01X1633063D01*
G03X1633082Y464006I-225J1485D01*
G01X1633083D01*
G03X1633093Y464008I-289J1472D01*
G01X1633097D01*
G03X1633161Y464019I-222J1485D01*
G01X1633164Y464020D01*
G03X1635250Y463410I2102J3317D01*
G01X1635265D01*
G03X1637286Y463971I-2J3927D01*
G01X1637305Y463981D01*
X1637405Y464009D01*
G02X1637437Y464007I4J-200D01*
G03X1637664Y463990I225J1485D01*
G01X1637665D01*
G03X1638810Y464519I0J1504D01*
G01X1638811Y464520D01*
X1638815Y464525D01*
G03X1638824Y464536I-1159J957D01*
G02X1638873Y464572I142J-142D01*
G03X1639784Y464766I-357J3910D01*
G02X1639832Y464772I49J-194D01*
G01X1644558D01*
G02X1644612Y464764I-2J-200D01*
G01X1644656Y464752D01*
X1644682Y464745D01*
X1644706Y464731D01*
G03X1644984Y464604I760J1296D01*
G03X1645329Y464531I481J1423D01*
G01X1645372Y464527D01*
X1645480Y464466D01*
G02X1645550Y464401I-97J-175D01*
G01X1645698Y464174D01*
X1645699Y464173D01*
X1645702Y464168D01*
G02X1645729Y464038I-171J-103D01*
G01X1645721Y463994D01*
X1645715Y463977D01*
G03X1645645Y463685I1419J-495D01*
G03X1645631Y463511I1488J-207D01*
G01Y463475D01*
G03X1647133Y461977I1502J4D01*
G03X1648635Y463479I0J1502D01*
G03X1647221Y464978I-1502J0D01*
G02X1647192Y464983I19J199D01*
G02X1647152Y464997I46J195D01*
G02X1647097Y465037I89J180D01*
G03X1647093Y465041I-143J-139D01*
G01X1647084Y465050D01*
G02X1647076Y465060I152J130D01*
G01X1646916Y465307D01*
X1646913Y465312D01*
X1646874Y465368D01*
X1646868Y465417D01*
X1646861Y465467D01*
X1646878Y465512D01*
G03X1646894Y465560I-1418J499D01*
G01Y465569D01*
X1646907Y465603D01*
X1646908Y465607D01*
X1646919Y465643D01*
X1646941Y465671D01*
G02X1646994Y465718I157J-124D01*
G01X1647009Y465727D01*
X1647012Y465730D01*
X1647194Y465843D01*
X1647225Y465863D01*
X1647319Y465882D01*
G02X1647363Y465883I27J-198D01*
G01X1647377Y465881D01*
G03X1647603Y465865I219J1486D01*
G01X1647604D01*
G03X1649105Y467326I0J1502D01*
G01X1649106Y467339D01*
Y467367D01*
G03X1648921Y468090I-1502J1D01*
G01X1648909Y468112D01*
X1648901Y468127D01*
X1648897Y468169D01*
Y468170D01*
G02X1648906Y468253I199J20D01*
G01X1648956Y468393D01*
Y468395D01*
X1649005Y468534D01*
G02X1649032Y468585I188J-67D01*
G01X1654635Y470904D01*
G02X1654685Y470914I64J-189D01*
G02X1654700Y470915I21J-199D01*
G01X1654933D01*
G03X1655075Y470974I0J200D01*
G01X1655173Y471072D01*
G02X1655237Y471115I141J-141D01*
G01X1655275Y471131D01*
X1655375D01*
X1655400Y471125D01*
G03X1655770Y471077I377J1454D01*
G01X1655791D01*
G03X1657119Y471902I-13J1503D01*
G01X1657135Y471933D01*
G02X1657141Y471941I163J-116D01*
G01X1658859Y472652D01*
G03X1660129Y473499I-1502J3628D01*
G01X1665920Y479270D01*
X1665926Y479276D01*
G02X1665934Y479283I136J-147D01*
G01X1688076Y495794D01*
X1690878Y497884D01*
X1690898Y497889D01*
X1690925Y497896D01*
X1706429D01*
G02X1706461Y497893I-3J-200D01*
G01X1706463D01*
G02X1706569Y497839I-34J-197D01*
G01X1707925Y496483D01*
G02X1707984Y496341I-141J-142D01*
G01Y474388D01*
G02X1707925Y474246I-200J0D01*
G01X1698659Y464981D01*
G03X1698266Y464457I1630J-1632D01*
G01X1698253Y464432D01*
X1696100Y462279D01*
G03X1695436Y460676I1603J-1603D01*
G01Y443515D01*
G02X1695428Y443459I-200J0D01*
G02X1695422Y443441I-193J54D01*
G01X1695407Y443405D01*
X1682756Y430754D01*
G03X1682092Y429151I1603J-1603D01*
G01Y399089D01*
G02X1682090Y399061I-200J0D01*
G02X1681984Y398912I-198J28D01*
G03X1681982Y398910I140J-142D01*
G02X1681964Y398902I-90J178D01*
G01X1681951Y398897D01*
X1681874Y398867D01*
G02X1681806Y398857I-63J190D01*
G01X1681804D01*
X1681762Y398858D01*
X1681638Y398914D01*
X1681610Y398943D01*
G03X1680551Y399414I-1092J-1030D01*
G01X1680518D01*
G03Y396410I0J-1502D01*
G01X1680528D01*
G03X1680748Y396427I-5J1502D01*
G01X1680764Y396430D01*
G03X1680935Y396469I-248J1481D01*
G03X1681611Y396881I-416J1443D01*
G01X1681624Y396895D01*
X1681638Y396910D01*
X1681723Y396949D01*
G02X1681771Y396965I87J-180D01*
G02X1681795Y396968I37J-197D01*
G01X1681808D01*
G02X1681875Y396956I-1J-200D01*
G02X1681879Y396955I-47J-195D01*
G01X1681973Y396918D01*
G02X1682057Y396848I-81J-183D01*
G01X1682075Y396822D01*
X1682084Y396793D01*
G02X1682087Y396780I-193J-51D01*
G02X1682092Y396737I-195J-44D01*
G01Y390891D01*
G03X1682314Y389913I2267J1D01*
G01X1682315Y389910D01*
X1682323Y389888D01*
G02X1682324Y389883I-195J-42D01*
G03X1682326Y389879I177J86D01*
G02X1682334Y389823I-192J-56D01*
G01Y388997D01*
G03X1682393Y388855I200J0D01*
G01X1698926Y372322D01*
G03X1699068Y372263I142J141D01*
G01X1699681D01*
G02X1699770Y372242I0J-200D01*
G01X1699823Y372216D01*
G02X1699864Y372185I-99J-174D01*
G01X1701101Y370947D01*
X1703839Y368209D01*
G02X1703892Y368108I-143J-140D01*
G01Y368106D01*
G02X1703896Y368069I-196J-40D01*
G01Y346591D01*
G02X1703867Y346487I-201J0D01*
G01X1703773Y346448D01*
G02X1703555Y346490I-78J184D01*
G01X1692649Y357397D01*
X1692624Y357439D01*
X1692617Y357462D01*
G03X1691182Y358518I-1435J-447D01*
G03X1689680Y357016I0J-1502D01*
G01X1689679D01*
G03X1690736Y355581I1503J0D01*
G01X1690737D01*
G02X1690819Y355531I-60J-191D01*
G01X1702173Y344177D01*
G02X1702226Y344075I-143J-139D01*
G02X1702230Y344037I-196J-40D01*
G01Y336955D01*
G02X1702226Y336917I-200J2D01*
G02X1702209Y336866I-196J37D01*
G02X1702190Y336835I-179J89D01*
G37*
G36*
G01X4707Y1431686D02*
X39119D01*
G02X39261Y1431627I0J-200D01*
G01X44097Y1426791D01*
G02X44156Y1426649I-141J-142D01*
G01Y1294142D01*
G03X44170Y1294069I200J1D01*
G01X56428Y1263012D01*
G02X56442Y1262938I-186J-74D01*
G01Y1260231D01*
G03X56594Y1259465I2001J-1D01*
G01X64307Y1240843D01*
G02X64322Y1240766I-185J-76D01*
G01Y1217987D01*
G03X64875Y1216606I2001J0D01*
G02X64930Y1216469I-145J-138D01*
G01Y1211173D01*
G02X64864Y1211025I-200J0D01*
G01X64613Y1210798D01*
X64533Y1210771D01*
X64490Y1210776D01*
G03X64332Y1210784I-155J-1494D01*
G03X63841Y1210701I1J-1502D01*
G01X63840D01*
X63837Y1210700D01*
G03X63760Y1210652I65J-189D01*
G01X60835Y1207727D01*
G03X60776Y1207585I141J-142D01*
G01Y1200719D01*
G02X60713Y1200574I-200J1D01*
G01X60472Y1200345D01*
X60396Y1200317D01*
X60354Y1200320D01*
G03X60269Y1200322I-78J-1500D01*
G03Y1197318I0J-1502D01*
G03X60354Y1197320I7J1502D01*
G01X60396Y1197323D01*
X60472Y1197295D01*
X60713Y1197066D01*
G02X60776Y1196921I-137J-146D01*
G01Y1179967D01*
G03X61146Y1179071I1267J-1D01*
G01X67076Y1173141D01*
G02X67135Y1173000I-141J-142D01*
G01Y1150943D01*
G02X67076Y1150801I-200J0D01*
G01X65678Y1149403D01*
X65650Y1149374D01*
X65576Y1149344D01*
X2903D01*
G02X2761Y1149403I0J200D01*
G01X2339Y1149825D01*
G02X2280Y1149967I141J142D01*
G01Y1429259D01*
G02X2339Y1429401I200J0D01*
G01X4565Y1431627D01*
G02X4707Y1431686I142J-141D01*
G37*
G36*
G01X30190Y135918D02*
G03X30182Y136086I-1802J-2D01*
G02X30429Y136298I199J18D01*
G03X30788Y136255I357J1459D01*
G03X31475Y136421I1J1502D01*
G02X31708Y136385I92J-178D01*
G01X36579Y131514D01*
G02X36620Y131290I-141J-142D01*
G03X36486Y130670I1368J-620D01*
G03X36505Y130434I1502J2D01*
G03X35688Y130630I-817J-1605D01*
G03X33886Y128828I0J-1802D01*
G01Y125428D01*
G03X37490I1802J0D01*
G01Y128829D01*
G03X37484Y128979I-1802J3D01*
G02X37719Y129192I199J16D01*
G03X37985Y129168I267J1477D01*
G01X37988D01*
G03X38608Y129302I0J1502D01*
G02X38832Y129261I82J-182D01*
G01X40467Y127626D01*
G02X40526Y127484I-141J-142D01*
G01Y121476D01*
G03X41201Y119846I2306J0D01*
G01X43067Y117980D01*
G03X44698Y117304I1632J1631D01*
G01X46600D01*
G02X46742Y117245I0J-200D01*
G01X53803Y110184D01*
G03X55434Y109508I1632J1631D01*
G01X65247D01*
G02X65389Y109449I0J-200D01*
G01X65469Y109369D01*
G02X65528Y109235I-141J-142D01*
G01X65540Y108924D01*
X65515Y108854D01*
X65490Y108825D01*
G03X65054Y107650I1366J-1175D01*
G01Y104249D01*
G03X68658I1802J0D01*
G01Y105697D01*
G02X68782Y105882I200J0D01*
G01X68838Y105906D01*
X68956Y105882D01*
X70469Y104369D01*
G03X70557Y104286I1626J1636D01*
G01X70558Y104285D01*
G02X70623Y104142I-135J-148D01*
G01X70631Y103852D01*
G02X70572Y103705I-200J-5D01*
G01X68650Y101783D01*
G02X68508Y101724I-142J141D01*
G01X62071D01*
G02X61929Y101783I0J200D01*
G01X56228Y107485D01*
G03X55304Y107868I-924J-923D01*
G01X35997D01*
G02X35908Y107889I0J200D01*
G01X35906Y107890D01*
G03X35207Y108063I-700J-1329D01*
G03X34510Y107891I1J-1502D01*
G02X34506Y107889I-91J178D01*
G01X34485Y107878D01*
X34441Y107868D01*
X30334D01*
G02X30192Y107927I0J200D01*
G01X24617Y113502D01*
G03X23695Y113884I-923J-924D01*
G01X16534D01*
G02X16351Y114004I0J200D01*
G01X16205Y114341D01*
G02X16242Y114557I183J80D01*
G03X16645Y115581I-1099J1024D01*
G03X13641I-1502J0D01*
G03X14044Y114557I1502J0D01*
G02X14081Y114341I-146J-136D01*
G01X13935Y114004D01*
G02X13752Y113884I-183J80D01*
G01X11616D01*
G02X11436Y113997I0J200D01*
G01X11254Y114375D01*
X11268Y114489D01*
X11304Y114534D01*
G03X11633Y115471I-1173J938D01*
G01Y115473D01*
G03X10131Y116975I-1502J0D01*
G03X9955Y116964I6J-1502D01*
G01X9952D01*
G02X9797Y117013I-22J199D01*
G01X9573Y117212D01*
G02X9506Y117362I133J149D01*
G01Y130490D01*
G02X9613Y130667I200J0D01*
G01X9977Y130858D01*
X10087Y130852D01*
X10133Y130820D01*
G03X11442Y130412I1310J1899D01*
G01X11550D01*
G03X13181Y131088I-1J2307D01*
G01X13302Y131209D01*
G02X13567Y131224I141J-142D01*
G03X14996Y130728I1429J1811D01*
G01X14997D01*
G03X16627Y131403I0J2306D01*
G01X17805Y132581D01*
G02X17987Y132635I141J-142D01*
G01X18314Y132568D01*
G02X18459Y132446I-41J-196D01*
G03X19855Y131498I1396J554D01*
G03X21357Y133000I0J1502D01*
G01Y133002D01*
G03X21209Y133651I-1502J-1D01*
G01Y133652D01*
G02X21220Y133844I180J86D01*
G01X21399Y134130D01*
G02X21569Y134224I170J-106D01*
G01X21583D01*
G03X23214Y134900I-1J2307D01*
G01X24840Y136527D01*
G02X25100Y136546I141J-142D01*
G03X25988Y136255I888J1211D01*
G01X25989D01*
G03X26347Y136298I1J1502D01*
G02X26594Y136086I48J-194D01*
G03X26586Y135918I1794J-170D01*
G01Y132515D01*
G03X30190I1802J0D01*
G01Y135918D01*
G37*
G36*
G01X15586Y247606D02*
G03X16840Y248281I0J1502D01*
G01Y248283D01*
X16841D01*
G02X16986Y248371I167J-111D01*
G01X17295Y248402D01*
G02X17457Y248345I21J-199D01*
G01X24329Y241473D01*
G02X24368Y241245I-141J-142D01*
G01X24177Y240846D01*
X24067Y240785D01*
X24004Y240792D01*
G03X23844Y240801I-164J-1493D01*
G03X25346Y239299I0J-1502D01*
G03X25311Y239620I-1502J-1D01*
G01Y239621D01*
G02X25385Y239822I195J42D01*
G01X25721Y240077D01*
X25837Y240087D01*
X25888Y240060D01*
G03X26962Y239794I1075J2040D01*
G01X30425D01*
G02X30590Y239707I0J-200D01*
G01X30804Y239395D01*
X30816Y239297D01*
X30798Y239251D01*
G03X30699Y238715I1403J-536D01*
G01Y238714D01*
G03X33703I1502J0D01*
G01Y238715D01*
G03X33604Y239251I-1502J0D01*
G01X33586Y239297D01*
X33598Y239395D01*
X33812Y239707D01*
G02X33977Y239794I165J-113D01*
G01X34744D01*
G02X34915Y239491I0J-200D01*
G03X34699Y238716I1287J-776D01*
G01Y238714D01*
G03X35671Y237309I1501J0D01*
G02X35800Y237122I-71J-187D01*
G01Y231715D01*
G02X35668Y231527I-200J0D01*
G03Y228707I517J-1410D01*
G02X35800Y228519I-68J-188D01*
G01Y173640D01*
G03X36475Y172010I2306J0D01*
G01X41716Y166769D01*
G03X43346Y166094I1630J1631D01*
G01X46061D01*
G02X46203Y166035I0J-200D01*
G01X69768Y142469D01*
G03X71398Y141794I1630J1631D01*
G01X73298D01*
G02X73444Y141730I-1J-200D01*
G01X73672Y141483D01*
X73699Y141405D01*
X73696Y141363D01*
G03X73692Y141247I1498J-110D01*
G03X76696I1502J0D01*
G01Y141249D01*
G03X76596Y141786I-1502J-2D01*
G02X76593Y141920I187J71D01*
G01X76630Y142032D01*
G02X76714Y142140I190J-61D01*
G03X77130Y142469I-1213J1962D01*
G01X77940Y143279D01*
G02X78082Y143338I142J-141D01*
G01X81069D01*
G02X81256Y143209I0J-200D01*
G03X82661Y142238I1405J531D01*
G03X83593Y142562I0J1502D01*
G01X83614Y142541D01*
G03X85244Y141866I1630J1631D01*
G01X89334D01*
G02X89484Y141799I1J-200D01*
G01X89683Y141576D01*
G02X89732Y141420I-150J-133D01*
G03X89722Y141247I1491J-173D01*
G03X91224Y139745I1502J0D01*
G03X91921Y139917I-1J1502D01*
G02X91925Y139919I91J-178D01*
G01X91946Y139930D01*
X91990Y139940D01*
X94255D01*
G02X94440Y139817I0J-200D01*
G01X94463Y139761D01*
X94440Y139643D01*
X90203Y135406D01*
G03X89528Y133776I1631J-1630D01*
G01Y116212D01*
G02X89469Y116070I-200J0D01*
G01X83964Y110565D01*
G02X83822Y110506I-142J141D01*
G01X80183D01*
G02X79985Y110675I0J200D01*
G03X78501Y111947I-1484J-230D01*
G01X78499D01*
G03X78066Y111883I1J-1502D01*
G02X77808Y112074I-58J191D01*
G01Y114623D01*
G03X74202I-1803J0D01*
G01Y112074D01*
G02X73944Y111883I-200J0D01*
G03X73511Y111947I-434J-1438D01*
G01X73509D01*
G03X72637Y111668I0J-1502D01*
G02X72380Y111689I-116J163D01*
G01X68633Y115437D01*
G03X67003Y116112I-1630J-1631D01*
G01X63810D01*
G02X63668Y116171I0J200D01*
G01X57360Y122479D01*
G02X57337Y122734I141J141D01*
G03X57600Y123583I-1239J849D01*
G03X56098Y125085I-1502J0D01*
G03X55249Y124822I0J-1502D01*
G02X54994Y124845I-114J165D01*
G01X52307Y127533D01*
G02X52248Y127675I141J142D01*
G01Y131525D01*
G03X51572Y133156I-2307J-1D01*
G01X48145Y136583D01*
G02X48127Y136846I141J142D01*
G03X48434Y137756I-1195J910D01*
G03X46932Y139258I-1502J0D01*
G03X46022Y138951I0J-1502D01*
G02X45759Y138969I-121J159D01*
G01X41625Y143103D01*
G03X39995Y143778I-1630J-1631D01*
G01X23426D01*
G03X21796Y143103I0J-2306D01*
G01X21100Y142407D01*
X20939Y142405D01*
X20880Y142460D01*
G03X19855Y142864I-1025J-1098D01*
G03X18353Y141388I0J-1502D01*
G01Y141349D01*
X18322Y141278D01*
X18093Y141053D01*
G02X17953Y140996I-140J143D01*
G01X17846D01*
G02X17709Y141050I0J200D01*
G01X17482Y141262D01*
X17449Y141331D01*
X17447Y141368D01*
G03X15948Y142769I-1499J-101D01*
G03X14446Y141267I0J-1502D01*
G03X15021Y140085I1502J0D01*
G01X15055Y140059D01*
X15095Y139983D01*
X15115Y139641D01*
G02X15057Y139488I-200J-12D01*
G01X12647Y137078D01*
G02X12430Y137035I-141J142D01*
G01X12373Y137058D01*
X12306Y137159D01*
Y139703D01*
G03X12304Y139778I-1306J3D01*
G02X12444Y139980I200J11D01*
G03X13501Y141415I-446J1435D01*
G03X11999Y142917I-1502J0D01*
G03X10825Y142352I0J-1502D01*
G02X10680Y142277I-156J125D01*
G01X10382Y142260D01*
G02X10230Y142318I-11J200D01*
G01X9865Y142682D01*
G02X9806Y142824I141J142D01*
G01Y157329D01*
G02X9896Y157496I200J0D01*
G01X10177Y157680D01*
G02X10366Y157696I109J-167D01*
G03X10966Y157571I600J1377D01*
G03X12468Y159073I0J1502D01*
G03X11889Y160258I-1502J0D01*
G02X11812Y160416I123J158D01*
G01Y160730D01*
G02X11889Y160888I200J0D01*
G03X12468Y162073I-923J1185D01*
G03X10966Y163575I-1502J0D01*
G03X10366Y163450I0J-1503D01*
G01X10319Y163430D01*
X10219Y163438D01*
X9896Y163650D01*
G02X9806Y163817I110J167D01*
G01Y167718D01*
X9836Y167791D01*
X9839Y167794D01*
X10662D01*
G02X10839Y167689I1J-200D01*
G01X11006Y167377D01*
G02X10996Y167172I-177J-94D01*
G03X10745Y166341I1250J-831D01*
G03X13749I1502J0D01*
G03X13498Y167172I-1501J0D01*
G02X13488Y167377I167J111D01*
G01X13655Y167689D01*
G02X13832Y167794I176J-95D01*
G01X15466D01*
G02X15624Y167717I0J-200D01*
G01X15847Y167432D01*
X15866Y167342D01*
X15855Y167298D01*
G03X15811Y166937I1459J-361D01*
G03X18815I1502J0D01*
G03X18771Y167298I-1503J0D01*
G01X18760Y167342D01*
X18779Y167432D01*
X19002Y167717D01*
G02X19160Y167794I158J-123D01*
G01X20556D01*
G02X20721Y167707I0J-200D01*
G01X20908Y167436D01*
G02X20930Y167252I-165J-113D01*
G03X20833Y166721I1405J-531D01*
G03X23837I1502J0D01*
G03X23740Y167252I-1502J0D01*
G02X23762Y167436I187J71D01*
G01X23949Y167707D01*
G02X24114Y167794I165J-113D01*
G01X26067D01*
G03X26989Y168176I-1J1306D01*
G01X27489Y168676D01*
G03X27872Y169600I-923J924D01*
G01Y176658D01*
G02X27893Y176747I200J0D01*
G01X27894Y176749D01*
G03X28067Y177448I-1329J700D01*
G03X25063I-1502J0D01*
G03X25235Y176751I1502J1D01*
G02X25237Y176747I-178J-91D01*
G01X25248Y176726D01*
X25258Y176682D01*
Y170606D01*
G02X25058Y170406I-200J0D01*
G01X9298D01*
G03X9077Y170388I-5J-1306D01*
G01X9033Y170380D01*
X8948Y170404D01*
X8681Y170629D01*
G02X8610Y170782I129J153D01*
G01Y181712D01*
G02X8733Y181897I200J0D01*
G01X8789Y181920D01*
X8907Y181897D01*
X15226Y175578D01*
G02X15275Y175498I-141J-142D01*
G01Y175497D01*
G03X16709Y174441I1434J446D01*
G03X18211Y175943I0J1502D01*
G03X17156Y177377I-1502J0D01*
G01X17154D01*
G02X17074Y177426I62J190D01*
G01X9719Y184780D01*
G02X9660Y184922I141J142D01*
G01Y216193D01*
G02X9726Y216342I200J0D01*
G01X9980Y216569D01*
X10060Y216595D01*
X10102Y216591D01*
G03X10259Y216583I155J1494D01*
G03X11365Y217068I0J1504D01*
G02X11512Y217133I148J-135D01*
G01X11806D01*
G02X11953Y217068I-1J-200D01*
G03X13059Y216583I1106J1019D01*
G03Y219587I0J1502D01*
G03X11953Y219102I0J-1504D01*
G02X11806Y219037I-148J135D01*
G01X11512D01*
G02X11365Y219102I1J200D01*
G03X10259Y219587I-1106J-1019D01*
G03X10102Y219579I-2J-1502D01*
G01X10060Y219575D01*
X9980Y219601D01*
X9726Y219828D01*
G02X9660Y219977I134J149D01*
G01Y229073D01*
G02X9719Y229215I200J0D01*
G01X10266Y229762D01*
G02X10408Y229820I141J-142D01*
G01X19494D01*
G02X19636Y229761I0J-200D01*
G01X21116Y228281D01*
G02X21165Y228201I-141J-142D01*
G01Y228200D01*
G03X22599Y227144I1434J446D01*
G03X24101Y228646I0J1502D01*
G03X23046Y230080I-1502J0D01*
G01X23044D01*
G02X22964Y230129I62J190D01*
G01X22112Y230981D01*
G02X22056Y231155I141J141D01*
G01X22117Y231525D01*
X22175Y231602D01*
X22218Y231623D01*
G03X23058Y232971I-662J1348D01*
G03X20054I-1502J0D01*
G03X20058Y232862I1502J1D01*
G01X20061Y232821D01*
X20033Y232743D01*
X19805Y232498D01*
G02X19659Y232434I-147J136D01*
G01X9784D01*
G03X9191Y232291I1J-1307D01*
G01X9144Y232267D01*
X9041Y232271D01*
X8705Y232477D01*
G02X8610Y232648I105J170D01*
G01Y252969D01*
G02X8667Y253109I200J0D01*
G01X8891Y253338D01*
X8962Y253369D01*
X9001D01*
G03X10429Y254514I-31J1502D01*
G02X10570Y254659I194J-48D01*
G01X10906Y254753D01*
G02X11101Y254701I53J-193D01*
G01X14823Y250979D01*
G02X14880Y250817I-142J-141D01*
G01X14849Y250508D01*
G02X14761Y250363I-199J22D01*
G01X14760Y250362D01*
G03X14084Y249108I825J-1254D01*
G03X15586Y247606I1502J0D01*
G37*
G36*
G01X137335Y242399D02*
Y242398D01*
G03X137162Y241699I1329J-700D01*
G03X138218Y240265I1502J0D01*
G01X138229Y240262D01*
G02X138299Y240216I-73J-187D01*
G01X138674Y239841D01*
X139437Y239079D01*
G02X139493Y238958I-143J-140D01*
G02X139494Y238939I-199J-20D01*
G01Y231938D01*
G02X139413Y231778I-200J1D01*
G01X139155Y231587D01*
G02X139072Y231551I-119J160D01*
G01X139025Y231542D01*
X138979Y231556D01*
G03X138550Y231619I-430J-1439D01*
G01X138547D01*
G03Y228615I0J-1502D01*
G01X138550D01*
G03X138979Y228678I-1J1502D01*
G01X139002Y228685D01*
X139049Y228688D01*
X139072Y228683D01*
G02X139155Y228647I-36J-196D01*
G01X139413Y228456D01*
G02X139494Y228296I-119J-161D01*
G01Y216444D01*
G02X139381Y216264I-200J0D01*
G01X139369Y216259D01*
G02X139251Y216248I-77J185D01*
G01X139225Y216253D01*
X139175Y216280D01*
X126444Y229011D01*
G02X126398Y229081I141J143D01*
G01X126395Y229092D01*
G03X124961Y230148I-1434J-446D01*
G03X123459Y228646I0J-1502D01*
G03X124514Y227212I1502J0D01*
G01X124515D01*
X124526Y227209D01*
G02X124596Y227163I-73J-187D01*
G01X137423Y214336D01*
G02X137476Y214234I-143J-139D01*
G02X137480Y214196I-196J-40D01*
G01Y187211D01*
G02X137421Y187069I-200J0D01*
G01X109087Y158734D01*
G02X109014Y158688I-141J142D01*
G02X108946Y158676I-68J188D01*
G01X104248D01*
G02X104156Y158699I1J200D01*
G01X104155D01*
G03X103456Y158872I-700J-1329D01*
G03Y155868I0J-1502D01*
G03X104155Y156041I-1J1502D01*
G01X104156D01*
G02X104248Y156064I93J-177D01*
G01X109232D01*
G02X109412Y155951I0J-200D01*
G01X109417Y155939D01*
G02X109428Y155821I-185J-77D01*
G01X109423Y155795D01*
X109396Y155745D01*
X97696Y144045D01*
G02X97546Y143999I-129J153D01*
G01X97258Y144049D01*
G02X97173Y144086I35J197D01*
G01X97085Y144151D01*
X97057Y144185D01*
X97046Y144206D01*
G03X95711Y145020I-1335J-688D01*
G03X95021Y144852I0J-1501D01*
G01X94983Y144833D01*
X94945Y144830D01*
G02X94862Y144842I-14J199D01*
G01X94585Y144943D01*
G02X94477Y145036I68J188D01*
G03X92337Y146480I-2140J-864D01*
G01X88763D01*
G02X88630Y146530I-1J200D01*
G01X88547Y146603D01*
G02X88482Y146720I132J150D01*
G03X87002Y147963I-1480J-260D01*
G03X85747Y147287I0J-1503D01*
G01X85741Y147278D01*
X85575Y147188D01*
G02X85440Y147239I-2J200D01*
G01X85404Y147276D01*
G03X83773Y147952I-1632J-1631D01*
G01X81941D01*
G02X81811Y148001I1J200D01*
G01X81597Y148205D01*
G02X81542Y148336I145J138D01*
G03X78540I-1501J-59D01*
G02X78485Y148205I-200J7D01*
G01X78271Y148001D01*
G02X78141Y147952I-131J151D01*
G01X77043D01*
G03X75412Y147276I1J-2307D01*
G01X75155Y147018D01*
X74599Y146461D01*
G02X74478Y146407I-137J145D01*
G02X74461Y146406I-20J199D01*
G01X73177D01*
G02X73011Y146495I0J200D01*
G01X72931Y146615D01*
X72825Y146774D01*
G02X72793Y146864I167J110D01*
G01X72788Y146913D01*
X72808Y146961D01*
G03X72924Y147540I-1387J579D01*
G03X71422Y149042I-1502J0D01*
G01X71420D01*
G03X70396Y148638I1J-1502D01*
G01X70384Y148627D01*
G02X70119Y148642I-124J157D01*
G01X48730Y170031D01*
G03X47100Y170706I-1630J-1631D01*
G01X44385D01*
G02X44271Y170741I-1J200D01*
G02X44255Y170754I118J162D01*
G01X40460Y174549D01*
G02X40447Y174565I149J134D01*
G02X40412Y174679I165J113D01*
G01Y240196D01*
G03X39737Y241826I-2306J0D01*
G01X37832Y243731D01*
G03X36202Y244406I-1630J-1631D01*
G01X35575D01*
G02X35447Y244452I0J200D01*
G01X35420Y244474D01*
X35385Y244534D01*
X35379Y244570D01*
G03X33902Y245799I-1477J-273D01*
G03X33204Y245627I0J-1502D01*
G01X33178Y245614D01*
X33136Y245604D01*
X33005D01*
G02X32829Y245708I0J201D01*
G01X32820Y245728D01*
G02X32805Y245804I185J76D01*
G01Y245838D01*
X32828Y245902D01*
X32850Y245929D01*
G03X33184Y246873I-1168J944D01*
G01Y246896D01*
G03X31682Y248376I-1502J-22D01*
G03X30180Y246874I0J-1502D01*
G01Y246873D01*
G03X30346Y246187I1502J0D01*
G01Y246186D01*
G02X30369Y246086I-177J-93D01*
G01X30367Y246037D01*
X30227Y245807D01*
X30157Y245693D01*
G02X29991Y245604I-166J111D01*
G01X28107D01*
G02X27966Y245662I0J200D01*
G01X24725Y248903D01*
X18144Y255483D01*
G02X18092Y255574I142J141D01*
G02X18086Y255624I194J49D01*
G01Y256318D01*
G03X17704Y257240I-1306J-1D01*
G01X15198Y259746D01*
G02X15150Y259822I141J142D01*
G01X15149Y259827D01*
G03X14166Y260814I-1434J-446D01*
G01X14154Y260818D01*
G02X14082Y260864I69J188D01*
G01X14056Y260890D01*
X14041Y260926D01*
G02X14026Y261002I185J76D01*
G01Y267601D01*
Y267608D01*
G02X14135Y267779I200J-7D01*
G01X14155Y267788D01*
X14461Y267938D01*
G02X14568Y267958I89J-179D01*
G01X14596Y267955D01*
X14648Y267934D01*
X14670Y267917D01*
G03X15542Y267607I915J1192D01*
G01X15544D01*
G03X15577Y267606I62J1500D01*
G01X15604D01*
G03Y270610I-18J1502D01*
G01X15584D01*
G03X14670Y270299I1J-1502D01*
G01X14648Y270282D01*
X14596Y270261D01*
X14568Y270258D01*
G02X14461Y270278I-18J199D01*
G01X14155Y270428D01*
X14135Y270437D01*
G02X14026Y270608I91J178D01*
G01Y277482D01*
G03X13644Y278404I-1306J-1D01*
G01X11950Y280098D01*
G02X11914Y280148I142J140D01*
G02X11892Y280239I178J91D01*
G01Y283004D01*
G02X11896Y283042I200J-2D01*
G02X11949Y283144I196J-37D01*
G01X15864Y287059D01*
G02X15934Y287105I143J-141D01*
G01X15945Y287108D01*
G03X16284Y287261I-444J1435D01*
G02X16312Y287275I103J-171D01*
G02X16345Y287285I74J-186D01*
G02X16388Y287290I44J-195D01*
G01X26248D01*
G02X26286Y287286I-2J-200D01*
G02X26388Y287233I-37J-196D01*
G01X31751Y281869D01*
G02X31810Y281727I-141J-142D01*
G01Y274873D01*
G03X31869Y274731I200J0D01*
G01X33041Y273559D01*
G03X33183Y273500I142J141D01*
G01X45466D01*
G03X45608Y273559I0J200D01*
G01X50491Y278442D01*
G03X50492Y278443I-923J924D01*
G01X75634Y303586D01*
G02X75709Y303633I141J-142D01*
G02X75775Y303644I65J-189D01*
G01X103856D01*
G03X104778Y304026I-1J1306D01*
G01X108161Y307409D01*
G02X108369Y307455I141J-142D01*
G01X108378Y307451D01*
G02X108470Y307376I-75J-185D01*
G01X108485Y307353D01*
X108502Y307298D01*
Y268180D01*
G02X108500Y268150I-200J-2D01*
G02X108445Y268040I-198J30D01*
G01X103043Y262639D01*
G03X102660Y261715I923J-924D01*
G01Y254807D01*
G02X102555Y254632I-200J1D01*
G01X102535Y254624D01*
G02X102419Y254612I-78J184D01*
G01X102393Y254617D01*
X102341Y254645D01*
X100562Y256424D01*
G03X99640Y256806I-923J-924D01*
G01X89120D01*
G02X89091Y256808I-1J200D01*
G02X88979Y256864I29J198D01*
G01X86480Y259364D01*
G03X85558Y259746I-923J-924D01*
G01X82901D01*
G03X81979Y259364I1J-1306D01*
G01X80401Y257786D01*
G02X80331Y257740I-143J141D01*
G01X80320Y257737D01*
G03X79264Y256312I446J-1434D01*
G01Y256301D01*
G03X79318Y255904I1502J2D01*
G01Y255903D01*
G02X79290Y255735I-193J-54D01*
G01X79163Y255568D01*
X79092Y255475D01*
G02X78933Y255396I-159J121D01*
G01X77139D01*
G02X77102Y255399I-2J200D01*
G02X76998Y255454I37J197D01*
G01X72649Y259804D01*
G03X71727Y260186I-923J-924D01*
G01X58779D01*
G02X58687Y260209I1J200D01*
G01X58686D01*
G03X57987Y260382I-700J-1329D01*
G03Y257378I0J-1502D01*
G03X58686Y257551I-1J1502D01*
G01X58687D01*
G02X58779Y257574I93J-177D01*
G01X71101D01*
G02X71138Y257571I2J-200D01*
G02X71242Y257516I-37J-197D01*
G01X75591Y253166D01*
G03X76513Y252784I923J924D01*
G01X97864D01*
G02X97955Y252762I0J-200D01*
G02X98005Y252726I-90J-178D01*
G01X98090Y252641D01*
G02X98126Y252591I-142J-140D01*
G02X98148Y252500I-178J-91D01*
G01Y222913D01*
G02X98020Y222727I-200J1D01*
G01X97845Y222660D01*
X97669Y222593D01*
G02X97450Y222646I-71J187D01*
G03X96333Y223144I-1117J-1004D01*
G03Y220140I0J-1502D01*
G03X97450Y220637I1J1502D01*
G02X97451Y220639I172J-85D01*
G02X97551Y220698I147J-135D01*
G01X97552D01*
G02X97670Y220691I48J-194D01*
G01X98020Y220557D01*
G02X98148Y220371I-72J-187D01*
G01Y216980D01*
G03X98530Y216058I1306J1D01*
G01X106089Y208499D01*
G02X106135Y208429I-141J-143D01*
G01X106138Y208418D01*
G03X109006Y208417I1434J445D01*
G01Y208418D01*
X109009Y208429D01*
G02X109055Y208499I187J-73D01*
G01X111064Y210508D01*
G03X111446Y211430I-924J923D01*
G01Y216348D01*
G02X111537Y216515I200J-1D01*
G01X111599Y216555D01*
X111819Y216698D01*
G02X111913Y216730I109J-167D01*
G01X111962Y216734D01*
X112009Y216713D01*
G03X112620Y216583I611J1372D01*
G01X112621D01*
G03X113726Y217067I0J1503D01*
G01X113728Y217069D01*
X113836Y217116D01*
G02X113916Y217133I81J-183D01*
G01X114126D01*
G02X114206Y217116I-1J-200D01*
G01X114314Y217069D01*
X114316Y217067D01*
G03X115421Y216583I1105J1019D01*
G03Y219587I0J1502D01*
G03X114316Y219103I0J-1503D01*
G01X114314Y219101D01*
X114206Y219054D01*
G02X114126Y219037I-81J183D01*
G01X113916D01*
G02X113836Y219054I1J200D01*
G01X113728Y219101D01*
X113726Y219103D01*
G03X112739Y219582I-1105J-1020D01*
G03X111321Y218840I-119J-1499D01*
G01X111320Y218838D01*
G02X111260Y218774I-172J101D01*
G01X111242Y218761D01*
X111198Y218745D01*
X110954Y218713D01*
X110861Y218701D01*
G02X110696Y218755I-26J198D01*
G01X109133Y220319D01*
G03X108209Y220702I-924J-923D01*
G01X107046D01*
G02X106846Y220902I0J200D01*
G01Y224143D01*
G02X106868Y224234I200J0D01*
G02X106904Y224284I178J-90D01*
G01X106999Y224379D01*
G03X107382Y225303I-923J924D01*
G01Y260144D01*
G02X107386Y260182I200J-2D01*
G02X107439Y260284I196J-37D01*
G01X112384Y265229D01*
G03X112766Y266151I-924J923D01*
G01Y367728D01*
G02X112879Y367908I200J0D01*
G01X112891Y367913D01*
G02X113009Y367924I77J-185D01*
G01X113035Y367919D01*
X113085Y367892D01*
X137300Y343678D01*
G02X137347Y343603I-142J-141D01*
G02X137358Y343537I-189J-65D01*
G01Y242491D01*
G02X137335Y242399I-200J1D01*
G37*
G36*
G01X69119Y606083D02*
G03X67684Y607139I-1435J-447D01*
G03X67626Y607138I-3J-1502D01*
G03X67484Y607126I55J-1501D01*
G03X66476Y606531I199J-1489D01*
G01Y606530D01*
X66467Y606518D01*
X66443Y606494D01*
G02X66316Y606436I-141J141D01*
G01X66069Y606418D01*
G02X65913Y606476I-15J199D01*
G01X65315Y607074D01*
G03X63684Y607750I-1632J-1631D01*
G03X61935Y606947I0J-2306D01*
G02X61789Y606877I-152J130D01*
G01X61606Y606872D01*
G02X61459Y606930I-6J200D01*
G01X61315Y607074D01*
G03X59684Y607750I-1632J-1631D01*
G03X57378Y605444I0J-2306D01*
G01Y605442D01*
G03X58053Y603812I2306J0D01*
G01X62915Y598950D01*
G02X62973Y598788I-141J-142D01*
G01X62953Y598594D01*
X62948Y598543D01*
G02X62890Y598420I-199J19D01*
G01X62849Y598379D01*
X62834Y598369D01*
G03X62182Y597130I851J-1239D01*
G03X63684Y595628I1502J0D01*
G03X65173Y596934I0J1502D01*
G01X65174Y596940D01*
X65175Y596945D01*
X65179Y596976D01*
X65223Y597061D01*
G02X65286Y597141I184J-80D01*
G01X65323Y597173D01*
X65401Y597198D01*
X65443Y597194D01*
G03X65668Y597184I215J2296D01*
G01X65966D01*
G02X66096Y597136I0J-200D01*
G01X66110Y597124D01*
X66136Y597099D01*
X66202Y596983D01*
X66208Y596951D01*
G03X67684Y595730I1476J282D01*
G03X69170Y597012I0J1502D01*
G01Y597015D01*
G02X69368Y597184I198J-31D01*
G01X70792D01*
G02X70958Y597096I0J-200D01*
G01X71022Y597001D01*
Y596999D01*
X71142Y596818D01*
X71151Y596720D01*
X71131Y596673D01*
G03X71013Y596092I1384J-584D01*
G01Y596076D01*
G03X74017I1502J13D01*
G01Y596090D01*
G03X73899Y596673I-1502J-1D01*
G01X73879Y596720D01*
X73888Y596818D01*
X74008Y596999D01*
Y597001D01*
X74072Y597096D01*
G02X74238Y597184I166J-112D01*
G01X75957D01*
G02X75976Y597167I-123J-157D01*
G01X76176Y596960D01*
G02X76232Y596821I-144J-139D01*
G01Y596746D01*
X76233Y596717D01*
G03X79235I1501J65D01*
G01X79236Y596746D01*
Y596819D01*
Y596823D01*
G02X79293Y596963I200J0D01*
G01X79335Y597006D01*
X79450Y597124D01*
G02X79593Y597184I143J-140D01*
G01X81950D01*
G02X82104Y597112I0J-200D01*
G01X82134Y597077D01*
Y597075D01*
X82146Y597062D01*
G02X82194Y596923I-152J-130D01*
G01X82193Y596914D01*
X82192Y596907D01*
G03X82182Y596729I1492J-173D01*
G03X83684Y595227I1502J0D01*
G03X85176Y596553I0J1502D01*
G01X85186Y596638D01*
G03X85187Y596658I-199J20D01*
G01Y596730D01*
G03X85185Y596806I-1503J-2D01*
G01X85183Y596845D01*
X85197Y596885D01*
X85211Y596928D01*
X85397Y597122D01*
G02X85542Y597184I145J-138D01*
G01X87269D01*
G02X87409Y597127I0J-200D01*
G01X87410Y597126D01*
X89807Y594729D01*
G02X89809Y594727I-140J-142D01*
G02X89866Y594587I-143J-140D01*
G01Y447038D01*
X89795Y446936D01*
X89735Y446914D01*
G03Y444098I522J-1408D01*
G01X89764Y444087D01*
X89812Y444050D01*
X89830Y444025D01*
G02X89866Y443910I-164J-114D01*
G01Y377875D01*
G03X90541Y376245I2306J0D01*
G01X93907Y372879D01*
G03X95537Y372204I1630J1631D01*
G01X98256D01*
G03X99427Y372523I1J2306D01*
G02X99528Y372551I102J-172D01*
G01X102937D01*
G02X102956Y372550I-1J-200D01*
G02X103079Y372492I-19J-199D01*
G01X105865Y369706D01*
G02X105924Y369564I-141J-142D01*
G01Y309629D01*
G02X105865Y309487I-200J0D01*
G01X102711Y306333D01*
G02X102569Y306274I-142J141D01*
G01X79125D01*
X79096Y306256D01*
X75149D01*
G03X74227Y305874I1J-1306D01*
G01X49086Y280733D01*
X49058Y280704D01*
X48984Y280674D01*
X39942D01*
G02X39795Y280738I0J200D01*
G01X39730Y280807D01*
Y280809D01*
X39568Y280984D01*
X39541Y281062D01*
X39544Y281104D01*
G03X39550Y281272I-2260J165D01*
G01Y281274D01*
G03X39068Y282671I-2267J0D01*
G02X39057Y282686I156J126D01*
G03X38748Y283070I-1941J-1246D01*
G01X29187Y292631D01*
G03X27557Y293306I-1630J-1631D01*
G01X14498D01*
G03X12868Y292631I0J-2306D01*
G01X6636Y286399D01*
X6608Y286370D01*
X6534Y286340D01*
X6043D01*
G02X5901Y286399I0J200D01*
G01X5259Y287041D01*
X5230Y287069D01*
X5200Y287143D01*
Y324217D01*
G02X5257Y324357I200J0D01*
G01X5258Y324358D01*
X21983Y341083D01*
G03X22042Y341225I-141J142D01*
G01Y493869D01*
G02X22504Y494263I400J-1D01*
G02X22614Y494207I-31J-198D01*
G01X25762Y491058D01*
G03X26684Y490676I923J924D01*
G01X34882D01*
X34929Y490664D01*
X34950Y490653D01*
G03X35204Y490548I698J1330D01*
G01X35227Y490540D01*
X35269Y490515D01*
X36293Y489491D01*
G02X36295Y489489I-140J-142D01*
G02X36352Y489349I-143J-140D01*
G01Y477403D01*
G03X36735Y476479I1306J0D01*
G01X40176Y473038D01*
X40201Y472996D01*
X40208Y472973D01*
G03X41643Y471917I1435J447D01*
G03X42011Y471962I3J1502D01*
G01X42057Y471973D01*
X42146Y471954D01*
X42317Y471821D01*
G02X42394Y471663I-123J-158D01*
G01Y470820D01*
G03X42776Y469898I1306J1D01*
G01X43408Y469266D01*
G03X44330Y468884I923J924D01*
G01X59371D01*
G03X60293Y469266I-1J1306D01*
G01X62604Y471578D01*
X62645Y471603D01*
X62669Y471610D01*
G03X63726Y473045I-446J1435D01*
G03X62224Y474547I-1502J0D01*
G03X60789Y473491I0J-1503D01*
G01X60782Y473468D01*
X60757Y473426D01*
X58887Y471555D01*
X58859Y471526D01*
X58785Y471496D01*
X51209D01*
G02X51033Y471601I0J200D01*
G01X50888Y471871D01*
G02X50893Y472069I176J95D01*
G01X50914Y472104D01*
X50915Y472106D01*
X50920Y472113D01*
G03X51145Y472905I-1278J791D01*
G03X49643Y474407I-1502J0D01*
G03X48142Y472961I0J-1502D01*
G01Y472960D01*
X48140Y472917D01*
Y472905D01*
G03X48389Y472077I1503J1D01*
G01X48390Y472076D01*
G02X48399Y471874I-168J-109D01*
G01X48398Y471872D01*
X48253Y471602D01*
G02X48077Y471496I-176J94D01*
G01X47209D01*
G02X47033Y471601I0J200D01*
G01X46888Y471871D01*
G02X46893Y472069I176J95D01*
G01X46914Y472104D01*
X46915Y472106D01*
X46920Y472113D01*
G03X47145Y472905I-1278J791D01*
G03X45643Y474407I-1502J0D01*
G03X45485Y474398I6J-1502D01*
G01X45442Y474394D01*
X45362Y474419D01*
X45136Y474621D01*
X45133Y474624D01*
X45109Y474645D01*
G02X45040Y474796I131J151D01*
G01Y480664D01*
X45105Y480763D01*
X45160Y480787D01*
G03X46065Y482165I-597J1378D01*
G03X45008Y483600I-1503J0D01*
G01X44984Y483607D01*
X44943Y483632D01*
X41477Y487098D01*
X41448Y487126D01*
X41418Y487200D01*
Y492918D01*
G03X41383Y493216I-1306J-2D01*
G01Y493218D01*
X41378Y493241D01*
Y493358D01*
G03X41319Y493500I-200J0D01*
G01X41237Y493582D01*
X41224Y493602D01*
X41223Y493604D01*
G03X41036Y493841I-1112J-685D01*
G01X39943Y494934D01*
G03X39707Y495121I-924J-924D01*
G01X39687Y495133D01*
X39602Y495218D01*
G03X39461Y495276I-141J-142D01*
G01X39460D01*
X39343D01*
X39320Y495281D01*
G03X39020Y495316I-300J-1271D01*
G01X37494D01*
G02X37341Y495387I0J200D01*
G01X37321Y495411D01*
X37177Y495582D01*
G02X37161Y495604I153J128D01*
G02X37130Y495723I169J108D01*
G03X37152Y495982I-1480J256D01*
G03X34148I-1502J0D01*
G03X34170Y495723I1502J-3D01*
G02X34139Y495604I-200J-11D01*
G02X34123Y495582I-169J106D01*
G01X33979Y495411D01*
X33959Y495387D01*
G02X33806Y495316I-153J129D01*
G01X29142D01*
G02X29000Y495375I0J200D01*
G01X27185Y497191D01*
X27156Y497219D01*
X27126Y497293D01*
Y526956D01*
X27138Y527003D01*
X27149Y527025D01*
G03X27322Y527725I-1330J700D01*
G01Y527736D01*
X27320Y527783D01*
G03X25819Y529228I-1501J-57D01*
G01X25818D01*
G03X25057Y529020I1J-1500D01*
G02X25037Y529010I-99J174D01*
G03X25029Y529006I84J-179D01*
G01X24984Y528983D01*
X24885Y528986D01*
X24579Y529160D01*
G02X24478Y529334I99J174D01*
G01Y543118D01*
G02X24580Y543292I200J0D01*
G01X24842Y543441D01*
G02X24941Y543467I99J-174D01*
G01X24997D01*
X25045Y543438D01*
G03X25818Y543224I773J1288D01*
G01X25854D01*
G03X27321Y544726I-35J1502D01*
G03X25819Y546228I-1502J0D01*
G01X25818D01*
G03X25057Y546020I1J-1500D01*
G02X25037Y546010I-99J174D01*
G03X25029Y546006I84J-179D01*
G01X24984Y545983D01*
X24885Y545986D01*
X24579Y546160D01*
G02X24478Y546334I99J174D01*
G01Y547118D01*
G02X24580Y547292I200J0D01*
G01X24842Y547441D01*
G02X24941Y547467I99J-174D01*
G01X24997D01*
X25045Y547438D01*
G03X25818Y547224I773J1288D01*
G01X25854D01*
G03X27321Y548726I-35J1502D01*
G03X25819Y550228I-1502J0D01*
G01X25818D01*
G03X25057Y550020I1J-1500D01*
G02X25037Y550010I-99J174D01*
G03X25029Y550006I84J-179D01*
G01X24984Y549983D01*
X24885Y549986D01*
X24579Y550160D01*
G02X24478Y550334I99J174D01*
G01Y837238D01*
G02X24537Y837380I200J0D01*
G01X39196Y852039D01*
G02X39338Y852098I142J-141D01*
G01X63918D01*
G02X64261Y851492I0J-400D01*
G03X64046Y850718I1288J-775D01*
G03X67052I1503J0D01*
G03X66837Y851492I-1503J-1D01*
G02X67180Y852098I343J206D01*
G01X119528D01*
G02X119670Y852039I0J-200D01*
G01X120797Y850912D01*
G02X120856Y850770I-141J-142D01*
G01Y808994D01*
G02X120797Y808852I-200J0D01*
G01X110310Y798365D01*
G02X110105Y798316I-142J141D01*
G01X110094Y798320D01*
X110092Y798321D01*
G03X109591Y798407I-501J-1416D01*
G03X108089Y796919I0J-1502D01*
G01Y796904D01*
G03X108178Y796395I1502J0D01*
G01X108198Y796340D01*
X108173Y796228D01*
X106731Y794786D01*
G03X106672Y794644I141J-142D01*
G01Y774460D01*
G02X106613Y774318I-200J0D01*
G01X93684Y761389D01*
G03X93625Y761247I141J-142D01*
G01Y664380D01*
G03X93684Y664238I200J0D01*
G01X94249Y663673D01*
X94262Y663652D01*
G03X94749Y663166I1276J792D01*
G01X94769Y663153D01*
X96513Y661409D01*
G02X96515Y661407I-140J-142D01*
G02X96572Y661267I-143J-140D01*
G01Y660260D01*
G02X96503Y660109I-200J0D01*
G01X96244Y659883D01*
X96162Y659858D01*
X96119Y659864D01*
G03X95919Y659877I-197J-1490D01*
G01X95917D01*
G03X94719Y659281I0J-1502D01*
G01X94690Y659243D01*
X94608Y659202D01*
X94408Y659201D01*
X94263Y659200D01*
G02X94227Y659203I-1J200D01*
G01X94169Y659213D01*
X94107Y659251D01*
X94084Y659280D01*
G03X93981Y659398I-1181J-927D01*
G03X92897Y659861I-1085J-1040D01*
G03Y656857I0J-1502D01*
G03X94086Y657442I0J1501D01*
G01X94094Y657452D01*
X94095Y657453D01*
X94122Y657489D01*
X94205Y657531D01*
X94406Y657532D01*
X94615Y657533D01*
X94697Y657493D01*
X94726Y657456D01*
G03X94828Y657338I1187J923D01*
G01X94829Y657337D01*
G03X94888Y657279I1083J1042D01*
G01X94916Y657252D01*
X94933Y657216D01*
G02X94951Y657136I-182J-83D01*
G01X94953Y656997D01*
Y656995D01*
X94956Y656854D01*
G02X94900Y656711I-200J-4D01*
G01X94899Y656710D01*
G03X94471Y655660I1074J-1050D01*
G03X95603Y654204I1502J0D01*
G01X95604D01*
G02X95718Y654124I-51J-193D01*
G01X95888Y653881D01*
X95906Y653814D01*
X95902Y653777D01*
G03X95896Y653645I1300J-125D01*
G01Y599834D01*
G02X95775Y599650I-200J0D01*
G02X95554Y599693I-79J184D01*
G01X91213Y604034D01*
G03X90291Y604416I-923J-924D01*
G01X89276D01*
G02X89102Y604517I0J200D01*
G01X89050Y604600D01*
G02X89024Y604748I170J106D01*
G01X89030Y604775D01*
X89040Y604796D01*
G03X89186Y605441I-1356J646D01*
G01Y605443D01*
G03X86182I-1502J0D01*
G03X86329Y604797I1501J2D01*
G01X86330Y604794D01*
X86341Y604769D01*
X86346Y604744D01*
G02X86334Y604630I-197J-37D01*
G01X86325Y604608D01*
X86262Y604509D01*
G02X86261Y604507I-179J88D01*
G02X86094Y604416I-168J109D01*
G01X81480D01*
X81479D01*
G02X81325Y604489I1J200D01*
G02X81317Y604500I158J123D01*
G01X81100Y604806D01*
X81086Y604901D01*
X81102Y604948D01*
G03X81186Y605442I-1418J495D01*
G01Y605443D01*
G03X78182I-1502J0D01*
G03X78329Y604797I1501J2D01*
G01X78330Y604794D01*
X78341Y604769D01*
X78346Y604744D01*
G02X78334Y604630I-197J-37D01*
G01X78325Y604608D01*
X78262Y604509D01*
G02X78261Y604507I-179J88D01*
G02X78094Y604416I-168J109D01*
G01X70835D01*
G02X70693Y604475I0J200D01*
G01X69151Y606018D01*
X69126Y606060D01*
X69119Y606083D01*
G37*
G36*
G01X59228Y1018314D02*
Y1004106D01*
G02X59169Y1003965I-200J1D01*
G01X58601Y1003397D01*
X58573Y1003368D01*
X58499Y1003338D01*
X11122D01*
G02X10980Y1003397I0J200D01*
G01X7648Y1006729D01*
G02X7589Y1006871I141J142D01*
G01Y1019074D01*
X7879Y1019364D01*
X58178D01*
X59228Y1018314D01*
G37*
G36*
G01X6739Y1083957D02*
X34609D01*
G02X34751Y1083898I0J-200D01*
G01X36086Y1082563D01*
G02X36145Y1082421I-141J-142D01*
G01Y1076830D01*
G03X36204Y1076688I200J0D01*
G01X45755Y1067137D01*
G03X45897Y1067078I142J141D01*
G01X58719D01*
G02X58861Y1067019I0J-200D01*
G01X59210Y1066670D01*
G02X59269Y1066528I-141J-142D01*
G01Y1023063D01*
G02X59210Y1022921I-200J0D01*
G01X57306Y1021017D01*
G02X57164Y1020958I-142J141D01*
G01X7398D01*
G02X7256Y1021017I0J200D01*
G01X5469Y1022804D01*
G02X5410Y1022946I141J142D01*
G01Y1063440D01*
G02X5480Y1063592I200J0D01*
G01X5745Y1063818D01*
X5829Y1063841D01*
X5873Y1063835D01*
G03X6108Y1063816I238J1483D01*
G03Y1066820I0J1502D01*
G03X5873Y1066801I3J-1502D01*
G01X5829Y1066795D01*
X5745Y1066818D01*
X5480Y1067044D01*
G02X5410Y1067196I130J152D01*
G01Y1068733D01*
G02X5480Y1068885I200J0D01*
G01X5745Y1069111D01*
X5829Y1069134D01*
X5873Y1069128D01*
G03X6108Y1069109I238J1483D01*
G03Y1072113I0J1502D01*
G03X5873Y1072094I3J-1502D01*
G01X5829Y1072088D01*
X5745Y1072111D01*
X5480Y1072337D01*
G02X5410Y1072489I130J152D01*
G01Y1074122D01*
G02X5482Y1074276I200J0D01*
G01X5754Y1074501D01*
X5840Y1074523D01*
X5884Y1074515D01*
G03X6161Y1074489I278J1476D01*
G03Y1077493I0J1502D01*
G03X5884Y1077467I1J-1502D01*
G01X5840Y1077459D01*
X5754Y1077481D01*
X5482Y1077706D01*
G02X5410Y1077860I128J154D01*
G01Y1079419D01*
G02X5478Y1079569I200J0D01*
G01X5736Y1079796D01*
X5818Y1079821D01*
X5861Y1079815D01*
G03X6053Y1079803I190J1490D01*
G03X7555Y1081305I0J1502D01*
G03X6353Y1082777I-1502J0D01*
G01X6299Y1082788D01*
X6218Y1082862D01*
X6100Y1083252D01*
G02X6150Y1083451I192J58D01*
G01X6597Y1083898D01*
G02X6739Y1083957I142J-141D01*
G37*
G36*
G01X6510Y1146766D02*
X71708D01*
G02X71850Y1146707I0J-200D01*
G01X73598Y1144959D01*
G02X73657Y1144817I-141J-142D01*
G01Y1092978D01*
G02X73598Y1092836I-200J0D01*
G01X65944Y1085182D01*
G03X65885Y1085040I141J-142D01*
G01Y1072137D01*
G02X65826Y1071995I-200J0D01*
G01X63164Y1069333D01*
X63136Y1069304D01*
X63062Y1069274D01*
X45593D01*
G02X45451Y1069333I0J200D01*
G01X37597Y1077187D01*
X37568Y1077215D01*
X37538Y1077289D01*
Y1080248D01*
X37568Y1080321D01*
X37570Y1080323D01*
Y1084574D01*
G03X37511Y1084716I-200J0D01*
G01X36424Y1085803D01*
G03X36282Y1085862I-142J-141D01*
G01X7936D01*
G02X7784Y1085932I0J200D01*
G01X7558Y1086195D01*
X7534Y1086278D01*
X7540Y1086322D01*
G03X7557Y1086546I-1485J225D01*
G03X6055Y1088048I-1502J0D01*
G03X5848Y1088034I-2J-1502D01*
G01X5804Y1088028D01*
X5722Y1088052D01*
X5462Y1088279D01*
G02X5393Y1088430I131J151D01*
G01Y1090081D01*
G02X5462Y1090232I200J0D01*
G01X5723Y1090459D01*
X5805Y1090483D01*
X5849Y1090477D01*
G03X6059Y1090462I212J1487D01*
G03Y1093466I0J1502D01*
G03X5849Y1093451I2J-1502D01*
G01X5805Y1093445D01*
X5723Y1093469D01*
X5462Y1093696D01*
G02X5393Y1093847I131J151D01*
G01Y1145649D01*
G02X5452Y1145791I200J0D01*
G01X6368Y1146707D01*
G02X6510Y1146766I142J-141D01*
G37*
G36*
G01X18593Y1537672D02*
X61738D01*
G02X61878Y1537615I0J-200D01*
G01X61879Y1537614D01*
X63113Y1536380D01*
G02X63172Y1536238I-141J-142D01*
G01Y1513886D01*
G02X63113Y1513744I-200J0D01*
G01X61054Y1511685D01*
G02X60912Y1511626I-142J141D01*
G01X54398D01*
G03X54256Y1511567I0J-200D01*
G01X51521Y1508832D01*
G03X51462Y1508690I141J-142D01*
G01Y1461494D01*
G02X51403Y1461352I-200J0D01*
G01X47017Y1456966D01*
G02X46875Y1456907I-142J141D01*
G01X22722D01*
G03X22580Y1456848I0J-200D01*
G01X20446Y1454714D01*
G03X20387Y1454572I141J-142D01*
G01Y1435147D01*
G02X20328Y1435005I-200J0D01*
G01X19245Y1433922D01*
G02X19103Y1433863I-142J141D01*
G01X10862D01*
G02X10720Y1433922I0J200D01*
G01X8661Y1435981D01*
G02X8602Y1436123I141J142D01*
G01Y1492694D01*
G02X8709Y1492871I200J0D01*
G01X9073Y1493061D01*
X9184Y1493054D01*
X9230Y1493022D01*
G03X10089Y1492752I859J1231D01*
G03Y1495756I0J1502D01*
G03X9230Y1495486I0J-1501D01*
G01X9184Y1495454D01*
X9073Y1495447D01*
X8710Y1495637D01*
G02X8627Y1495719I93J177D01*
G01X8626D01*
G02X8602Y1495815I176J95D01*
G01Y1497581D01*
G02X8661Y1497723I200J0D01*
G01X13197Y1502259D01*
G02X13339Y1502318I142J-141D01*
G01X23381D01*
G03X23523Y1502377I0J200D01*
G01X24606Y1503460D01*
G03X24665Y1503602I-141J142D01*
G01Y1512369D01*
G03X24606Y1512511I-200J0D01*
G01X23673Y1513444D01*
G03X23531Y1513503I-142J-141D01*
G01X17843D01*
G02X17701Y1513562I0J200D01*
G01X16318Y1514945D01*
G02X16259Y1515087I141J142D01*
G01Y1522052D01*
G02X16318Y1522194I200J0D01*
G01X17175Y1523051D01*
G02X17317Y1523110I142J-141D01*
G01X23006D01*
G03X23148Y1523169I0J200D01*
G01X24081Y1524102D01*
G03X24140Y1524244I-141J142D01*
G01Y1531134D01*
G03X24081Y1531276I-200J0D01*
G01X23073Y1532284D01*
G03X22931Y1532343I-142J-141D01*
G01X17693D01*
G02X17551Y1532402I0J200D01*
G01X16318Y1533635D01*
G02X16259Y1533777I141J142D01*
G01Y1535338D01*
G02X16318Y1535480I200J0D01*
G01X18451Y1537613D01*
G02X18593Y1537672I142J-141D01*
G37*
G36*
G01X30969Y1560341D02*
X71195D01*
G02X71335Y1560284I0J-200D01*
G01X71336Y1560283D01*
X74972Y1556647D01*
G02X75031Y1556505I-141J-142D01*
G01Y1530005D01*
G02X75019Y1529938I-200J1D01*
G01X73312Y1525163D01*
G03X73269Y1525029I1788J-648D01*
G01X66148Y1499298D01*
G03X66116Y1499162I1834J-503D01*
G01X65656Y1496850D01*
G02X65460Y1496689I-196J39D01*
G01X54473D01*
G02X54331Y1496748I0J200D01*
G01X52522Y1498557D01*
G02X52464Y1498698I142J141D01*
G01Y1506690D01*
G02X52521Y1506830I200J0D01*
G01X52522Y1506831D01*
X55757Y1510066D01*
G02X55899Y1510125I142J-141D01*
G01X61587D01*
G03X61729Y1510184I0J200D01*
G01X64389Y1512844D01*
G03X64448Y1512986I-141J142D01*
G01Y1537064D01*
G03X64389Y1537206I-200J0D01*
G01X62893Y1538702D01*
G03X62751Y1538761I-142J-141D01*
G01X18519D01*
G03X18395Y1538718I0J-200D01*
G02X18393Y1538716I-141J139D01*
G02X18270Y1538674I-123J158D01*
G01X18178D01*
G03X18037Y1538615I1J-200D01*
G01X15316Y1535894D01*
G03X15258Y1535754I142J-141D01*
G01Y1533361D01*
G03X15316Y1533221I200J1D01*
G01X17137Y1531400D01*
G03X17277Y1531342I141J142D01*
G01X22516D01*
G02X22658Y1531283I0J-200D01*
G01X23030Y1530910D01*
G02X23089Y1530769I-141J-142D01*
G01Y1525295D01*
G02X23030Y1525153I-200J0D01*
G01X22097Y1524220D01*
G02X21955Y1524161I-142J141D01*
G01X16867D01*
G03X16725Y1524102I0J-200D01*
G01X15455Y1522832D01*
G03X15401Y1522735I141J-142D01*
G02X15347Y1522639I-195J46D01*
G01X15316Y1522608D01*
G03X15258Y1522468I142J-141D01*
G01Y1514671D01*
G03X15316Y1514531I200J1D01*
G01X17287Y1512560D01*
G03X17427Y1512502I141J142D01*
G01X23114D01*
G02X23224Y1512470I1J-200D01*
G01X23246Y1512455D01*
X23605Y1512096D01*
G02X23653Y1512018I-142J-141D01*
G01X23664Y1511985D01*
Y1503959D01*
X23628Y1503904D01*
G02X23602Y1503872I-167J109D01*
G01X23109Y1503379D01*
X23081Y1503350D01*
X23007Y1503320D01*
X12924D01*
G03X12783Y1503261I1J-200D01*
G01X12648Y1503127D01*
G02X12507Y1503069I-141J142D01*
G01X8460D01*
G02X8318Y1503128I0J200D01*
G01X5509Y1505937D01*
G02X5450Y1506079I141J142D01*
G01Y1536996D01*
G02X5558Y1537174I200J0D01*
G01X5866Y1537334D01*
G02X5887Y1537343I89J-179D01*
G01X5892Y1537345D01*
G02X6052Y1537337I71J-187D01*
G01X6082Y1537322D01*
X6094Y1537314D01*
G03X6951Y1537045I858J1232D01*
G03Y1540049I0J1502D01*
G03X6094Y1539780I1J-1501D01*
G01X6082Y1539772D01*
X6052Y1539757D01*
G02X5892Y1539749I-89J179D01*
G01X5876Y1539755D01*
X5558Y1539920D01*
G02X5461Y1540033I92J177D01*
G01X5450Y1540065D01*
Y1552453D01*
G02X5538Y1552619I200J0D01*
G01X5814Y1552805D01*
G02X6001Y1552824I111J-166D01*
G03X6567Y1552713I567J1391D01*
G03X8069Y1554215I0J1502D01*
G03X6907Y1555678I-1502J0D01*
G02X6858Y1555696I44J195D01*
G01X6836Y1555708D01*
X6746Y1555790D01*
G02X6689Y1555880I134J148D01*
G01X6602Y1556164D01*
G02X6652Y1556364I191J58D01*
G01X10570Y1560282D01*
G02X10712Y1560341I142J-141D01*
G01X16275D01*
G02X16327Y1560334I0J-200D01*
G01X16400Y1560314D01*
X16423Y1560301D01*
X16424D01*
X16470Y1560275D01*
G03X20470Y1559218I4002J7048D01*
G01X26774D01*
G03X30774Y1560275I-2J8105D01*
G01X30820Y1560301D01*
X30821D01*
X30844Y1560314D01*
X30917Y1560334D01*
G02X30969Y1560341I52J-193D01*
G37*
G36*
G01X35871Y139166D02*
X38956D01*
G02X39097Y139107I-1J-200D01*
G01X47576Y130628D01*
G02X47634Y130487I-142J-141D01*
G01Y126637D01*
G03X48310Y125006I2307J1D01*
G01X58853Y114463D01*
G02X58897Y114245I-141J-142D01*
G01X58873Y114188D01*
X58774Y114122D01*
X56472D01*
G02X56331Y114180I0J200D01*
G01X49269Y121242D01*
G03X47638Y121918I-1632J-1631D01*
G01X45736D01*
G02X45595Y121976I0J200D01*
G01X45197Y122374D01*
G02X45138Y122515I141J142D01*
G01Y128522D01*
G03X44463Y130153I-2306J1D01*
G01X35792Y138824D01*
G02X35748Y139042I141J142D01*
G01X35772Y139099D01*
X35871Y139166D01*
G37*
G36*
G01X50277Y1636181D02*
X88993D01*
G02X89135Y1636122I0J-200D01*
G01X91922Y1633335D01*
G02X91981Y1633193I-141J-142D01*
G01Y1595148D01*
G02X91922Y1595006I-200J0D01*
G01X83009Y1586093D01*
G02X82867Y1586034I-142J141D01*
G01X75751D01*
G03X75609Y1585975I0J-200D01*
G01X73493Y1583859D01*
G03X73434Y1583717I141J-142D01*
G01Y1579979D01*
G02X73375Y1579837I-200J0D01*
G01X70424Y1576886D01*
G02X70282Y1576827I-142J141D01*
G01X44309D01*
G02X44167Y1576886I0J200D01*
G01X43102Y1577951D01*
G02X43043Y1578093I141J142D01*
G01Y1597518D01*
G02X43055Y1597587I200J1D01*
G03X44324Y1604724I-19433J7137D01*
G03X43055Y1611861I-20702J0D01*
G02X43043Y1611930I188J68D01*
G01Y1628947D01*
G02X43102Y1629089I200J0D01*
G01X50135Y1636122D01*
G02X50277Y1636181I142J-141D01*
G37*
G36*
G01X61085Y93334D02*
X58089Y96330D01*
G02X58045Y96548I141J142D01*
G01X58069Y96605D01*
X58168Y96672D01*
X69997D01*
G02X70138Y96613I-1J-200D01*
G01X71753Y94998D01*
G03X72677Y94616I923J924D01*
G01X76935D01*
G02X77037Y94587I-2J-200D01*
G03X77804Y94377I766J1292D01*
G03X78503Y94550I-1J1502D01*
G01X78525Y94561D01*
X78572Y94572D01*
X80689D01*
G02X80874Y94449I0J-200D01*
G01X80897Y94392D01*
X80874Y94275D01*
X79933Y93334D01*
G02X79792Y93276I-141J142D01*
G01X66358D01*
X66256Y93346D01*
X66234Y93405D01*
G03X63424I-1405J-531D01*
G01X63402Y93346D01*
X63300Y93276D01*
X61226D01*
G02X61085Y93334I0J200D01*
G37*
G36*
G01X137657Y54588D02*
X166715D01*
X166891Y54412D01*
Y52762D01*
X166720Y52591D01*
X137657D01*
G03X131720Y46654I0J-5937D01*
G01Y7874D01*
G02X125846Y2000I-5874J0D01*
G01X78602D01*
G02X72728Y7874I0J5874D01*
G01Y45793D01*
X74726D01*
Y7874D01*
G03X78602Y3998I3876J0D01*
G01X125846D01*
G03X129722Y7874I0J3876D01*
G01Y46654D01*
G02X137657Y54588I7935J-1D01*
G37*
G36*
G01X97118Y113489D02*
G03X97342Y113789I-924J924D01*
G01X97369Y113838D01*
X97462Y113893D01*
X97518D01*
G02X97718Y113693I0J-200D01*
G01Y112347D01*
G02X97659Y112206I-200J1D01*
G01X82697Y97244D01*
G02X82556Y97186I-141J142D01*
G01X78572D01*
X78525Y97197D01*
X78503Y97208D01*
G03X77804Y97381I-700J-1329D01*
G03X77183Y97246I1J-1502D01*
G01X77143Y97228D01*
X74773D01*
G02X74601Y97327I1J200D01*
G01X74399Y97670D01*
X74398Y97776D01*
X74423Y97822D01*
G03X74612Y98551I-1313J729D01*
G03X73110Y100053I-1502J0D01*
G03X71796Y99278I0J-1501D01*
G01X71777Y99243D01*
X71714Y99194D01*
X71366Y99094D01*
X71287Y99103D01*
X71253Y99122D01*
G03X70621Y99284I-630J-1144D01*
G01X70329D01*
G02X70144Y99408I0J200D01*
G01X70121Y99465D01*
X70144Y99582D01*
X72803Y102241D01*
G02X72944Y102300I142J-141D01*
G01X73371D01*
G02X73512Y102241I-1J-200D01*
G01X74799Y100954D01*
G03X75723Y100572I923J924D01*
G01X83659D01*
G03X84583Y100954I1J1306D01*
G01X97118Y113489D01*
G37*
G36*
G01X76602Y1580680D02*
G03I-597J0D01*
G37*
G36*
G01X83030Y1580590D02*
G03I-597J0D01*
G37*
G36*
G01X231727Y1089015D02*
X231728D01*
G02X231965Y1088981I96J-175D01*
G01X232162Y1088784D01*
G02X232221Y1088642I-141J-142D01*
G01Y1087849D01*
G02X232126Y1087678I-200J-1D01*
G01X231791Y1087472D01*
X231688Y1087468D01*
X231642Y1087491D01*
G03X231102Y1087619I-540J-1075D01*
G03Y1085215I0J-1202D01*
G03X231642Y1085343I0J1203D01*
G01X231688Y1085366D01*
X231791Y1085362D01*
X232126Y1085156D01*
G02X232221Y1084985I-105J-170D01*
G01Y1084109D01*
G02X232126Y1083938I-200J-1D01*
G01X231791Y1083732D01*
X231688Y1083728D01*
X231642Y1083751D01*
G03X231102Y1083879I-540J-1075D01*
G03Y1081475I0J-1202D01*
G03X231174Y1081477I3J1202D01*
G01X231175D01*
G02X231357Y1081382I12J-200D01*
G01X231541Y1081081D01*
G02X231543Y1080875I-170J-105D01*
G03X231474Y1080752I3302J-1933D01*
G02X231404Y1080678I-176J96D01*
G03X230829Y1080235I2037J-3239D01*
G02X230747Y1080189I-136J147D01*
G03X229849Y1079291I355J-1253D01*
G02X229803Y1079209I-193J54D01*
G03X228770Y1076594I2793J-2615D01*
G01Y1076440D01*
G02X228656Y1076260I-200J0D01*
G01X228278Y1076079D01*
X228164Y1076093D01*
X228119Y1076130D01*
G03X227362Y1076398I-757J-935D01*
G03Y1073994I0J-1202D01*
G03X228119Y1074262I0J1203D01*
G01X228164Y1074299D01*
X228278Y1074313D01*
X228656Y1074132D01*
G02X228770Y1073952I-86J-180D01*
G01Y1071282D01*
G02X228756Y1071210I-200J1D01*
G03X228490Y1069788I3660J-1420D01*
G01Y1063972D01*
G02X228483Y1063919I-200J-1D01*
G01X130233Y712541D01*
G02X130040Y712395I-193J54D01*
G01X110282D01*
G02X110082Y712595I0J200D01*
G01Y745641D01*
G02X110141Y745783I200J0D01*
G01X118088Y753730D01*
G02X118332Y753761I142J-141D01*
G03X119099Y753550I767J1290D01*
G03X120507Y754528I0J1503D01*
G01X120522Y754569D01*
X129146Y763193D01*
G03X129528Y764115I-924J923D01*
G01Y798495D01*
G02X129587Y798637I200J0D01*
G01X132404Y801453D01*
G03X132786Y802375I-924J923D01*
G01Y845155D01*
G02X132845Y845297I200J0D01*
G01X142424Y854875D01*
G03X142806Y855797I-924J923D01*
G01Y947453D01*
G02X142821Y947530I200J1D01*
G01X158908Y986366D01*
G03X159008Y986866I-1207J501D01*
G01Y986960D01*
G02X159083Y987116I200J0D01*
G01X159329Y987311D01*
G02X159497Y987350I125J-156D01*
G01X159498D01*
G03X159836Y987311I340J1463D01*
G03Y990315I0J1502D01*
G03X159499Y990276I3J-1502D01*
G01X159497D01*
X159453Y990266D01*
X159365Y990286D01*
X159083Y990510D01*
G02X159008Y990666I125J156D01*
G01Y995995D01*
G03X158625Y996919I-1306J0D01*
G01X157319Y998225D01*
G02X157270Y998305I141J142D01*
G01Y998306D01*
G03X155836Y999362I-1434J-446D01*
G03X154334Y997860I0J-1502D01*
G03X155389Y996426I1502J0D01*
G01X155391D01*
G02X155471Y996377I-62J-190D01*
G01X156335Y995513D01*
G02X156394Y995371I-141J-142D01*
G01Y987166D01*
G02X156379Y987089I-200J-1D01*
G01X140293Y948253D01*
G03X140194Y947755I1207J-499D01*
G01Y893854D01*
G02X140071Y893670I-200J1D01*
G02X139852Y893713I-78J184D01*
G01X139653Y893912D01*
G03X139511Y893971I-142J-141D01*
G01X132874D01*
G02X132732Y894030I0J200D01*
G01X100037Y926726D01*
G02X99978Y926868I141J142D01*
G01Y957423D01*
G03X99919Y957565I-200J0D01*
G01X84139Y973344D01*
G02X84080Y973486I141J142D01*
G01Y997052D01*
G02X84196Y997234I200J0D01*
G01X84578Y997412D01*
X84693Y997396D01*
X84738Y997358D01*
G03X85705Y997005I967J1149D01*
G01X85706D01*
G03Y1000009I0J1502D01*
G01X85705D01*
G03X84738Y999656I0J-1502D01*
G01X84693Y999618D01*
X84578Y999602D01*
X84196Y999780D01*
G02X84080Y999962I84J182D01*
G01Y1020400D01*
G02X84139Y1020542I200J0D01*
G01X86591Y1022993D01*
G02X86754Y1023051I142J-141D01*
G01X87110Y1023011D01*
X87187Y1022964D01*
X87211Y1022925D01*
G03X88479Y1022229I1268J807D01*
G03X89981Y1023731I0J1502D01*
G03X89412Y1024908I-1502J0D01*
G01X89379Y1024934D01*
X89340Y1025009D01*
X89317Y1025346D01*
G02X89372Y1025498I200J14D01*
G03X89789Y1026528I-1085J1039D01*
G01Y1026567D01*
X89819Y1026640D01*
X94650Y1031471D01*
G02X94792Y1031530I142J-141D01*
G01X100124D01*
G02X100281Y1031453I-1J-200D01*
G01X100505Y1031168D01*
X100523Y1031079D01*
X100512Y1031034D01*
G03X100468Y1030674I1458J-361D01*
G01Y1030672D01*
G03X101028Y1029501I1504J0D01*
G02X101103Y1029346I-125J-156D01*
G01Y1028138D01*
G03X101162Y1027996I200J0D01*
G01X105316Y1023842D01*
G03X105458Y1023783I142J141D01*
G01X108851D01*
X108956Y1023706D01*
X108976Y1023643D01*
G03X111842I1433J451D01*
G01X111862Y1023706D01*
X111967Y1023783D01*
X135517D01*
G02X135635Y1023744I-1J-200D01*
G03X135743Y1023673I878J1218D01*
G02X135839Y1023505I-104J-171D01*
G01X135840Y1023382D01*
G02X135750Y1023211I-200J-4D01*
G03X135069Y1021954I820J-1257D01*
G03X138073I1502J0D01*
G03X137354Y1023235I-1501J0D01*
G02X137258Y1023403I104J171D01*
G01X137257Y1023526D01*
G02X137347Y1023697I200J4D01*
G03X137416Y1023744I-811J1264D01*
G01X137469Y1023783D01*
X137495D01*
X140299Y1026587D01*
G02X140441Y1026646I142J-141D01*
G01X140630D01*
G02X140813Y1026526I0J-200D01*
G01X140960Y1026190D01*
G02X140923Y1025974I-184J-80D01*
G03X140524Y1024954I1104J-1020D01*
G03X143528I1502J0D01*
G03X143129Y1025974I-1503J0D01*
G02X143092Y1026190I147J136D01*
G01X143239Y1026526D01*
G02X143422Y1026646I183J-80D01*
G01X161409D01*
G03X161742Y1026677I5J1751D01*
G01X161760Y1026681D01*
X162358D01*
G03X162500Y1026740I0J200D01*
G01X178709Y1042949D01*
G03X178768Y1043091I-141J142D01*
G01Y1054103D01*
G03X178710Y1054243I-200J-1D01*
G01X178706Y1054248D01*
X178676Y1054320D01*
Y1057283D01*
G03X178162Y1058521I-1751J-1D01*
G01X172893Y1063790D01*
G02X172834Y1063932I141J142D01*
G01Y1065992D01*
G03X172321Y1067230I-1750J0D01*
G01X169024Y1070527D01*
G03X167786Y1071040I-1238J-1237D01*
G01X161996D01*
G02X161854Y1071099I0J200D01*
G01X161242Y1071711D01*
G03X161100Y1071770I-142J-141D01*
G01X159278D01*
G02X159093Y1071895I0J200D01*
G01X158954Y1072240D01*
G02X159000Y1072458I186J75D01*
G01X159001Y1072459D01*
G03X159371Y1073326I-831J867D01*
G03X158169Y1074528I-1202J0D01*
G03X157726Y1074443I1J-1202D01*
G01X157725D01*
G02X157540Y1074463I-73J186D01*
G01X157266Y1074649D01*
G02X157178Y1074815I112J166D01*
G01Y1075577D01*
G02X157266Y1075743I200J0D01*
G01X157540Y1075929D01*
G02X157725Y1075949I112J-166D01*
G01X157726D01*
G03X158169Y1075864I444J1117D01*
G03Y1078268I0J1202D01*
G03X157726Y1078183I1J-1202D01*
G01X157725D01*
G02X157540Y1078203I-73J186D01*
G01X157266Y1078389D01*
G02X157178Y1078555I112J166D01*
G01Y1089128D01*
G02X157237Y1089270I200J0D01*
G01X157749Y1089782D01*
G02X157891Y1089841I142J-141D01*
G01X169912D01*
X170014Y1089770D01*
X170036Y1089710D01*
G03X172482I1223J447D01*
G01X172504Y1089770D01*
X172606Y1089841D01*
X173652D01*
X173754Y1089770D01*
X173776Y1089710D01*
G03X176222I1223J447D01*
G01X176244Y1089770D01*
X176346Y1089841D01*
X177393D01*
X177495Y1089770D01*
X177517Y1089710D01*
G03X179963I1223J447D01*
G01X179985Y1089770D01*
X180087Y1089841D01*
X181133D01*
X181235Y1089770D01*
X181257Y1089710D01*
G03X183703I1223J447D01*
G01X183725Y1089770D01*
X183827Y1089841D01*
X184873D01*
X184975Y1089770D01*
X184997Y1089710D01*
G03X187443I1223J447D01*
G01X187465Y1089770D01*
X187567Y1089841D01*
X188613D01*
X188715Y1089770D01*
X188737Y1089710D01*
G03X191183I1223J447D01*
G01X191205Y1089770D01*
X191307Y1089841D01*
X192353D01*
X192455Y1089770D01*
X192477Y1089710D01*
G03X194923I1223J447D01*
G01X194945Y1089770D01*
X195047Y1089841D01*
X196093D01*
X196195Y1089770D01*
X196217Y1089710D01*
G03X198663I1223J447D01*
G01X198685Y1089770D01*
X198787Y1089841D01*
X199834D01*
X199936Y1089770D01*
X199958Y1089710D01*
G03X202404I1223J447D01*
G01X202426Y1089770D01*
X202528Y1089841D01*
X203574D01*
X203676Y1089770D01*
X203698Y1089710D01*
G03X206144I1223J447D01*
G01X206166Y1089770D01*
X206268Y1089841D01*
X207314D01*
X207416Y1089770D01*
X207438Y1089710D01*
G03X209884I1223J447D01*
G01X209906Y1089770D01*
X210008Y1089841D01*
X211054D01*
X211156Y1089770D01*
X211178Y1089710D01*
G03X213624I1223J447D01*
G01X213646Y1089770D01*
X213748Y1089841D01*
X214794D01*
X214896Y1089770D01*
X214918Y1089710D01*
G03X217364I1223J447D01*
G01X217386Y1089770D01*
X217488Y1089841D01*
X218534D01*
X218636Y1089770D01*
X218658Y1089710D01*
G03X221104I1223J447D01*
G01X221126Y1089770D01*
X221228Y1089841D01*
X222275D01*
X222377Y1089770D01*
X222399Y1089710D01*
G03X224845I1223J447D01*
G01X224867Y1089770D01*
X224969Y1089841D01*
X226015D01*
X226117Y1089770D01*
X226139Y1089710D01*
G03X228585I1223J447D01*
G01X228607Y1089770D01*
X228709Y1089841D01*
X229755D01*
X229857Y1089770D01*
X229879Y1089710D01*
G03X231102Y1088855I1223J447D01*
G03X231727Y1089015I0J1301D01*
G37*
G36*
G01X103677Y1186725D02*
X106237D01*
G02X106313Y1186710I0J-200D01*
G01X110319Y1185050D01*
G02X110384Y1185007I-76J-185D01*
G01X114324Y1181067D01*
G03X114466Y1181008I142J141D01*
G01X122865D01*
G02X123003Y1180952I-1J-200D01*
G01X123231Y1180734D01*
X123263Y1180665D01*
X123264Y1180625D01*
G03X123908Y1179457I1501J66D01*
G01X123947Y1179431D01*
X123991Y1179351D01*
X124013Y1178942D01*
X123977Y1178857D01*
X123942Y1178826D01*
G03X123423Y1177691I983J-1136D01*
G03X126427I1502J0D01*
G03X125782Y1178925I-1503J0D01*
G01X125743Y1178951D01*
X125699Y1179031D01*
X125677Y1179440D01*
X125713Y1179525D01*
X125748Y1179556D01*
G03X126266Y1180625I-982J1136D01*
G01X126267Y1180665D01*
X126299Y1180734D01*
X126527Y1180952D01*
G02X126665Y1181008I139J-144D01*
G01X129129D01*
G02X129283Y1180936I0J-200D01*
G01X129508Y1180666D01*
X129531Y1180580D01*
X129522Y1180536D01*
G03X129498Y1180266I1478J-267D01*
G03X131000Y1178764I1502J0D01*
G03X132016Y1179160I0J1501D01*
G01X132045Y1179187D01*
X132116Y1179214D01*
X132433Y1179207D01*
G02X132570Y1179148I-5J-200D01*
G01X134099Y1177619D01*
G02X134158Y1177477I-141J-142D01*
G01Y1101095D01*
G02X134099Y1100953I-200J0D01*
G01X132980Y1099834D01*
G02X132839Y1099776I-141J142D01*
G01X110566D01*
G03X108935Y1099100I1J-2307D01*
G01X108456Y1098621D01*
G02X108314Y1098562I-142J141D01*
G01X89218D01*
G02X89077Y1098621I1J200D01*
G01X84371Y1103326D01*
G02X84312Y1103467I141J142D01*
G01Y1162787D01*
G02X84371Y1162928I200J-1D01*
G01X98324Y1176880D01*
G03X98880Y1178225I-1346J1344D01*
G01Y1181929D01*
G02X98939Y1182070I200J-1D01*
G01X103535Y1186666D01*
G02X103677Y1186725I142J-141D01*
G37*
G36*
G01X100760Y217606D02*
Y229381D01*
G02X100884Y229566I200J0D01*
G01X100941Y229589D01*
X101058Y229566D01*
X102374Y228250D01*
X102399Y228208D01*
X102407Y228185D01*
G03X103841Y227129I1434J446D01*
G03X104258Y227188I0J1503D01*
G01X104304Y227201D01*
X104395Y227184D01*
X104689Y226963D01*
G02X104768Y226804I-121J-159D01*
G01Y225927D01*
G02X104710Y225786I-200J0D01*
G01X104615Y225691D01*
G03X104232Y224767I923J-924D01*
G01Y221177D01*
G02X104149Y221014I-200J-1D01*
G01X103844Y220797D01*
X103749Y220783D01*
X103702Y220799D01*
G03X103213Y220881I-489J-1420D01*
G03Y217877I0J-1502D01*
G03X104471Y218559I0J1501D01*
G01X104496Y218597D01*
X104573Y218644D01*
X104927Y218681D01*
G02X105089Y218623I20J-199D01*
G01X105241Y218471D01*
G03X106165Y218088I924J923D01*
G01X107585D01*
G02X107726Y218030I0J-200D01*
G01X108775Y216981D01*
G02X108834Y216840I-141J-142D01*
G01Y212056D01*
G02X108775Y211915I-200J1D01*
G01X107713Y210853D01*
G02X107431I-141J142D01*
G01X100819Y217465D01*
G02X100760Y217606I141J142D01*
G37*
G36*
G01X173126Y1097070D02*
G03X172915Y1097053I-1J-1302D01*
G01X172914D01*
G02X172744Y1097106I-32J197D01*
G01X172479Y1097360D01*
X172447Y1097448D01*
X172453Y1097495D01*
G03X172461Y1097637I-1194J139D01*
G03X171259Y1096435I-1202J0D01*
G03X171400Y1096443I3J1202D01*
G01X171447Y1096449D01*
X171535Y1096417D01*
X171821Y1096117D01*
X171849Y1096027D01*
X171841Y1095981D01*
G03X171824Y1095769I1285J-210D01*
G01Y1095490D01*
G02X171758Y1095341I-200J0D01*
G01X171506Y1095114D01*
X171424Y1095088D01*
X171383Y1095093D01*
G03X171259Y1095099I-120J-1196D01*
G03X170057Y1093897I0J-1202D01*
G03X170078Y1093676I1202J3D01*
G01Y1093674D01*
G02X170023Y1093497I-197J-36D01*
G01X169753Y1093228D01*
X169660Y1093199D01*
X169624Y1093206D01*
G03X168186Y1092041I-236J-1179D01*
G01Y1092024D01*
G03X168332Y1091451I1202J1D01*
G01X168336Y1091443D01*
X168338Y1091440D01*
X168352Y1091413D01*
G02X168368Y1091333I-184J-78D01*
G01X168367Y1091280D01*
X168319Y1091198D01*
X168157Y1090921D01*
G02X168039Y1090842I-163J116D01*
G01X166997D01*
G02X166879Y1090921I45J195D01*
G01X166717Y1091198D01*
X166695Y1091235D01*
G02X166667Y1091335I172J102D01*
G01Y1091339D01*
G02X166678Y1091404I200J0D01*
G01X166695Y1091433D01*
G03X166851Y1091994I-1046J593D01*
G01Y1092027D01*
G03X165649Y1093229I-1202J0D01*
G01X165648D01*
G03X164446Y1092041I0J-1202D01*
G01Y1092024D01*
G03X164592Y1091451I1202J1D01*
G01X164596Y1091443D01*
X164598Y1091440D01*
X164612Y1091413D01*
G02X164628Y1091333I-184J-78D01*
G01X164627Y1091280D01*
X164579Y1091198D01*
X164417Y1090921D01*
G02X164299Y1090842I-163J116D01*
G01X163257D01*
G02X163139Y1090921I45J195D01*
G01X162977Y1091198D01*
X162955Y1091235D01*
G02X162927Y1091335I172J102D01*
G01Y1091339D01*
G02X162938Y1091404I200J0D01*
G01X162955Y1091433D01*
G03X163111Y1091994I-1046J593D01*
G01Y1092027D01*
G03X161909Y1093229I-1202J0D01*
G01X161908D01*
G03X160706Y1092041I0J-1202D01*
G01Y1092024D01*
G03X160852Y1091451I1202J1D01*
G01X160856Y1091443D01*
X160858Y1091440D01*
X160872Y1091413D01*
G02X160888Y1091333I-184J-78D01*
G01X160887Y1091280D01*
X160839Y1091198D01*
X160677Y1090921D01*
G02X160559Y1090842I-163J116D01*
G01X159517D01*
G02X159399Y1090921I45J195D01*
G01X159237Y1091198D01*
X159215Y1091235D01*
G02X159187Y1091335I172J102D01*
G01Y1091339D01*
G02X159198Y1091404I200J0D01*
G01X159215Y1091433D01*
G03X159371Y1091994I-1046J593D01*
G01Y1092027D01*
G03X158169Y1093229I-1202J0D01*
G01X158168D01*
G03X156966Y1092041I0J-1202D01*
G01Y1092024D01*
G03X157112Y1091451I1202J1D01*
G01X157116Y1091443D01*
X157118Y1091440D01*
X157132Y1091412D01*
G02X157148Y1091333I-184J-78D01*
G01X157147Y1091280D01*
Y1090679D01*
G02X157088Y1090537I-200J0D01*
G01X156235Y1089685D01*
G03X156176Y1089543I141J-142D01*
G01Y1072069D01*
G03X156235Y1071927I200J0D01*
G01X156910Y1071253D01*
G02X156969Y1071111I-141J-142D01*
G01Y1068552D01*
G02X156910Y1068410I-200J0D01*
G01X156503Y1068003D01*
G02X156361Y1067944I-142J141D01*
G01X150434D01*
G02X150292Y1068003I0J200D01*
G01X148205Y1070090D01*
G02X148146Y1070232I141J142D01*
G01Y1076968D01*
X148147Y1076975D01*
G03X148150Y1077065I-1199J85D01*
G01Y1077067D01*
G03X148147Y1077157I-1202J5D01*
G01X148146Y1077164D01*
Y1080708D01*
X148147Y1080715D01*
G03X148150Y1080805I-1199J85D01*
G01Y1080807D01*
G03X148147Y1080897I-1202J5D01*
G01X148146Y1080904D01*
Y1084449D01*
X148147Y1084456D01*
G03X148150Y1084546I-1199J85D01*
G01Y1084548D01*
G03X148147Y1084638I-1202J5D01*
G01X148146Y1084645D01*
Y1087363D01*
G03X148087Y1087505I-200J0D01*
G01X148065Y1087527D01*
G02X148027Y1087756I142J141D01*
G01Y1087757D01*
G03X148150Y1088287I-1080J530D01*
G03X146948Y1089489I-1202J0D01*
G03X146418Y1089366I0J-1203D01*
G01X146417D01*
G02X146188Y1089404I-88J180D01*
G01X144753Y1090839D01*
X144729D01*
G02X144650Y1090867I26J198D01*
G01X144608Y1090905D01*
X144606Y1090907D01*
G03X144596Y1090916I-138J-143D01*
G01X144586Y1090923D01*
X144369Y1091140D01*
G02X144312Y1091256I141J142D01*
G01Y1091257D01*
G02X144313Y1091314I198J25D01*
G01X144315Y1091325D01*
G02X144329Y1091366I195J-44D01*
G01X144337Y1091380D01*
G03X144509Y1092027I-1131J647D01*
G03X143207Y1093329I-1302J0D01*
G03X142603Y1093180I1J-1303D01*
G01X142602D01*
G02X142510Y1093157I-93J177D01*
G01X142362D01*
X142343Y1093166D01*
X135453Y1100056D01*
G02X135417Y1100106I142J140D01*
G02X135395Y1100197I178J91D01*
G01Y1178868D01*
G02X135417Y1178959I200J0D01*
G02X135453Y1179009I178J-90D01*
G01X135614Y1179170D01*
G02X135664Y1179206I140J-142D01*
G02X135755Y1179228I91J-178D01*
G01X138266D01*
G03X138365Y1179229I10J3892D01*
G01X138383Y1179230D01*
X139440D01*
G03X139479I19J3891D01*
G01X139522D01*
G03X139539Y1179231I-220J3884D01*
G01X139562D01*
X139579Y1179232D01*
X139592D01*
G02X139744Y1179154I-7J-200D01*
G01X139818Y1179051D01*
G02X139854Y1178958I-163J-116D01*
G01X139860Y1178910D01*
X139791Y1178829D01*
G03X139505Y1178050I918J-779D01*
G03X140707Y1176848I1202J0D01*
G03X141595Y1177240I0J1202D01*
G01X141596Y1177241D01*
G02X141737Y1177305I147J-136D01*
G01X141900Y1177301D01*
X142051Y1177297D01*
G02X142133Y1177277I-5J-200D01*
G01X142170Y1177259D01*
X142172Y1177257D01*
X142199Y1177224D01*
G03X143205Y1176748I1007J827D01*
G01X146929D01*
X146931D01*
G03X147710Y1176995I15J1303D01*
G03X148063Y1177379I-763J1056D01*
G03X148065Y1177383I-1165J585D01*
G03X148087Y1177423I-1130J647D01*
G02X148089Y1177425I142J-140D01*
G03X148195Y1177677I-1141J628D01*
G01X148196Y1177681D01*
G03X148203Y1177705I-1247J377D01*
G01X148206Y1177716D01*
X148207Y1177719D01*
G03X148210Y1177729I-1244J379D01*
G01X148211Y1177733D01*
Y1177734D01*
X148212Y1177738D01*
X148213Y1177741D01*
X148214Y1177748D01*
G03X148222Y1177784I-1268J301D01*
G03X148231Y1177832I-1276J264D01*
G03X148250Y1178051I-1284J222D01*
G03X147994Y1178826I-1303J-1D01*
G01X147981Y1178843D01*
X147978Y1178848D01*
G02X147967Y1179018I176J97D01*
G01X148056Y1179193D01*
Y1179195D01*
X148079Y1179239D01*
Y1179241D01*
X148136Y1179354D01*
G02X148314Y1179464I179J-90D01*
G01X149423D01*
G02X149473Y1179457I-3J-200D01*
G01X149550Y1179434D01*
G02X149590Y1179402I-104J-171D01*
G02X149628Y1179347I-143J-140D01*
G01X149671Y1179254D01*
X149789Y1179000D01*
G02X149800Y1178938I-189J-65D01*
G01X149777Y1178873D01*
Y1178871D01*
X149757Y1178813D01*
X149737Y1178788D01*
G03X149485Y1178058I950J-736D01*
G01Y1178021D01*
G03X150687Y1176849I1202J30D01*
G01X150688D01*
G03X151890Y1178054I0J1202D01*
G01Y1178057D01*
G03X151638Y1178787I-1202J-6D01*
G01X151617Y1178814D01*
X151574Y1178938D01*
G02X151585Y1179000I200J-3D01*
G01X151703Y1179254D01*
X151748Y1179351D01*
G02X151762Y1179375I179J-88D01*
G02X151815Y1179429I167J-111D01*
G01X151837Y1179442D01*
G02X151875Y1179457I92J-178D01*
G02X151926Y1179464I52J-193D01*
G01X151996D01*
G03X153253Y1179679I-2J3796D01*
G03X153566Y1179805I-1260J3582D01*
G01X153567D01*
G03X153596Y1179819I-1636J3426D01*
G01X153639Y1179838D01*
X153667Y1179852D01*
X153689Y1179864D01*
X153703Y1179871D01*
X153704D01*
G03X153713Y1179876I-1838J3318D01*
G01X153723Y1179881D01*
X153726Y1179883D01*
X153757Y1179899D01*
X153758D01*
X153759Y1179900D01*
X153760D01*
G03X153767Y1179904I-1872J3283D01*
G01X153768D01*
G03X153771Y1179906I-109J166D01*
G01X153772D01*
G03X153774Y1179907I-1692J3386D01*
G01X153790Y1179916D01*
X153792Y1179917D01*
G03X154128Y1180121I-1800J3343D01*
G01X154141Y1180130D01*
G03X154669Y1180568I-2150J3129D01*
G03X154684Y1180583I-2677J2692D01*
G01X154693Y1180592D01*
G02X154764Y1180637I140J-143D01*
G01X154775Y1180640D01*
G03X154948Y1180707I-346J1151D01*
G02X155215Y1180440I87J-180D01*
G03X155097Y1179921I1084J-519D01*
G03X157501I1202J0D01*
G03X157480Y1180143I-1202J-2D01*
G01X157471Y1180192D01*
X157500Y1180285D01*
X157803Y1180589D01*
X157898Y1180618D01*
X157947Y1180609D01*
G03X158168Y1180589I218J1182D01*
G03X159370Y1181791I0J1202D01*
G03X159345Y1182033I-1203J-2D01*
G01Y1182037D01*
X159340Y1182063D01*
X159369Y1182156D01*
X159674Y1182460D01*
X159767Y1182489D01*
X159816Y1182480D01*
G03X160039Y1182459I224J1181D01*
G03X160261Y1182480I-2J1202D01*
G01X160310Y1182489D01*
X160403Y1182460D01*
X160708Y1182155D01*
X160737Y1182062D01*
X160728Y1182013D01*
G03X160707Y1181791I1181J-224D01*
G03X163111I1202J0D01*
G03X163090Y1182013I-1202J-2D01*
G01X163081Y1182062D01*
X163110Y1182155D01*
X163415Y1182460D01*
X163508Y1182489D01*
X163557Y1182480D01*
G03X163779Y1182459I224J1181D01*
G03X164001Y1182480I-2J1202D01*
G01X164050Y1182489D01*
X164143Y1182460D01*
X164448Y1182155D01*
X164477Y1182062D01*
X164468Y1182013D01*
G03X164447Y1181791I1181J-224D01*
G03X166851I1202J0D01*
G03X166830Y1182013I-1202J-2D01*
G01X166821Y1182062D01*
X166850Y1182155D01*
X167155Y1182460D01*
X167248Y1182489D01*
X167297Y1182480D01*
G03X167519Y1182459I224J1181D01*
G03Y1184863I0J1202D01*
G03X167376Y1184854I4J-1202D01*
G01X167375D01*
G02X167207Y1184914I-24J199D01*
G01X166953Y1185180D01*
X166925Y1185269D01*
X166929Y1185295D01*
G03X166951Y1185531I-1281J238D01*
G03X166929Y1185764I-1303J-5D01*
G01Y1185770D01*
X166925Y1185793D01*
X166953Y1185882D01*
X167207Y1186148D01*
G02X167375Y1186208I144J-139D01*
G01X167376D01*
G03X167519Y1186199I147J1193D01*
G03X166317Y1187401I0J1202D01*
G03X166326Y1187259I1202J5D01*
G01Y1187257D01*
X166331Y1187211D01*
X166299Y1187123D01*
X165999Y1186836D01*
X165910Y1186809D01*
X165877Y1186814D01*
G03X165651Y1186834I-227J-1283D01*
G01X165372D01*
G02X165223Y1186900I0J200D01*
G01X165024Y1187121D01*
G02X164974Y1187275I149J134D01*
G01Y1187276D01*
G03X164981Y1187401I-1195J130D01*
G03X163779Y1188603I-1202J0D01*
G03X163635Y1188594I3J-1202D01*
G01X163634D01*
G02X163466Y1188654I-24J199D01*
G01X163212Y1188920D01*
X163185Y1189009D01*
X163189Y1189036D01*
G03X163210Y1189271I-1281J233D01*
G03X163189Y1189505I-1302J1D01*
G01Y1189507D01*
X163185Y1189533D01*
X163212Y1189622D01*
X163466Y1189888D01*
G02X163634Y1189948I144J-139D01*
G01X163635D01*
G03X163779Y1189939I147J1193D01*
G03X164981Y1191141I0J1202D01*
G03X164974Y1191265I-1202J-6D01*
G01Y1191267D01*
G02X165024Y1191421I199J20D01*
G01X165223Y1191642D01*
G02X165372Y1191708I149J-134D01*
G01X165651D01*
G03X165876Y1191728I-2J1303D01*
G01X165878D01*
X165910Y1191733D01*
X165999Y1191706D01*
X166265Y1191451D01*
G02X166326Y1191285I-138J-145D01*
G01Y1191284D01*
G03X166317Y1191141I1193J-147D01*
G03X167519Y1192343I1202J0D01*
G03X167376Y1192334I4J-1202D01*
G01X167375D01*
G02X167207Y1192394I-24J199D01*
G01X166953Y1192660D01*
X166925Y1192749D01*
X166929Y1192775D01*
G03X166951Y1193011I-1281J238D01*
G03X166929Y1193244I-1303J-5D01*
G01Y1193250D01*
X166925Y1193273D01*
X166953Y1193362D01*
X167207Y1193628D01*
G02X167375Y1193688I144J-139D01*
G01X167376D01*
G03X167519Y1193679I147J1193D01*
G03X166317Y1194881I0J1202D01*
G03X166326Y1194739I1202J5D01*
G01Y1194737D01*
X166331Y1194691D01*
X166299Y1194603D01*
X165999Y1194316D01*
X165910Y1194289D01*
X165877Y1194294D01*
G03X165651Y1194314I-227J-1283D01*
G01X165372D01*
G02X165223Y1194380I0J200D01*
G01X165024Y1194601D01*
G02X164974Y1194755I149J134D01*
G01Y1194756D01*
G03X164981Y1194881I-1195J130D01*
G03X163779Y1196083I-1202J0D01*
G03X163634Y1196074I2J-1202D01*
G01X163633D01*
G02X163465Y1196134I-24J199D01*
G01X163211Y1196400D01*
X163183Y1196490D01*
X163191Y1196537D01*
G03Y1196965I-1282J214D01*
G01X163183Y1197012D01*
X163211Y1197102D01*
X163465Y1197368D01*
G02X163633Y1197428I144J-139D01*
G01X163634D01*
G03X163779Y1197419I147J1193D01*
G03X164981Y1198621I0J1202D01*
G03X164974Y1198747I-1202J-4D01*
G01Y1198749D01*
X164970Y1198790D01*
X164996Y1198870D01*
X165223Y1199124D01*
G02X165372Y1199190I149J-134D01*
G01X165604D01*
X165612Y1199189D01*
X165648D01*
G03X165877Y1199209I2J1304D01*
G01X165879D01*
X165910Y1199214D01*
X165999Y1199187D01*
X166300Y1198901D01*
X166332Y1198811D01*
X166326Y1198765D01*
G03X166317Y1198621I1193J-147D01*
G03X167519Y1199823I1202J0D01*
G01X167517D01*
G03X167128Y1199758I1J-1202D01*
G02X167098Y1199750I-66J189D01*
G01X167046Y1199741D01*
G02X166846Y1199941I0J200D01*
G01X166857Y1199996D01*
G02X166866Y1200028I196J-38D01*
G03X166893Y1200107I-1219J461D01*
G01Y1200109D01*
G03X166899Y1200127I-1233J421D01*
G01Y1200128D01*
X166908Y1200157D01*
G03X166912Y1200170I-1241J389D01*
G01X166914Y1200179D01*
X166919Y1200201D01*
G03X166922Y1200215I-1272J280D01*
G01Y1200216D01*
X166926Y1200236D01*
G03X166944Y1200355I-1278J254D01*
G01Y1200356D01*
X166945Y1200362D01*
Y1200368D01*
G03X166946Y1200378I-1296J135D01*
G01Y1200379D01*
G03X166948Y1200404I-1298J116D01*
G01Y1200413D01*
G03X166949Y1200428I-1299J94D01*
G01Y1200432D01*
X166950Y1200439D01*
Y1200470D01*
G03Y1200486I-1302J8D01*
G01Y1200493D01*
G03X166929Y1200726I-1302J0D01*
G01Y1200728D01*
X166925Y1200754D01*
X166952Y1200843D01*
X167206Y1201109D01*
G02X167374Y1201169I144J-139D01*
G01X167375D01*
G03X167519Y1201160I147J1193D01*
G03X166317Y1202362I0J1202D01*
G03X166326Y1202218I1202J3D01*
G01X166332Y1202172D01*
X166300Y1202082D01*
X165999Y1201796D01*
X165910Y1201768D01*
X165876Y1201774D01*
G03X165649Y1201794I-227J-1282D01*
G01X165372D01*
G02X165223Y1201860I0J200D01*
G01X165024Y1202081D01*
G02X164974Y1202235I149J134D01*
G01Y1202236D01*
G03X164981Y1202362I-1195J130D01*
G03X163779Y1203564I-1202J0D01*
G03X163634Y1203555I2J-1202D01*
G01X163633D01*
G02X163465Y1203615I-24J199D01*
G01X163211Y1203881D01*
X163183Y1203971D01*
X163191Y1204018D01*
G03Y1204446I-1282J214D01*
G01X163183Y1204493D01*
X163211Y1204583D01*
X163465Y1204849D01*
G02X163633Y1204909I144J-139D01*
G01X163634D01*
G03X163779Y1204900I147J1193D01*
G03X164981Y1206102I0J1202D01*
G03X164974Y1206227I-1202J-5D01*
G01Y1206229D01*
G02X165024Y1206383I199J20D01*
G01X165223Y1206604D01*
G02X165372Y1206670I149J-134D01*
G01X165649D01*
G03X165875Y1206690I-1J1302D01*
G01X165877D01*
X165910Y1206696D01*
X165999Y1206668D01*
X166300Y1206382D01*
X166332Y1206292D01*
X166326Y1206246D01*
G03X166317Y1206102I1193J-147D01*
G03X167519Y1207304I1202J0D01*
G03X167375Y1207295I3J-1202D01*
G01X167374D01*
G02X167206Y1207355I-24J199D01*
G01X166952Y1207621D01*
X166925Y1207710D01*
X166929Y1207737D01*
G03X166950Y1207972I-1281J233D01*
G03X166929Y1208206I-1302J1D01*
G01Y1208208D01*
X166925Y1208234D01*
X166952Y1208323D01*
X167206Y1208589D01*
G02X167374Y1208649I144J-139D01*
G01X167375D01*
G03X167519Y1208640I147J1193D01*
G03X166317Y1209842I0J1202D01*
G03X166326Y1209698I1202J3D01*
G01X166332Y1209652D01*
X166300Y1209562D01*
X165999Y1209276D01*
X165910Y1209248D01*
X165876Y1209254D01*
G03X165649Y1209274I-227J-1282D01*
G01X165372D01*
G02X165223Y1209340I0J200D01*
G01X165024Y1209561D01*
G02X164974Y1209715I149J134D01*
G01Y1209716D01*
G03X164981Y1209842I-1195J130D01*
G03X163779Y1211044I-1202J0D01*
G03X163634Y1211035I2J-1202D01*
G01X163633D01*
G02X163465Y1211095I-24J199D01*
G01X163211Y1211361D01*
X163183Y1211451D01*
X163191Y1211498D01*
G03Y1211926I-1282J214D01*
G01X163183Y1211973D01*
X163211Y1212063D01*
X163465Y1212329D01*
G02X163633Y1212389I144J-139D01*
G01X163634D01*
G03X163779Y1212380I147J1193D01*
G03X164981Y1213582I0J1202D01*
G03X164974Y1213707I-1202J-5D01*
G01Y1213709D01*
G02X165024Y1213863I199J20D01*
G01X165223Y1214084D01*
G02X165372Y1214150I149J-134D01*
G01X165649D01*
G03X165875Y1214170I-1J1302D01*
G01X165877D01*
X165910Y1214176D01*
X165999Y1214148D01*
X166300Y1213862D01*
X166332Y1213772D01*
X166326Y1213726D01*
G03X166317Y1213582I1193J-147D01*
G03X167519Y1214784I1202J0D01*
G03X167375Y1214775I3J-1202D01*
G01X167374D01*
G02X167206Y1214835I-24J199D01*
G01X166952Y1215101D01*
X166925Y1215190D01*
X166929Y1215217D01*
G03X166950Y1215452I-1281J233D01*
G03X166929Y1215686I-1302J1D01*
G01Y1215688D01*
X166925Y1215714D01*
X166952Y1215803D01*
X167206Y1216069D01*
G02X167374Y1216129I144J-139D01*
G01X167375D01*
G03X167519Y1216120I147J1193D01*
G03X166317Y1217322I0J1202D01*
G03X166326Y1217178I1202J3D01*
G01X166332Y1217132D01*
X166300Y1217042D01*
X165999Y1216756D01*
X165910Y1216728D01*
X165876Y1216734D01*
G03X165649Y1216754I-227J-1282D01*
G01X165372D01*
G02X165223Y1216820I0J200D01*
G01X165024Y1217041D01*
G02X164974Y1217195I149J134D01*
G01Y1217196D01*
G03X164981Y1217322I-1195J130D01*
G03X163779Y1218524I-1202J0D01*
G03X163634Y1218515I2J-1202D01*
G01X163633D01*
G02X163465Y1218575I-24J199D01*
G01X163211Y1218841D01*
X163183Y1218931D01*
X163191Y1218978D01*
G03Y1219406I-1282J214D01*
G01X163183Y1219453D01*
X163211Y1219543D01*
X163465Y1219809D01*
G02X163633Y1219869I144J-139D01*
G01X163634D01*
G03X163779Y1219860I147J1193D01*
G03Y1222264I0J1202D01*
G03X163373Y1222193I1J-1202D01*
G02X163116Y1222446I-68J188D01*
G03X163153Y1222552I-1210J482D01*
G03X163167Y1222601I-1245J382D01*
G01X163172Y1222622D01*
G03X163210Y1222931I-1264J312D01*
G01Y1223210D01*
G02X163276Y1223359I200J0D01*
G01X163530Y1223586D01*
X163610Y1223612D01*
X163652Y1223608D01*
G03X163779Y1223601I130J1195D01*
G03Y1226005I0J1202D01*
G03X163653Y1225998I4J-1202D01*
G01X163651D01*
X163610Y1225994D01*
X163530Y1226020D01*
X163276Y1226247D01*
G02X163210Y1226396I134J149D01*
G01Y1226673D01*
G03X163190Y1226899I-1303J-1D01*
G01Y1226901D01*
X163184Y1226934D01*
X163212Y1227023D01*
X163466Y1227289D01*
G02X163635Y1227350I145J-137D01*
G03X163779Y1227341I147J1193D01*
G03Y1229745I0J1202D01*
G03X163556Y1229724I1J-1202D01*
G01X163507Y1229715D01*
X163414Y1229744D01*
X163109Y1230048D01*
X163080Y1230141D01*
X163085Y1230169D01*
G03Y1230657I-1178J244D01*
G01Y1230661D01*
X163080Y1230684D01*
X163110Y1230779D01*
X163379Y1231047D01*
G02X163556Y1231102I141J-142D01*
G01X163557D01*
G03X163779Y1231081I224J1181D01*
G03X164981Y1232283I0J1202D01*
G03X164973Y1232425I-1202J3D01*
G01Y1232426D01*
G02X165033Y1232594I199J24D01*
G01X165298Y1232847D01*
X165388Y1232875D01*
X165435Y1232867D01*
G03X165647Y1232850I210J1286D01*
G01X165648D01*
G03X165874Y1232870I-1J1303D01*
G01X165876D01*
X165910Y1232876D01*
X165999Y1232848D01*
X166265Y1232593D01*
G02X166326Y1232427I-138J-145D01*
G01Y1232426D01*
G03X166317Y1232283I1193J-147D01*
G03X167519Y1233485I1202J0D01*
G03X167375Y1233476I3J-1202D01*
G01X167374D01*
G02X167206Y1233536I-24J199D01*
G01X166952Y1233802D01*
X166924Y1233891D01*
X166928Y1233917D01*
G03X166950Y1234153I-1281J238D01*
G01Y1234430D01*
G02X167016Y1234579I200J0D01*
G01X167270Y1234806D01*
X167350Y1234832D01*
X167392Y1234828D01*
G03X167519Y1234821I130J1195D01*
G03X168721Y1236023I0J1202D01*
G03X168700Y1236245I-1202J-2D01*
G01X168691Y1236294D01*
X168720Y1236387D01*
X169023Y1236691D01*
X169118Y1236720D01*
X169167Y1236711D01*
G03X169515Y1236698I218J1182D01*
G01X169517D01*
G03X169623Y1236714I-126J1195D01*
G01X169625D01*
X169660Y1236721D01*
X169753Y1236692D01*
X170023Y1236423D01*
G02X170078Y1236246I-142J-141D01*
G01Y1236245D01*
G03X170057Y1236023I1181J-224D01*
G03X171259Y1234821I1202J0D01*
G03X171383Y1234828I-6J1202D01*
G01X171385D01*
G02X171539Y1234778I20J-199D01*
G01X171760Y1234579D01*
G02X171826Y1234430I-134J-149D01*
G01Y1234153D01*
G03X171848Y1233918I1302J3D01*
G01Y1233914D01*
X171852Y1233892D01*
X171824Y1233803D01*
X171537Y1233503D01*
X171449Y1233471D01*
X171402Y1233477D01*
G03X171259Y1233485I-139J-1194D01*
G03X172461Y1232283I0J-1202D01*
G03X172452Y1232425I-1202J-5D01*
G01Y1232428D01*
G02X172512Y1232594I199J22D01*
G01X172778Y1232849D01*
X172867Y1232877D01*
X172886Y1232874D01*
G03X173128Y1232851I244J1279D01*
G01X173129D01*
G03X173355Y1232871I-1J1302D01*
G01X173357D01*
X173390Y1232877D01*
X173479Y1232849D01*
X173780Y1232563D01*
X173812Y1232473D01*
X173806Y1232427D01*
G03X173797Y1232283I1193J-147D01*
G03X174999Y1233485I1202J0D01*
G03X174855Y1233476I3J-1202D01*
G01X174854D01*
G02X174686Y1233536I-24J199D01*
G01X174432Y1233802D01*
X174405Y1233891D01*
X174409Y1233918D01*
G03X174430Y1234153I-1281J233D01*
G01Y1234430D01*
G02X174496Y1234579I200J0D01*
G01X174750Y1234806D01*
X174830Y1234832D01*
X174872Y1234828D01*
G03X174999Y1234821I130J1195D01*
G03X176201Y1236023I0J1202D01*
G03X176180Y1236245I-1202J-2D01*
G01X176171Y1236294D01*
X176200Y1236387D01*
X176505Y1236692D01*
X176598Y1236721D01*
X176624Y1236716D01*
G03X176869Y1236691I244J1177D01*
G03X177104Y1236714I1J1202D01*
G01X177106D01*
X177141Y1236721D01*
X177234Y1236692D01*
X177504Y1236423D01*
G02X177559Y1236246I-142J-141D01*
G01Y1236245D01*
G03X177538Y1236023I1181J-224D01*
G03X178740Y1234821I1202J0D01*
G03X178865Y1234827I5J1202D01*
G01X178906Y1234832D01*
X178988Y1234806D01*
X179240Y1234579D01*
G02X179306Y1234430I-134J-149D01*
G01Y1234153D01*
G03X179328Y1233918I1302J3D01*
G01Y1233914D01*
X179332Y1233892D01*
X179304Y1233803D01*
X179017Y1233503D01*
X178929Y1233471D01*
X178882Y1233477D01*
G03X178740Y1233485I-139J-1194D01*
G03X179942Y1232283I0J-1202D01*
G03X179933Y1232425I-1202J-5D01*
G01Y1232427D01*
X179928Y1232473D01*
X179960Y1232561D01*
X180259Y1232848D01*
X180349Y1232876D01*
X180396Y1232868D01*
G03X180608Y1232851I210J1285D01*
G03X180834Y1232871I-1J1302D01*
G01X180837D01*
X180871Y1232877D01*
X180960Y1232849D01*
X181261Y1232563D01*
X181293Y1232473D01*
X181287Y1232427D01*
G03X181278Y1232283I1193J-147D01*
G03X182480Y1233485I1202J0D01*
G03X182335Y1233476I2J-1202D01*
G01X182288Y1233470D01*
X182200Y1233502D01*
X181912Y1233802D01*
X181885Y1233891D01*
X181889Y1233918D01*
G03X181910Y1234153I-1281J233D01*
G01Y1234430D01*
G02X181976Y1234579I200J0D01*
G01X182230Y1234806D01*
X182310Y1234832D01*
X182352Y1234828D01*
G03X182480Y1234821I130J1195D01*
G03X183682Y1236023I0J1202D01*
G03X183661Y1236245I-1202J-2D01*
G01X183652Y1236294D01*
X183681Y1236387D01*
X183984Y1236691D01*
X184079Y1236720D01*
X184128Y1236711D01*
G03X184349Y1236691I218J1182D01*
G03X184584Y1236714I1J1202D01*
G01X184586D01*
X184621Y1236721D01*
X184714Y1236692D01*
X184984Y1236423D01*
G02X185039Y1236246I-142J-141D01*
G01Y1236245D01*
G03X185018Y1236023I1181J-224D01*
G03X186220Y1234821I1202J0D01*
G03X186345Y1234827I5J1202D01*
G01X186386Y1234832D01*
X186468Y1234806D01*
X186720Y1234579D01*
G02X186786Y1234430I-134J-149D01*
G01Y1234153D01*
G03X186808Y1233918I1302J3D01*
G01Y1233914D01*
X186812Y1233892D01*
X186784Y1233803D01*
X186497Y1233503D01*
X186409Y1233471D01*
X186362Y1233477D01*
G03X186220Y1233485I-139J-1194D01*
G03X187422Y1232283I0J-1202D01*
G03X187413Y1232425I-1202J-5D01*
G01Y1232427D01*
X187408Y1232473D01*
X187440Y1232561D01*
X187739Y1232848D01*
X187829Y1232876D01*
X187876Y1232868D01*
G03X188088Y1232851I210J1285D01*
G03X188314Y1232871I-1J1302D01*
G01X188317D01*
X188351Y1232877D01*
X188440Y1232849D01*
X188741Y1232563D01*
X188773Y1232473D01*
X188767Y1232427D01*
G03X188758Y1232283I1193J-147D01*
G03X189960Y1233485I1202J0D01*
G03X189815Y1233476I2J-1202D01*
G01X189768Y1233470D01*
X189680Y1233502D01*
X189392Y1233802D01*
X189365Y1233891D01*
X189369Y1233918D01*
G03X189390Y1234153I-1281J233D01*
G01Y1234430D01*
G02X189456Y1234579I200J0D01*
G01X189710Y1234806D01*
X189790Y1234832D01*
X189832Y1234828D01*
G03X189960Y1234821I130J1195D01*
G03X191162Y1236023I0J1202D01*
G03X191141Y1236245I-1202J-2D01*
G01X191132Y1236294D01*
X191161Y1236387D01*
X191464Y1236691D01*
X191559Y1236720D01*
X191608Y1236711D01*
G03X191956Y1236698I218J1182D01*
G01X191958D01*
G03X192064Y1236714I-126J1195D01*
G01X192066D01*
X192101Y1236721D01*
X192194Y1236692D01*
X192464Y1236423D01*
G02X192519Y1236246I-142J-141D01*
G01Y1236245D01*
G03X192498Y1236023I1181J-224D01*
G03X193700Y1234821I1202J0D01*
G03X193825Y1234827I5J1202D01*
G01X193866Y1234832D01*
X193948Y1234806D01*
X194200Y1234579D01*
G02X194266Y1234430I-134J-149D01*
G01Y1234153D01*
G03X194288Y1233917I1303J2D01*
G01Y1233913D01*
X194292Y1233892D01*
X194264Y1233803D01*
X193977Y1233503D01*
X193889Y1233471D01*
X193842Y1233477D01*
G03X193700Y1233485I-139J-1194D01*
G03X194902Y1232283I0J-1202D01*
G03X194894Y1232426I-1202J4D01*
G01X194888Y1232473D01*
X194920Y1232561D01*
X195219Y1232848D01*
X195308Y1232876D01*
X195326Y1232873D01*
G03X195569Y1232850I244J1280D01*
G01X195572D01*
G03X195797Y1232870I-2J1303D01*
G01X195799D01*
X195831Y1232875D01*
X195920Y1232848D01*
X196186Y1232593D01*
G02X196247Y1232427I-138J-145D01*
G01Y1232426D01*
G03X196238Y1232283I1193J-147D01*
G03X197440Y1233485I1202J0D01*
G03X197297Y1233476I4J-1202D01*
G01X197296D01*
G02X197128Y1233536I-24J199D01*
G01X196874Y1233802D01*
X196846Y1233891D01*
X196850Y1233917D01*
G03X196872Y1234153I-1281J238D01*
G01Y1234430D01*
G02X196938Y1234579I200J0D01*
G01X197159Y1234778D01*
G02X197313Y1234828I134J-149D01*
G01X197314D01*
G03X197440Y1234821I130J1195D01*
G03Y1237225I0J1202D01*
G03X197315Y1237218I5J-1202D01*
G01X197313D01*
G02X197159Y1237268I-20J199D01*
G01X196938Y1237467D01*
G02X196872Y1237616I134J149D01*
G01Y1237893D01*
G03X196850Y1238126I-1303J-5D01*
G01Y1238132D01*
X196846Y1238155D01*
X196874Y1238244D01*
X197128Y1238510D01*
G02X197296Y1238570I144J-139D01*
G01X197297D01*
G03X197440Y1238561I147J1193D01*
G03X198642Y1239763I0J1202D01*
G03X198639Y1239846I-1202J-2D01*
G02X198692Y1239997I200J15D01*
G01X198892Y1240210D01*
G02X199038Y1240274I147J-136D01*
G01X199583D01*
G02X199729Y1240210I-1J-200D01*
G01X199929Y1239997D01*
G02X199982Y1239846I-147J-136D01*
G03X199979Y1239763I1199J-85D01*
G03X202383I1202J0D01*
G01Y1239764D01*
G03X202351Y1240039I-1202J-1D01*
G01X202346Y1240084D01*
G02X202500Y1240279I200J1D01*
G03X202514Y1240283I-48J194D01*
G03X202596Y1240333I-60J191D01*
G01X202658Y1240395D01*
G02X202680Y1240414I141J-141D01*
G02X202739Y1240444I119J-161D01*
G01X202784Y1240458D01*
X202833Y1240449D01*
G03X203543Y1240537I214J1182D01*
G03X203581Y1240555I-496J1095D01*
G02X203837Y1240283I76J-185D01*
G03X203719Y1239764I1084J-519D01*
G01Y1239763D01*
G03X206123I1202J0D01*
G03X206007Y1240278I-1201J0D01*
G02X206177Y1240563I181J85D01*
G02X206272Y1240545I11J-200D01*
G03X206347Y1240513I509J1090D01*
G03X206598Y1240446I434J1122D01*
G01X206599D01*
X206614Y1240444D01*
G03X206789Y1240431I176J1189D01*
G01X206815D01*
G03X207095Y1240470I-25J1202D01*
G03X207310Y1240549I-305J1163D01*
G02X207520Y1240526I87J-180D01*
G02X207577Y1240282I-123J-157D01*
G03X207459Y1239763I1084J-519D01*
G03X209863I1202J0D01*
G01Y1239764D01*
G03X209754Y1240263I-1202J-1D01*
G02X209741Y1240301I182J83D01*
G01X209726Y1240367D01*
G02X209926Y1240567I200J0D01*
G01X210011Y1240548D01*
G03X210035Y1240537I513J1087D01*
G03X211023I494J1095D01*
G03X211061Y1240555I-496J1095D01*
G02X211317Y1240283I76J-185D01*
G03X211199Y1239764I1084J-519D01*
G01Y1239763D01*
G03X213603I1202J0D01*
G03X213487Y1240278I-1201J0D01*
G02X213657Y1240563I181J85D01*
G02X213752Y1240545I11J-200D01*
G03X213827Y1240513I509J1090D01*
G03X214078Y1240446I434J1122D01*
G01X214079D01*
X214094Y1240444D01*
G03X214269Y1240431I176J1189D01*
G01X214295D01*
G03X214575Y1240470I-25J1202D01*
G03X214790Y1240549I-305J1163D01*
G02X215000Y1240526I87J-180D01*
G02X215057Y1240282I-123J-157D01*
G03X214939Y1239763I1084J-519D01*
G03X217343I1202J0D01*
G03X217225Y1240281I-1202J-1D01*
G02X217492Y1240548I180J87D01*
G01X217493D01*
G03X217516Y1240537I530J1079D01*
G03X218504I494J1095D01*
G03X218530Y1240549I-491J1097D01*
G02X218797Y1240282I87J-180D01*
G03X218679Y1239763I1084J-519D01*
G03X221083I1202J0D01*
G03X221062Y1239983I-1202J-4D01*
G01Y1239985D01*
G02X221117Y1240162I197J36D01*
G01X221384Y1240431D01*
X221477Y1240460D01*
X221502Y1240456D01*
G03X221567Y1240445I233J1180D01*
G01X221581Y1240443D01*
G03X221750Y1240431I169J1190D01*
G01X221751D01*
G03X221991Y1240456I-4J1200D01*
G01X221996D01*
X222023Y1240461D01*
X222116Y1240432D01*
X222386Y1240163D01*
G02X222441Y1239986I-142J-141D01*
G01Y1239985D01*
G03X222420Y1239763I1181J-224D01*
G03X223622Y1238561I1202J0D01*
G03X223764Y1238569I3J1202D01*
G01X223811Y1238575D01*
X223899Y1238543D01*
X224186Y1238243D01*
X224214Y1238154D01*
X224210Y1238131D01*
G03X224188Y1237893I1281J-238D01*
G01Y1237616D01*
G02X224122Y1237467I-200J0D01*
G01X223870Y1237240D01*
X223788Y1237214D01*
X223747Y1237219D01*
G03X223622Y1237225I-120J-1196D01*
G03Y1234821I0J-1202D01*
G03X223747Y1234827I5J1202D01*
G01X223788Y1234832D01*
X223870Y1234806D01*
X224122Y1234579D01*
G02X224188Y1234430I-134J-149D01*
G01Y1234153D01*
G03X224210Y1233917I1303J2D01*
G01Y1233913D01*
X224214Y1233892D01*
X224186Y1233803D01*
X223899Y1233503D01*
X223811Y1233471D01*
X223764Y1233477D01*
G03X223622Y1233485I-139J-1194D01*
G03X224824Y1232283I0J-1202D01*
G03X224816Y1232426I-1202J4D01*
G01X224810Y1232473D01*
X224842Y1232561D01*
X225141Y1232848D01*
X225230Y1232876D01*
X225248Y1232873D01*
G03X225491Y1232850I244J1280D01*
G01X225494D01*
G03X225719Y1232870I-2J1303D01*
G01X225721D01*
X225753Y1232875D01*
X225842Y1232848D01*
X226108Y1232593D01*
G02X226169Y1232427I-138J-145D01*
G01Y1232426D01*
G03X226160Y1232283I1193J-147D01*
G03X227362Y1233485I1202J0D01*
G03X227219Y1233476I4J-1202D01*
G01X227218D01*
G02X227050Y1233536I-24J199D01*
G01X226796Y1233802D01*
X226768Y1233891D01*
X226772Y1233917D01*
G03X226794Y1234153I-1281J238D01*
G01Y1234430D01*
G02X226860Y1234579I200J0D01*
G01X227081Y1234778D01*
G02X227235Y1234828I134J-149D01*
G01X227236D01*
G03X227362Y1234821I130J1195D01*
G03X228564Y1236023I0J1202D01*
G03X228543Y1236245I-1202J-2D01*
G01X228534Y1236294D01*
X228563Y1236387D01*
X228866Y1236691D01*
X228961Y1236720D01*
X229010Y1236711D01*
G03X229231Y1236691I218J1182D01*
G01X229243D01*
G03X229443Y1236710I-13J1202D01*
G03X229454Y1236712I-210J1184D01*
G01X229503Y1236721D01*
X229596Y1236692D01*
X229866Y1236423D01*
G02X229921Y1236246I-142J-141D01*
G01Y1236245D01*
G03X229900Y1236023I1181J-224D01*
G03X231102Y1237225I1202J0D01*
G03X230583Y1237107I0J-1202D01*
G02X230316Y1237374I-87J180D01*
G03X230374Y1237518I-1084J520D01*
G03X230384Y1237550I-1143J375D01*
G01X230391Y1237575D01*
G03X230433Y1237835I-1159J321D01*
G01X230435Y1237864D01*
G02X230454Y1237918I196J-39D01*
G01X230500Y1237985D01*
X230504Y1237991D01*
X230535Y1238035D01*
G02X230570Y1238071I160J-120D01*
G01X230588Y1238086D01*
X230619Y1238098D01*
G03X231597Y1238662I-1387J3535D01*
G02X231633Y1238685I125J-156D01*
G03X232182Y1239234I-530J1079D01*
G02X232205Y1239270I179J-89D01*
G03X232740Y1240182I-2976J2359D01*
G03X232942Y1240827I-3509J1453D01*
G01X232943Y1240831D01*
X232950Y1240857D01*
G02X233010Y1240941I187J-70D01*
G01X233036Y1240962D01*
X233067Y1240973D01*
G02X233135Y1240985I68J-188D01*
G01X233467D01*
G02X233641Y1240884I0J-200D01*
G01X233839Y1240534D01*
X233838Y1240427D01*
X233810Y1240380D01*
G03X233640Y1239764I1032J-616D01*
G01Y1239763D01*
G03X234842Y1238561I1202J0D01*
G03X234984Y1238569I3J1202D01*
G01X235031Y1238575D01*
X235119Y1238543D01*
X235405Y1238243D01*
X235433Y1238153D01*
X235425Y1238107D01*
G03X235408Y1237895I1287J-210D01*
G01Y1237616D01*
G02X235342Y1237467I-200J0D01*
G01X235090Y1237240D01*
X235008Y1237214D01*
X234967Y1237219D01*
G03X234842Y1237225I-120J-1196D01*
G03Y1234821I0J-1202D01*
G03X234967Y1234827I5J1202D01*
G01X235008Y1234832D01*
X235090Y1234806D01*
X235342Y1234579D01*
G02X235408Y1234430I-134J-149D01*
G01Y1234152D01*
G03X235430Y1233916I1304J3D01*
G01Y1233912D01*
X235434Y1233892D01*
X235406Y1233803D01*
X235119Y1233503D01*
X235031Y1233471D01*
X234984Y1233477D01*
G03X234842Y1233485I-139J-1194D01*
G03X236044Y1232283I0J-1202D01*
G03X236036Y1232425I-1202J3D01*
G01X236030Y1232472D01*
X236062Y1232560D01*
X236362Y1232847D01*
X236451Y1232875D01*
X236473Y1232871D01*
G03X236712Y1232849I239J1282D01*
G03X236949Y1232871I-2J1304D01*
G01X236953D01*
X236973Y1232875D01*
X237062Y1232847D01*
X237362Y1232560D01*
X237394Y1232472D01*
X237388Y1232425D01*
G03X237380Y1232283I1194J-139D01*
G03X238582Y1233485I1202J0D01*
G03X238440Y1233477I-3J-1202D01*
G01X238393Y1233471D01*
X238305Y1233503D01*
X238018Y1233803D01*
X237990Y1233892D01*
X237994Y1233914D01*
G03X238016Y1234152I-1282J239D01*
G01Y1234430D01*
G02X238082Y1234579I200J0D01*
G01X238334Y1234806D01*
X238416Y1234832D01*
X238457Y1234827D01*
G03X238582Y1234821I120J1196D01*
G03X239784Y1236023I0J1202D01*
G03X239764Y1236243I-1202J2D01*
G01X239755Y1236292D01*
X239784Y1236387D01*
X240088Y1236690D01*
X240181Y1236719D01*
X240207Y1236714D01*
G03X240684Y1236712I243J1177D01*
G01X240686D01*
X240723Y1236719D01*
X240816Y1236690D01*
X241120Y1236387D01*
X241149Y1236292D01*
X241140Y1236243D01*
G03X241120Y1236023I1182J-218D01*
G03X242322Y1234821I1202J0D01*
G03X242447Y1234828I-5J1202D01*
G01X242449D01*
G02X242603Y1234778I20J-199D01*
G01X242824Y1234579D01*
G02X242890Y1234430I-134J-149D01*
G01Y1234153D01*
G03X242912Y1233918I1302J3D01*
G01Y1233914D01*
X242916Y1233892D01*
X242888Y1233803D01*
X242634Y1233537D01*
G02X242465Y1233476I-145J137D01*
G03X242322Y1233485I-147J-1193D01*
G03X243524Y1232283I0J-1202D01*
G03X243515Y1232426I-1202J-4D01*
G02X243576Y1232595I198J24D01*
G01X243842Y1232849D01*
X243931Y1232877D01*
X243955Y1232873D01*
G03X244192Y1232851I238J1280D01*
G03X244427Y1232873I-3J1302D01*
G01X244431D01*
X244453Y1232877D01*
X244542Y1232849D01*
X244808Y1232595D01*
G02X244869Y1232426I-137J-145D01*
G03X244860Y1232283I1193J-147D01*
G03X246062Y1231081I1202J0D01*
G01X246063D01*
G03X246588Y1231202I-1J1202D01*
G02X246782Y1231192I88J-180D01*
G01X247069Y1231012D01*
G02X247163Y1230842I-106J-170D01*
G01Y1229984D01*
G02X247069Y1229814I-200J0D01*
G01X246782Y1229634D01*
G02X246588Y1229624I-106J170D01*
G03X246063Y1229745I-526J-1081D01*
G01X246062D01*
G03Y1227341I0J-1202D01*
G01X246063D01*
G03X246588Y1227462I-1J1202D01*
G02X246782Y1227452I88J-180D01*
G01X247069Y1227272D01*
G02X247163Y1227102I-106J-170D01*
G01Y1226244D01*
G02X247069Y1226074I-200J0D01*
G01X246782Y1225894D01*
G02X246588Y1225884I-106J170D01*
G03X246063Y1226005I-526J-1081D01*
G01X246062D01*
G03Y1223601I0J-1202D01*
G01X246063D01*
G03X246588Y1223722I-1J1202D01*
G02X246782Y1223712I88J-180D01*
G01X247069Y1223532D01*
G02X247163Y1223362I-106J-170D01*
G01Y1222503D01*
G02X247069Y1222333I-200J0D01*
G01X246782Y1222153D01*
G02X246588Y1222143I-106J170D01*
G03X246063Y1222264I-526J-1081D01*
G01X246062D01*
G03Y1219860I0J-1202D01*
G01X246063D01*
G03X246588Y1219981I-1J1202D01*
G02X246782Y1219971I88J-180D01*
G01X247069Y1219791D01*
G02X247163Y1219621I-106J-170D01*
G01Y1216464D01*
G02X247101Y1216320I-200J1D01*
G03Y1214582I832J-869D01*
G01X247131Y1214553D01*
X247163Y1214479D01*
Y1214287D01*
G02X247104Y1214145I-200J0D01*
G01X246301Y1213342D01*
G03X245796Y1212582I1631J-1631D01*
G01X245777Y1212534D01*
X245694Y1212468D01*
X245249Y1212400D01*
X245152Y1212437D01*
X245118Y1212478D01*
G03X244192Y1212914I-926J-765D01*
G03Y1210510I0J-1202D01*
G03X245118Y1210945I0J1203D01*
G01X245152Y1210986D01*
X245249Y1211023D01*
X245641Y1210963D01*
G02X245796Y1210841I-30J-198D01*
G03X247061Y1209575I2136J870D01*
G02X247183Y1209420I-76J-185D01*
G01X247244Y1209029D01*
X247206Y1208930D01*
X247165Y1208897D01*
G03X246731Y1207972I769J-925D01*
G03X249135I1202J0D01*
G03X248700Y1208897I-1201J0D01*
G01X248699Y1208898D01*
G02X248630Y1209081I129J153D01*
G01X248682Y1209421D01*
G02X248804Y1209576I198J-30D01*
G03X249140Y1209746I-870J2136D01*
G01X249199Y1209783D01*
X249336Y1209767D01*
X249851Y1209252D01*
G03X249993Y1209193I142J141D01*
G01X250702D01*
G02X250844Y1209134I0J-200D01*
G01X250849Y1209129D01*
G02Y1208847I-142J-141D01*
G01X250845Y1208843D01*
G03X250471Y1207972I827J-871D01*
G03X251673Y1206770I1202J0D01*
G03X252762Y1207462I0J1203D01*
G02X252979Y1207574I181J-85D01*
G03X253398Y1207536I417J2268D01*
G01X254163D01*
G02X254342Y1207427I1J-200D01*
G01Y1207426D01*
G03X256484I1071J546D01*
G01Y1207427D01*
G02X256663Y1207536I178J-91D01*
G01X257903D01*
G02X258082Y1207427I1J-200D01*
G01Y1207426D01*
G03X260224I1071J546D01*
G01Y1207427D01*
G02X260403Y1207536I178J-91D01*
G01X261643D01*
G02X261822Y1207427I1J-200D01*
G01Y1207426D01*
G03X263964I1071J546D01*
G01Y1207427D01*
G02X264143Y1207536I178J-91D01*
G01X265383D01*
G02X265562Y1207427I1J-200D01*
G01Y1207426D01*
G03X267704I1071J546D01*
G01Y1207427D01*
G02X267883Y1207536I178J-91D01*
G01X269123D01*
G02X269302Y1207427I1J-200D01*
G01Y1207426D01*
G03X271444I1071J546D01*
G01Y1207427D01*
G02X271623Y1207536I178J-91D01*
G01X272864D01*
G02X273043Y1207427I1J-200D01*
G01Y1207426D01*
G03X273590Y1206890I1071J546D01*
G01X273641Y1206866D01*
X273702Y1206768D01*
Y1205436D01*
X273641Y1205338D01*
X273590Y1205314D01*
G03X272912Y1204232I524J-1082D01*
G03X273703Y1203102I1203J0D01*
G03X273702Y1203061I2305J-77D01*
G01Y1203057D01*
G03X274378Y1201428I2307J3D01*
G01X275037Y1200769D01*
G03X276668Y1200094I1630J1631D01*
G01X276720D01*
G03X277421Y1199370I1134J397D01*
G02X277519Y1199289I-72J-187D01*
G01X277580Y1199190D01*
G02X277609Y1199061I-170J-106D01*
G03X277594Y1198797I2291J-263D01*
G01Y1198075D01*
G02X277460Y1197886I-200J0D01*
G01X277459D01*
G03X276653Y1196801I395J-1135D01*
G01X276651Y1196748D01*
X276594Y1196658D01*
X276284Y1196493D01*
G02X276083Y1196500I-94J176D01*
G03X275959Y1196570I-671J-1045D01*
G01X275957D01*
G03X275923Y1196586I-545J-1115D01*
G01X275608Y1196732D01*
G03X275319Y1196825I-522J-1126D01*
G01X275303Y1196927D01*
Y1196929D01*
G03X274115Y1197953I-1189J-178D01*
G01X274113D01*
G03X274037Y1197951I-6J-1202D01*
G01X274026Y1197950D01*
X273926Y1198003D01*
X273688Y1198402D01*
G03X272621Y1199010I-1068J-634D01*
G01X271875D01*
G03X270805Y1198396I1J-1242D01*
G01X270563Y1197984D01*
X270465Y1197931D01*
X270455Y1197932D01*
G03X270395Y1197934I-70J-1200D01*
G03X270391I-2J-200D01*
G03X270331Y1197932I10J-1202D01*
G01X270321Y1197931D01*
X270223Y1197984D01*
X269981Y1198396D01*
G03X268911Y1199010I-1071J-628D01*
G01X268126D01*
G03X267059Y1198402I1J-1242D01*
G01X266821Y1198003D01*
X266721Y1197950D01*
X266710Y1197951D01*
G03X266634Y1197953I-70J-1200D01*
G01X266632D01*
G03X266556Y1197951I-6J-1202D01*
G01X266545Y1197950D01*
X266445Y1198003D01*
X266207Y1198402D01*
G03X265140Y1199010I-1068J-634D01*
G01X264386D01*
G03X263319Y1198402I1J-1242D01*
G01X263081Y1198003D01*
X262981Y1197950D01*
X262970Y1197951D01*
G03X262894Y1197953I-70J-1200D01*
G01X262892D01*
G03X262816Y1197951I-6J-1202D01*
G01X262805Y1197950D01*
X262705Y1198003D01*
X262467Y1198402D01*
G03X261400Y1199010I-1068J-634D01*
G01X260646D01*
G03X259579Y1198402I1J-1242D01*
G01X259341Y1198003D01*
X259241Y1197950D01*
X259230Y1197951D01*
G03X259154Y1197953I-70J-1200D01*
G01X259152D01*
G03X259076Y1197951I-6J-1202D01*
G01X259065Y1197950D01*
X258965Y1198003D01*
X258727Y1198402D01*
G03X257660Y1199010I-1068J-634D01*
G01X256906D01*
G03X255839Y1198402I1J-1242D01*
G01X255601Y1198003D01*
X255501Y1197950D01*
X255490Y1197951D01*
G03X255414Y1197953I-70J-1200D01*
G01X255412D01*
G03X255336Y1197951I-6J-1202D01*
G01X255325Y1197950D01*
X255225Y1198003D01*
X254987Y1198402D01*
G03X253920Y1199010I-1068J-634D01*
G01X253166D01*
G03X252099Y1198402I1J-1242D01*
G01X251861Y1198003D01*
X251761Y1197950D01*
X251750Y1197951D01*
G03X251674Y1197953I-70J-1200D01*
G01X251672D01*
G03X251596Y1197951I-6J-1202D01*
G01X251585Y1197950D01*
X251485Y1198003D01*
X251247Y1198402D01*
G03X250180Y1199010I-1068J-634D01*
G01X249426D01*
G03X248359Y1198402I1J-1242D01*
G01X248121Y1198003D01*
X248021Y1197950D01*
X248010Y1197951D01*
G03X247934Y1197953I-70J-1200D01*
G01X247932D01*
G03X247856Y1197951I-6J-1202D01*
G01X247845Y1197950D01*
X247745Y1198003D01*
X247507Y1198402D01*
G03X246440Y1199010I-1068J-634D01*
G01X245685D01*
G03X244618Y1198402I1J-1242D01*
G01X244380Y1198003D01*
X244280Y1197950D01*
X244269Y1197951D01*
G03X244193Y1197953I-70J-1200D01*
G01X244191D01*
G03X244115Y1197951I-6J-1202D01*
G01X244104Y1197950D01*
X244004Y1198003D01*
X243766Y1198402D01*
G03X242699Y1199010I-1068J-634D01*
G01X241945D01*
G03X240878Y1198402I1J-1242D01*
G01X240640Y1198003D01*
X240540Y1197950D01*
X240529Y1197951D01*
G03X240453Y1197953I-70J-1200D01*
G01X240451D01*
G03X240375Y1197951I-6J-1202D01*
G01X240364Y1197950D01*
X240264Y1198003D01*
X240026Y1198402D01*
G03X238959Y1199010I-1068J-634D01*
G01X238205D01*
G03X237138Y1198402I1J-1242D01*
G01X236900Y1198003D01*
X236800Y1197950D01*
X236789Y1197951D01*
G03X236713Y1197953I-70J-1200D01*
G01X236711D01*
G03X236635Y1197951I-6J-1202D01*
G01X236624Y1197950D01*
X236524Y1198003D01*
X236286Y1198402D01*
G03X235219Y1199010I-1068J-634D01*
G01X230725D01*
G03X229658Y1198402I1J-1242D01*
G01X229420Y1198003D01*
X229320Y1197950D01*
X229309Y1197951D01*
G03X229233Y1197953I-70J-1200D01*
G01X229231D01*
G03X229155Y1197951I-6J-1202D01*
G01X229144Y1197950D01*
X229044Y1198003D01*
X228806Y1198402D01*
G03X227739Y1199010I-1068J-634D01*
G01X226985D01*
G03X225918Y1198402I1J-1242D01*
G01X225680Y1198003D01*
X225580Y1197950D01*
X225569Y1197951D01*
G03X225493Y1197953I-70J-1200D01*
G01X225491D01*
G03X225415Y1197951I-6J-1202D01*
G01X225404Y1197950D01*
X225304Y1198003D01*
X225066Y1198402D01*
G03X223999Y1199010I-1068J-634D01*
G01X223244D01*
G03X222177Y1198402I1J-1242D01*
G01X221939Y1198003D01*
X221839Y1197950D01*
X221828Y1197951D01*
G03X221752Y1197953I-70J-1200D01*
G01X221750D01*
G03X221674Y1197951I-6J-1202D01*
G01X221663Y1197950D01*
X221563Y1198003D01*
X221325Y1198402D01*
G03X220258Y1199010I-1068J-634D01*
G01X219504D01*
G03X218437Y1198402I1J-1242D01*
G01X218199Y1198003D01*
X218099Y1197950D01*
X218088Y1197951D01*
G03X218012Y1197953I-70J-1200D01*
G01X218010D01*
G03X217934Y1197951I-6J-1202D01*
G01X217923Y1197950D01*
X217823Y1198003D01*
X217585Y1198402D01*
G03X216518Y1199010I-1068J-634D01*
G01X215764D01*
G03X214697Y1198402I1J-1242D01*
G01X214459Y1198003D01*
X214359Y1197950D01*
X214348Y1197951D01*
G03X214272Y1197953I-70J-1200D01*
G01X214270D01*
G03X214194Y1197951I-6J-1202D01*
G01X214183Y1197950D01*
X214083Y1198003D01*
X213845Y1198402D01*
G03X212778Y1199010I-1068J-634D01*
G01X212024D01*
G03X210957Y1198402I1J-1242D01*
G01X210719Y1198003D01*
X210619Y1197950D01*
X210608Y1197951D01*
G03X210532Y1197953I-70J-1200D01*
G01X210530D01*
G03X210454Y1197951I-6J-1202D01*
G01X210443Y1197950D01*
X210343Y1198003D01*
X210105Y1198402D01*
G03X209038Y1199010I-1068J-634D01*
G01X208284D01*
G03X207217Y1198402I1J-1242D01*
G01X206979Y1198003D01*
X206879Y1197950D01*
X206868Y1197951D01*
G03X206792Y1197953I-70J-1200D01*
G01X206790D01*
G03X206714Y1197951I-6J-1202D01*
G01X206703Y1197950D01*
X206603Y1198003D01*
X206365Y1198402D01*
G03X205298Y1199010I-1068J-634D01*
G01X204544D01*
G03X203477Y1198402I1J-1242D01*
G01X203239Y1198003D01*
X203139Y1197950D01*
X203128Y1197951D01*
G03X203052Y1197953I-70J-1200D01*
G01X203050D01*
G03X202974Y1197951I-6J-1202D01*
G01X202963Y1197950D01*
X202863Y1198003D01*
X202625Y1198402D01*
G03X201558Y1199010I-1068J-634D01*
G01X200804D01*
G03X199737Y1198402I1J-1242D01*
G01X199499Y1198003D01*
X199399Y1197950D01*
X199388Y1197951D01*
G03X199312Y1197953I-70J-1200D01*
G01X199310D01*
G03X199234Y1197951I-6J-1202D01*
G01X199223Y1197950D01*
X199123Y1198003D01*
X198885Y1198402D01*
G03X197818Y1199010I-1068J-634D01*
G01X197063D01*
G03X195996Y1198402I1J-1242D01*
G01X195758Y1198003D01*
X195658Y1197950D01*
X195647Y1197951D01*
G03X195571Y1197953I-70J-1200D01*
G01X195569D01*
G03X194368Y1196751I1J-1202D01*
G01Y1196748D01*
G03X194385Y1196548I1202J1D01*
G01X194388Y1196533D01*
X194341Y1196424D01*
X194025Y1196214D01*
G03X193472Y1195182I688J-1033D01*
G01Y1194580D01*
G03X194025Y1193548I1241J1D01*
G01X194341Y1193338D01*
X194388Y1193229D01*
X194385Y1193214D01*
G03X194368Y1193011I1185J-201D01*
G03X194369Y1192961I1202J-1D01*
G01X194373Y1192869D01*
G03X194237Y1192809I432J-1164D01*
G01X193900Y1192633D01*
G03X193827Y1192567I94J-177D01*
G01X193505Y1192085D01*
X193504Y1192071D01*
X192910Y1191477D01*
G02X192768Y1191418I-142J141D01*
G01X183733D01*
X183629Y1191493D01*
X183622Y1191515D01*
G03X183564Y1191660I-1143J-373D01*
G02X183831Y1191927I180J87D01*
G03X184350Y1191809I519J1084D01*
G03X183148Y1193011I0J1202D01*
G03X183169Y1192789I1202J2D01*
G01X183178Y1192740D01*
X183149Y1192647D01*
X182844Y1192342D01*
X182751Y1192313D01*
X182702Y1192322D01*
G03X182480Y1192343I-224J-1181D01*
G03X181278Y1191141I0J-1202D01*
G03X181458Y1190508I1203J0D01*
G01X181474Y1190483D01*
X181458Y1190346D01*
X181087Y1189975D01*
G03X181044Y1189910I142J-141D01*
G01X180891Y1189541D01*
G03X180876Y1189470I185J-76D01*
G01X180871Y1189269D01*
Y1189264D01*
G02X180868Y1189227I-261J3D01*
G01X180854Y1189147D01*
G02X180751Y1189005I-197J35D01*
G02X180679Y1188979I-137J267D01*
G02X180676Y1188978I-64J188D01*
G01X180332Y1188903D01*
G03X180219Y1188833I43J-195D01*
G01X179941Y1188485D01*
G02X179815Y1188412I-156J125D01*
G01X179511Y1188364D01*
X179438Y1188380D01*
X179406Y1188402D01*
G03X178741Y1188603I-665J-1001D01*
G01X178740D01*
G03X177538Y1187401I0J-1202D01*
G03X177559Y1187179I1202J2D01*
G01X177568Y1187130D01*
X177539Y1187037D01*
X177234Y1186732D01*
X177141Y1186703D01*
X177092Y1186712D01*
G03X176870Y1186733I-224J-1181D01*
G03X176647Y1186712I1J-1202D01*
G01X176598Y1186703D01*
X176505Y1186732D01*
X176235Y1187001D01*
G02X176180Y1187178I142J141D01*
G01Y1187179D01*
G03X176201Y1187401I-1181J224D01*
G03X173797I-1202J0D01*
G03X173818Y1187179I1202J2D01*
G01X173827Y1187130D01*
X173798Y1187037D01*
X173493Y1186732D01*
X173400Y1186703D01*
X173351Y1186712D01*
G03X173129Y1186733I-224J-1181D01*
G03X172907Y1186712I2J-1202D01*
G01X172858Y1186703D01*
X172765Y1186732D01*
X172460Y1187037D01*
X172431Y1187130D01*
X172440Y1187179D01*
G03X172461Y1187401I-1181J224D01*
G03X171259Y1186199I-1202J0D01*
G03X171481Y1186220I-2J1202D01*
G01X171530Y1186229D01*
X171623Y1186200D01*
X171928Y1185895D01*
X171957Y1185802D01*
X171948Y1185753D01*
G03X171927Y1185531I1181J-224D01*
G03X174331I1202J0D01*
G03X174310Y1185753I-1202J-2D01*
G01X174301Y1185802D01*
X174330Y1185895D01*
X174635Y1186200D01*
X174728Y1186229D01*
X174777Y1186220D01*
G03X174999Y1186199I224J1181D01*
G03X175222Y1186220I-1J1202D01*
G01X175271Y1186229D01*
X175364Y1186200D01*
X175634Y1185931D01*
G02X175689Y1185754I-142J-141D01*
G01Y1185753D01*
G03X175668Y1185531I1181J-224D01*
G03X178072I1202J0D01*
G03X178051Y1185753I-1202J-2D01*
G01X178042Y1185802D01*
X178071Y1185895D01*
X178376Y1186200D01*
X178469Y1186229D01*
X178518Y1186220D01*
G03X178740Y1186199I224J1181D01*
G01X178741D01*
G03X179406Y1186400I0J1202D01*
G01X179438Y1186422D01*
X179511Y1186438D01*
X179815Y1186390D01*
G02X179941Y1186317I-30J-198D01*
G01X180219Y1185969D01*
G03X180332Y1185899I156J125D01*
G01X180675Y1185824D01*
X180677D01*
G02X180747Y1185798I-69J-292D01*
G02X180853Y1185654I-91J-178D01*
G01X180867Y1185574D01*
Y1185570D01*
G02X180671Y1185278I-257J-39D01*
G02X180667Y1185277I-50J193D01*
G01X180310Y1185199D01*
G03X180197Y1185129I43J-195D01*
G01X179738Y1184555D01*
G03X179694Y1184430I156J-125D01*
G01Y1182857D01*
X179716Y1182794D01*
X179734Y1182771D01*
Y1182690D01*
G02X179687Y1182562I-200J1D01*
G03X179408Y1181791I923J-770D01*
G01Y1181790D01*
G03X179714Y1180989I1202J0D01*
G01X179737Y1180964D01*
X179741Y1180819D01*
X179738Y1180815D01*
G03X179694Y1180690I156J-125D01*
G01Y1179117D01*
X179716Y1179054D01*
X179734Y1179031D01*
Y1178950D01*
G02X179687Y1178822I-200J1D01*
G03X179408Y1178051I923J-770D01*
G01Y1178050D01*
G03X179714Y1177249I1202J0D01*
G01X179737Y1177224D01*
X179741Y1177079D01*
X179738Y1177075D01*
G03X179694Y1176950I156J-125D01*
G01Y1175376D01*
X179716Y1175313D01*
X179734Y1175290D01*
Y1175209D01*
G02X179687Y1175081I-200J1D01*
G03X179408Y1174310I923J-770D01*
G01Y1174309D01*
G03X179714Y1173508I1202J0D01*
G01X179737Y1173483D01*
X179741Y1173338D01*
X179738Y1173334D01*
G03X179694Y1173209I156J-125D01*
G01Y1171836D01*
G02X179606Y1171671I-200J1D01*
G01X179592Y1171661D01*
X179574Y1171677D01*
X179364Y1171758D01*
G03X178917Y1171842I-449J-1158D01*
G01X178562D01*
G03X177730Y1171520I2J-1242D01*
G01X177671Y1171467D01*
G03X176870Y1171772I-801J-899D01*
G03X176163Y1171542I0J-1202D01*
G01X176128Y1171517D01*
X176077Y1171519D01*
G02X175955Y1171570I12J200D01*
G01X175861Y1171653D01*
G03X175800Y1171690I-133J-150D01*
G01X175624Y1171758D01*
G03X175177Y1171842I-449J-1158D01*
G01X174821D01*
G03X173989Y1171520I2J-1242D01*
G01X173930Y1171467D01*
G03X173129Y1171772I-801J-899D01*
G03X172422Y1171542I0J-1202D01*
G01X172375Y1171508D01*
X172346Y1171509D01*
G02X172229Y1171555I11J200D01*
G03X170543Y1171464I-794J-955D01*
G02X170541Y1171462I-142J140D01*
G01X169054Y1169975D01*
G03X168690Y1169097I877J-878D01*
G01Y1160749D01*
G03X168717Y1160492I1241J0D01*
G02X168645Y1160294I-196J-41D01*
G03Y1158406I744J-944D01*
G02X168717Y1158208I-124J-157D01*
G03X168690Y1157951I1214J-257D01*
G01Y1157224D01*
G03X168727Y1156924I1241J1D01*
G02X168729Y1156914I-195J-44D01*
G03X168730Y1156909I1216J241D01*
G01Y1156847D01*
G03Y1154373I658J-1237D01*
G01Y1154336D01*
G02X168724Y1154289I-200J2D01*
G03X168693Y1154087I1208J-289D01*
G03X168690Y1153996I1238J-86D01*
G01Y1153269D01*
G03X168717Y1153012I1241J0D01*
G02X168645Y1152814I-196J-41D01*
G03Y1150926I744J-944D01*
G02X168717Y1150728I-124J-157D01*
G03X168690Y1150471I1214J-257D01*
G01Y1149528D01*
G03X168717Y1149271I1241J0D01*
G02X168645Y1149073I-196J-41D01*
G03Y1147185I744J-944D01*
G02X168717Y1146987I-124J-157D01*
G03X168690Y1146730I1214J-257D01*
G01Y1145788D01*
G03X168717Y1145531I1241J0D01*
G02X168645Y1145333I-196J-41D01*
G03Y1143445I744J-944D01*
G02X168717Y1143247I-124J-157D01*
G03X168690Y1142990I1214J-257D01*
G01Y1142368D01*
G03X168698Y1142313I200J1D01*
G01X168740Y1142162D01*
G02X168748Y1142107I-192J-56D01*
G01Y1142025D01*
G03X168788Y1141715I1242J3D01*
G01Y1141690D01*
G03X168187Y1140649I601J-1041D01*
G03X168904Y1139549I1202J0D01*
G02X169024Y1139375I-80J-183D01*
G03X169385Y1138551I1240J52D01*
G01X169405Y1138531D01*
G03X169499Y1138446I879J877D01*
G02X169314Y1138207I-196J-39D01*
G03X168086Y1136907I74J-1300D01*
G03X169389Y1135604I1303J0D01*
G01X173129D01*
G03X174432Y1136907I0J1303D01*
G03X173964Y1137906I-1303J-1D01*
G02X174029Y1138250I128J154D01*
G03X174475Y1138166I449J1158D01*
G01X175524D01*
G03X176638Y1138861I-1J1242D01*
G01X176735Y1139058D01*
G02X176915Y1139170I180J-88D01*
G01X176950D01*
X177102Y1138861D01*
G03X178216Y1138166I1115J547D01*
G01X179264D01*
G03X180378Y1138861I-1J1242D01*
G01X180475Y1139058D01*
G02X180655Y1139170I180J-88D01*
G01X180690D01*
X180842Y1138861D01*
G03X181956Y1138166I1115J547D01*
G01X183004D01*
G03X184118Y1138861I-1J1242D01*
G01X184215Y1139058D01*
G02X184395Y1139170I180J-88D01*
G01X184430D01*
X184582Y1138861D01*
G03X185696Y1138166I1115J547D01*
G01X186744D01*
G03X187858Y1138861I-1J1242D01*
G01X187955Y1139058D01*
G02X188135Y1139170I180J-88D01*
G01X188170D01*
X188322Y1138861D01*
G03X189436Y1138166I1115J547D01*
G01X190484D01*
G03X191598Y1138861I-1J1242D01*
G01X191695Y1139058D01*
G02X191875Y1139170I180J-88D01*
G01X191910D01*
X192062Y1138861D01*
G03X192788Y1138229I1114J547D01*
G02X192867Y1138180I-63J-190D01*
G01X194075Y1136972D01*
G03X194200Y1136914I142J141D01*
G01X194269Y1136908D01*
X194372Y1136810D01*
X194376Y1136775D01*
G03X195435Y1135715I1194J134D01*
G01X195437D01*
X195471Y1135711D01*
X195569Y1135608D01*
X195575Y1135539D01*
G03X195633Y1135414I199J17D01*
G01X196297Y1134750D01*
G03X197175Y1134386I878J877D01*
G01X197998D01*
G03X198565Y1134523I0J1241D01*
G02X198634Y1134162I-43J-195D01*
G03X198109Y1133169I677J-993D01*
G03X200513I1202J0D01*
G03X199988Y1134162I-1202J0D01*
G02X200057Y1134523I112J166D01*
G03X200624Y1134386I567J1104D01*
G01X201738D01*
G03X202305Y1134523I0J1241D01*
G02X202374Y1134162I-43J-195D01*
G03X201849Y1133169I677J-993D01*
G03X204253I1202J0D01*
G03X203728Y1134162I-1202J0D01*
G02X203797Y1134523I112J166D01*
G03X204364Y1134386I567J1104D01*
G01X205478D01*
G03X206045Y1134523I0J1241D01*
G02X206114Y1134162I-43J-195D01*
G03X205589Y1133169I677J-993D01*
G03X207993I1202J0D01*
G03X207468Y1134162I-1202J0D01*
G02X207537Y1134523I112J166D01*
G03X208104Y1134386I567J1104D01*
G01X209218D01*
G03X209785Y1134523I0J1241D01*
G02X209854Y1134162I-43J-195D01*
G03X209329Y1133169I677J-993D01*
G03X211733I1202J0D01*
G03X211208Y1134162I-1202J0D01*
G02X211277Y1134523I112J166D01*
G03X211844Y1134386I567J1104D01*
G01X212958D01*
G03X213525Y1134523I0J1241D01*
G02X213594Y1134162I-43J-195D01*
G03X213069Y1133169I677J-993D01*
G03X215473I1202J0D01*
G03X214948Y1134162I-1202J0D01*
G02X215017Y1134523I112J166D01*
G03X215584Y1134386I567J1104D01*
G01X216698D01*
G03X217265Y1134523I0J1241D01*
G02X217334Y1134162I-43J-195D01*
G03X216809Y1133169I677J-993D01*
G03X219213I1202J0D01*
G03X218688Y1134162I-1202J0D01*
G02X218757Y1134523I112J166D01*
G03X219324Y1134386I567J1104D01*
G01X220438D01*
G03X221005Y1134523I0J1241D01*
G02X221074Y1134162I-43J-195D01*
G03X220549Y1133169I677J-993D01*
G03X222953I1202J0D01*
G03X222428Y1134162I-1202J0D01*
G02X222497Y1134523I112J166D01*
G03X223064Y1134386I567J1104D01*
G01X224179D01*
G03X224746Y1134523I0J1241D01*
G02X224815Y1134162I-43J-195D01*
G03X224290Y1133169I677J-993D01*
G03X226694I1202J0D01*
G03X226169Y1134162I-1202J0D01*
G02X226238Y1134523I112J166D01*
G03X226805Y1134386I567J1104D01*
G01X227919D01*
G03X229041Y1135096I0J1242D01*
G01X229096Y1135213D01*
G02X229277Y1135328I181J-85D01*
G01X229314D01*
X229423Y1135096D01*
G03X230545Y1134386I1122J532D01*
G01X235399D01*
G03X235636Y1134408I4J1242D01*
G02X235707Y1134123I-96J-175D01*
G03X235510Y1133464I1004J-659D01*
G03X237914I1202J0D01*
G03X237717Y1134123I-1201J0D01*
G02X237788Y1134408I167J110D01*
G03X238025Y1134386I233J1220D01*
G01X239139D01*
G03X239706Y1134523I0J1241D01*
G02X239775Y1134162I-43J-195D01*
G03X239250Y1133169I677J-993D01*
G03X241654I1202J0D01*
G03X241129Y1134162I-1202J0D01*
G02X241198Y1134523I112J166D01*
G03X241765Y1134386I567J1104D01*
G01X242879D01*
G03X243446Y1134523I0J1241D01*
G02X243515Y1134162I-43J-195D01*
G03X242990Y1133169I677J-993D01*
G03X245394I1202J0D01*
G03X244869Y1134162I-1202J0D01*
G02X244938Y1134523I112J166D01*
G03X245505Y1134386I567J1104D01*
G01X246620D01*
G03X247187Y1134523I0J1241D01*
G02X247256Y1134162I-43J-195D01*
G03X246731Y1133169I677J-993D01*
G03X249135I1202J0D01*
G03X248610Y1134162I-1202J0D01*
G02X248679Y1134523I112J166D01*
G03X249246Y1134386I567J1104D01*
G01X250360D01*
G03X250927Y1134523I0J1241D01*
G02X250996Y1134162I-43J-195D01*
G03X250471Y1133169I677J-993D01*
G03X252875I1202J0D01*
G03X252350Y1134162I-1202J0D01*
G02X252419Y1134523I112J166D01*
G03X252986Y1134386I567J1104D01*
G01X254100D01*
G03X254667Y1134523I0J1241D01*
G02X254736Y1134162I-43J-195D01*
G03X254211Y1133169I677J-993D01*
G03X256615I1202J0D01*
G03X256090Y1134162I-1202J0D01*
G02X256159Y1134523I112J166D01*
G03X256726Y1134386I567J1104D01*
G01X257840D01*
G03X258407Y1134523I0J1241D01*
G02X258476Y1134162I-43J-195D01*
G03X257951Y1133169I677J-993D01*
G03X260355I1202J0D01*
G03X259830Y1134162I-1202J0D01*
G02X259899Y1134523I112J166D01*
G03X260466Y1134386I567J1104D01*
G01X261580D01*
G03X262147Y1134523I0J1241D01*
G02X262216Y1134162I-43J-195D01*
G03X261691Y1133169I677J-993D01*
G03X264095I1202J0D01*
G03X263570Y1134162I-1202J0D01*
G02X263639Y1134523I112J166D01*
G03X264206Y1134386I567J1104D01*
G01X265320D01*
G03X265887Y1134523I0J1241D01*
G02X265956Y1134162I-43J-195D01*
G03X265431Y1133169I677J-993D01*
G03X267835I1202J0D01*
G03X267310Y1134162I-1202J0D01*
G02X267379Y1134523I112J166D01*
G03X267946Y1134386I567J1104D01*
G01X269092D01*
G03X269624Y1134521I-32J1241D01*
G02X269781Y1134326I-43J-195D01*
G01X269717Y1134204D01*
G02X269659Y1134136I-177J93D01*
G03X269171Y1133169I714J-967D01*
G03X271575I1202J0D01*
G03X271087Y1134136I-1202J0D01*
G02X271029Y1134204I119J161D01*
G01X270965Y1134326D01*
G02X271122Y1134521I200J0D01*
G03X271654Y1134386I564J1106D01*
G01X275562D01*
G03X276440Y1134750I0J1241D01*
G01X277291Y1135601D01*
G03X277361Y1135678I-883J873D01*
G02X277563Y1135743I153J-129D01*
G03X277853Y1135707I292J1166D01*
G01X277854D01*
G03X279056Y1136909I0J1202D01*
G03X278813Y1137634I-1203J0D01*
G01X278728Y1137746D01*
G03X278768Y1137816I-1058J651D01*
G02X278796Y1137856I177J-94D01*
G01X278824Y1137887D01*
G03X278874Y1138020I-150J132D01*
G01Y1138064D01*
G02X278880Y1138111I200J-2D01*
G03X278914Y1138401I-1208J289D01*
G01Y1139157D01*
G03X278880Y1139447I-1242J1D01*
G02X278874Y1139494I194J49D01*
G01Y1139538D01*
G03X278824Y1139671I-200J1D01*
G01X278796Y1139702D01*
G02X278768Y1139742I149J134D01*
G03X278728Y1139812I-1098J-581D01*
G01X278813Y1139924D01*
G03Y1141374I-960J725D01*
G01X278728Y1141486D01*
G03X278768Y1141556I-1058J651D01*
G02X278796Y1141596I177J-94D01*
G01X278824Y1141627D01*
G03X278874Y1141760I-150J132D01*
G01Y1141804D01*
G02X278880Y1141851I200J-2D01*
G03X278914Y1142141I-1208J289D01*
G01Y1142897D01*
G03X278880Y1143187I-1242J1D01*
G02X278874Y1143234I194J49D01*
G01Y1143278D01*
G03X278824Y1143411I-200J1D01*
G01X278796Y1143442D01*
G02X278768Y1143482I149J134D01*
G03X278728Y1143552I-1098J-581D01*
G01X278813Y1143664D01*
G03Y1145114I-960J725D01*
G01X278728Y1145226D01*
G03X278768Y1145296I-1058J651D01*
G02X278796Y1145336I177J-94D01*
G01X278824Y1145367D01*
G03X278874Y1145500I-150J132D01*
G01Y1145544D01*
G02X278880Y1145591I200J-2D01*
G03X278914Y1145881I-1208J289D01*
G01Y1146637D01*
G03X278880Y1146927I-1242J1D01*
G02X278874Y1146974I194J49D01*
G01Y1147018D01*
G03X278824Y1147151I-200J1D01*
G01X278796Y1147182D01*
G02X278768Y1147222I149J134D01*
G03X278728Y1147292I-1098J-581D01*
G01X278813Y1147404D01*
G03Y1148854I-960J725D01*
G01X278728Y1148966D01*
G03X278768Y1149036I-1058J651D01*
G02X278796Y1149076I177J-94D01*
G01X278824Y1149107D01*
G03X278874Y1149240I-150J132D01*
G01Y1149284D01*
G02X278880Y1149331I200J-2D01*
G03X278914Y1149621I-1208J289D01*
G01Y1150378D01*
G03X278880Y1150668I-1242J1D01*
G02X278874Y1150715I194J49D01*
G01Y1150759D01*
G03X278824Y1150892I-200J1D01*
G01X278796Y1150923D01*
G02X278768Y1150963I149J134D01*
G03X278728Y1151033I-1098J-581D01*
G01X278813Y1151145D01*
G03Y1152595I-960J725D01*
G01X278728Y1152707D01*
G03X278768Y1152777I-1058J651D01*
G02X278796Y1152817I177J-94D01*
G01X278824Y1152848D01*
G03X278874Y1152981I-150J132D01*
G01Y1153025D01*
G02X278880Y1153072I200J-2D01*
G03X278914Y1153362I-1208J289D01*
G01Y1154118D01*
G03X278880Y1154408I-1242J1D01*
G02X278874Y1154455I194J49D01*
G01Y1154499D01*
G03X278824Y1154632I-200J1D01*
G01X278796Y1154663D01*
G02X278768Y1154703I149J134D01*
G03X278728Y1154773I-1098J-581D01*
G01X278813Y1154885D01*
G03Y1156335I-960J725D01*
G01X278728Y1156447D01*
G03X278768Y1156517I-1058J651D01*
G02X278796Y1156557I177J-94D01*
G01X278824Y1156588D01*
G03X278874Y1156721I-150J132D01*
G01Y1156765D01*
G02X278880Y1156812I200J-2D01*
G03X278914Y1157102I-1208J289D01*
G01Y1157858D01*
G03X278880Y1158148I-1242J1D01*
G02X278874Y1158195I194J49D01*
G01Y1158239D01*
G03X278824Y1158372I-200J1D01*
G01X278796Y1158403D01*
G02X278768Y1158443I149J134D01*
G03X278728Y1158513I-1098J-581D01*
G01X278813Y1158625D01*
G03Y1160075I-960J725D01*
G01X278728Y1160187D01*
G03X278768Y1160257I-1058J651D01*
G02X278796Y1160297I177J-94D01*
G01X278824Y1160328D01*
G03X278874Y1160461I-150J132D01*
G01Y1160505D01*
G02X278880Y1160552I200J-2D01*
G03X278914Y1160842I-1208J289D01*
G01Y1165338D01*
G03X278880Y1165628I-1242J1D01*
G02X278874Y1165675I194J49D01*
G01Y1165719D01*
G03X278824Y1165852I-200J1D01*
G01X278796Y1165883D01*
G02X278768Y1165923I149J134D01*
G03X278728Y1165993I-1098J-581D01*
G01X278813Y1166105D01*
G03Y1167555I-960J725D01*
G01X278728Y1167667D01*
G03X278768Y1167737I-1058J651D01*
G02X278796Y1167777I177J-94D01*
G01X278824Y1167808D01*
G03X278874Y1167941I-150J132D01*
G01Y1167985D01*
G02X278880Y1168032I200J-2D01*
G03X278914Y1168322I-1208J289D01*
G01Y1169078D01*
G03X278880Y1169368I-1242J1D01*
G02X278874Y1169415I194J49D01*
G01Y1169459D01*
G03X278824Y1169592I-200J1D01*
G01X278796Y1169623D01*
G02X278768Y1169663I149J134D01*
G03X278728Y1169733I-1098J-581D01*
G01X278813Y1169845D01*
G03X279056Y1170570I-960J725D01*
G03X277854Y1171772I-1202J0D01*
G03X277020Y1171435I1J-1202D01*
G01X276898Y1171318D01*
G03X276887Y1171323I-519J-1128D01*
G01X276866Y1171339D01*
G03X276745Y1171380I-121J-159D01*
G01X276719D01*
G03X276404Y1171420I-313J-1201D01*
G01X275564D01*
G03X275271Y1171386I-4J-1242D01*
G02X275224Y1171380I-49J194D01*
G01X275086D01*
G02X274948Y1171436I1J200D01*
G03X274114Y1171772I-834J-867D01*
G03X273280Y1171435I1J-1202D01*
G01X273158Y1171318D01*
G03X273147Y1171323I-519J-1128D01*
G01X273126Y1171339D01*
G03X273005Y1171380I-121J-159D01*
G01X272979D01*
G03X272664Y1171420I-313J-1201D01*
G01X271823D01*
G03X271530Y1171386I-4J-1242D01*
G02X271483Y1171380I-49J194D01*
G01X271345D01*
G02X271207Y1171436I1J200D01*
G03X270373Y1171772I-834J-867D01*
G03X270140Y1171749I1J-1202D01*
G01X270139D01*
G02X269974Y1171791I-38J196D01*
G01X269775Y1171954D01*
G02X269702Y1172109I127J155D01*
G01Y1172771D01*
G02X269775Y1172926I200J0D01*
G01X269974Y1173089D01*
G02X270139Y1173131I127J-154D01*
G01X270140D01*
G03X270373Y1173108I234J1179D01*
G03Y1175512I0J1202D01*
G03X270140Y1175489I1J-1202D01*
G01X270139D01*
G02X269974Y1175531I-38J196D01*
G01X269775Y1175694D01*
G02X269702Y1175849I127J155D01*
G01Y1176512D01*
G02X269775Y1176667I200J0D01*
G01X269974Y1176830D01*
G02X270139Y1176872I127J-154D01*
G01X270140D01*
G03X270373Y1176849I234J1179D01*
G03Y1179253I0J1202D01*
G03X270140Y1179230I1J-1202D01*
G01X270139D01*
G02X269974Y1179272I-38J196D01*
G01X269775Y1179435D01*
G02X269702Y1179590I127J155D01*
G01Y1182236D01*
G02X269902Y1182436I200J0D01*
G01X272571D01*
G02X272724Y1182364I-1J-200D01*
G01X272917Y1182135D01*
X272939Y1182049D01*
X272931Y1182005D01*
G03X272912Y1181793I1183J-213D01*
G01Y1181791D01*
G03X275316I1202J0D01*
G03X275059Y1182533I-1202J-1D01*
G02X275016Y1182663I157J124D01*
G01X275018Y1182724D01*
G02X275077Y1182859I200J-7D01*
G01X276292Y1184074D01*
G03X276549Y1184449I-878J877D01*
G02X276686Y1184563I183J-81D01*
G01X276987Y1184634D01*
X277075Y1184614D01*
X277111Y1184586D01*
G03X277854Y1184329I743J946D01*
G03X278935Y1185005I0J1202D01*
G01X278952Y1185040D01*
X279009Y1185092D01*
X279308Y1185201D01*
G02X279458Y1185195I68J-188D01*
G03X280399Y1184994I942J2105D01*
G01X280402D01*
G02X280572Y1184900I0J-200D01*
G01Y1184899D01*
G03X281346Y1184355I1022J632D01*
G02X281504Y1184178I-41J-196D01*
G03X282169Y1182769I2296J222D01*
G01X282869Y1182069D01*
G03X284084Y1181431I1631J1631D01*
G02X284231Y1181314I-36J-197D01*
G03X284700Y1180770I1103J477D01*
G02X284794Y1180600I-106J-170D01*
G01Y1180297D01*
G03X284941Y1179489I2306J2D01*
G02X284938Y1179343I-188J-69D01*
G01X284892Y1179229D01*
G02X284796Y1179127I-184J77D01*
G03X284132Y1178051I540J-1076D01*
G03X285334Y1176849I1202J0D01*
G03X286405Y1177506I0J1201D01*
G02X286509Y1177601I178J-91D01*
G01X286623Y1177646D01*
G02X286769Y1177647I74J-186D01*
G03X287600Y1177492I831J2152D01*
G01X287895D01*
G02X288063Y1177400I0J-200D01*
G03X288662Y1176922I1010J652D01*
G02X288794Y1176734I-68J-188D01*
G01Y1175627D01*
G02X288662Y1175439I-200J0D01*
G03X287872Y1174310I412J-1129D01*
G03X288804Y1173138I1203J0D01*
G02X288946Y1173015I-45J-195D01*
G03X289469Y1172209I2154J825D01*
G01X289626Y1172052D01*
G02Y1171769I-141J-142D01*
G01Y1171768D01*
G02X289426Y1171719I-141J142D01*
G03X289074Y1171772I-353J-1149D01*
G03X290276Y1170570I0J-1202D01*
G03X290223Y1170922I-1202J-1D01*
G02X290272Y1171122I191J59D01*
G01X290273D01*
G02X290556I142J-141D01*
G01X290869Y1170809D01*
G03X291558Y1170334I1632J1630D01*
G02X291668Y1170211I-81J-183D01*
G03X292815Y1169368I1147J359D01*
G03X293886Y1170024I0J1202D01*
G01Y1170025D01*
G02X294065Y1170134I178J-91D01*
G01X295305D01*
G02X295484Y1170025I1J-200D01*
G01Y1170024D01*
G03X297626I1071J546D01*
G01Y1170025D01*
G02X297805Y1170134I178J-91D01*
G01X299045D01*
G02X299224Y1170025I1J-200D01*
G01Y1170024D01*
G03X301366I1071J546D01*
G01Y1170025D01*
G02X301545Y1170134I178J-91D01*
G01X302785D01*
G02X302964Y1170025I1J-200D01*
G01Y1170024D01*
G03X305106I1071J546D01*
G01Y1170025D01*
G02X305285Y1170134I178J-91D01*
G01X306525D01*
G02X306704Y1170025I1J-200D01*
G01Y1170024D01*
G03X308846I1071J546D01*
G01Y1170025D01*
G02X309025Y1170134I178J-91D01*
G01X310265D01*
G02X310444Y1170025I1J-200D01*
G01Y1170024D01*
G03X312586I1071J546D01*
G01Y1170025D01*
G02X312765Y1170134I178J-91D01*
G01X314005D01*
G02X314184Y1170025I1J-200D01*
G01Y1170024D01*
G03X316326I1071J546D01*
G01Y1170025D01*
G02X316505Y1170134I178J-91D01*
G01X317746D01*
G02X317925Y1170025I1J-200D01*
G01Y1170024D01*
G03X320067I1071J546D01*
G01Y1170025D01*
G02X320246Y1170134I178J-91D01*
G01X321486D01*
G02X321665Y1170025I1J-200D01*
G01Y1170024D01*
G03X323807I1071J546D01*
G01Y1170025D01*
G02X323986Y1170134I178J-91D01*
G01X325226D01*
G02X325405Y1170025I1J-200D01*
G01Y1170024D01*
G03X326476Y1169368I1071J546D01*
G01X326477D01*
G03X326739Y1169397I0J1202D01*
G01X326789Y1169408D01*
X326887Y1169380D01*
X327449Y1168818D01*
G02X327508Y1168676I-141J-142D01*
G01Y1168302D01*
G02X327418Y1168135I-200J0D01*
G01X327138Y1167951D01*
G02X326950Y1167934I-110J167D01*
G03X326476Y1168032I-475J-1104D01*
G03Y1165628I0J-1202D01*
G03X326950Y1165726I-1J1202D01*
G01X326997Y1165746D01*
X327096Y1165737D01*
X327418Y1165525D01*
G02X327508Y1165358I-110J-167D01*
G01Y1160822D01*
G02X327418Y1160655I-200J0D01*
G01X327138Y1160471D01*
G02X326950Y1160454I-110J167D01*
G03X326476Y1160552I-475J-1104D01*
G03Y1158148I0J-1202D01*
G03X326950Y1158246I-1J1202D01*
G01X326997Y1158266D01*
X327096Y1158257D01*
X327418Y1158045D01*
G02X327508Y1157878I-110J-167D01*
G01Y1157082D01*
G02X327418Y1156915I-200J0D01*
G01X327138Y1156731D01*
G02X326950Y1156714I-110J167D01*
G03X326476Y1156812I-475J-1104D01*
G03Y1154408I0J-1202D01*
G03X326950Y1154506I-1J1202D01*
G01X326997Y1154526D01*
X327096Y1154517D01*
X327418Y1154305D01*
G02X327508Y1154138I-110J-167D01*
G01Y1153342D01*
G02X327418Y1153175I-200J0D01*
G01X327138Y1152991D01*
G02X326950Y1152974I-110J167D01*
G03X326476Y1153072I-475J-1104D01*
G03Y1150668I0J-1202D01*
G03X326950Y1150766I-1J1202D01*
G01X326997Y1150786D01*
X327096Y1150777D01*
X327418Y1150565D01*
G02X327508Y1150398I-110J-167D01*
G01Y1149601D01*
G02X327418Y1149434I-200J0D01*
G01X327138Y1149250D01*
G02X326950Y1149233I-110J167D01*
G03X326476Y1149331I-475J-1104D01*
G03Y1146927I0J-1202D01*
G03X326950Y1147025I-1J1202D01*
G01X326997Y1147045D01*
X327096Y1147036D01*
X327418Y1146824D01*
G02X327508Y1146657I-110J-167D01*
G01Y1145861D01*
G02X327418Y1145694I-200J0D01*
G01X327138Y1145510D01*
G02X326950Y1145493I-110J167D01*
G03X326476Y1145591I-475J-1104D01*
G03Y1143187I0J-1202D01*
G03X326950Y1143285I-1J1202D01*
G01X326997Y1143305D01*
X327096Y1143296D01*
X327418Y1143084D01*
G02X327508Y1142917I-110J-167D01*
G01Y1142121D01*
G02X327418Y1141954I-200J0D01*
G01X327138Y1141770D01*
G02X326950Y1141753I-110J167D01*
G03X326476Y1141851I-475J-1104D01*
G03Y1139447I0J-1202D01*
G03X326950Y1139545I-1J1202D01*
G01X326997Y1139565D01*
X327096Y1139556D01*
X327418Y1139344D01*
G02X327508Y1139177I-110J-167D01*
G01Y1139019D01*
X327455Y1138928D01*
X327419Y1138907D01*
G02X327414Y1138904I-105J170D01*
G03X327366Y1138868I95J-176D01*
G01X326663Y1138165D01*
G02X326627Y1138137I-140J143D01*
G02X326613Y1138130I-97J176D01*
G01X326563Y1138110D01*
X326525D01*
G03X326476Y1138111I-49J-1200D01*
G01X326474D01*
G03X325415Y1137476I1J-1202D01*
G01X325389Y1137427D01*
X325295Y1137370D01*
X323916D01*
X323822Y1137427D01*
X323796Y1137476D01*
G03X322736Y1138111I-1060J-567D01*
G01X322735D01*
G03X321675Y1137476I0J-1202D01*
G01X321649Y1137427D01*
X321555Y1137370D01*
X320256D01*
G02X320100Y1137444I-1J200D01*
G03X320023Y1137537I-2985J-2393D01*
G02X320007Y1137559I154J128D01*
G03X319647Y1137920I-1012J-649D01*
G02X319625Y1137936I106J170D01*
G03X317125Y1138866I-2501J-2897D01*
G01X316080D01*
G03X315296Y1138785I-1J-3826D01*
G02X315214I-41J196D01*
G03X314430Y1138866I-783J-3745D01*
G01X313385D01*
G03X310885Y1137936I1J-3827D01*
G02X310863Y1137920I-128J154D01*
G03X310534Y1137605I652J-1010D01*
G03X310503Y1137560I974J-704D01*
G02X310487Y1137537I-172J102D01*
G03X309923Y1136667I2899J-2497D01*
G02X309829Y1136573I-180J86D01*
G03X309680Y1136496I1669J-3411D01*
G01X309677Y1136494D01*
X309663Y1136487D01*
X309613Y1136465D01*
X309595Y1136461D01*
X309561Y1136462D01*
G02X309494Y1136478I12J200D01*
G01X309389Y1136541D01*
X309387D01*
X309153Y1136686D01*
G02X309106Y1136739I124J157D01*
G01X309099Y1136752D01*
X309093Y1136764D01*
G02X309075Y1136854I182J83D01*
G01X309076Y1136866D01*
X309077Y1136902D01*
Y1136909D01*
G03X307775Y1138212I-1303J0D01*
G01X304034D01*
G03X302731Y1136909I0J-1303D01*
G03X302753Y1136673I1303J2D01*
G01Y1136669D01*
X302757Y1136648D01*
X302729Y1136559D01*
X302442Y1136259D01*
X302354Y1136227D01*
X302307Y1136233D01*
G03X302165Y1136241I-139J-1194D01*
G03X303367Y1135039I0J-1202D01*
G03X303359Y1135182I-1202J4D01*
G01X303353Y1135229D01*
X303385Y1135317D01*
X303684Y1135604D01*
X303773Y1135632D01*
X303791Y1135629D01*
G03X304034Y1135606I244J1280D01*
G01X304312D01*
G02X304461Y1135540I0J-200D01*
G01X304660Y1135319D01*
G02X304710Y1135165I-149J-134D01*
G01Y1135164D01*
G03X304703Y1135039I1195J-130D01*
G03X305905Y1133837I1202J0D01*
G03X306126Y1133857I3J1202D01*
G01X306174Y1133866D01*
X306269Y1133837D01*
X306572Y1133534D01*
X306601Y1133439D01*
X306592Y1133391D01*
G03X306584Y1133340I1183J-212D01*
G01X306577Y1133289D01*
G03X306571Y1133169I1197J-120D01*
G03X306597Y1132920I1203J0D01*
G01Y1132916D01*
X306601Y1132899D01*
X306571Y1132804D01*
X306269Y1132501D01*
X306174Y1132472D01*
X306125Y1132481D01*
G03X305905Y1132501I-218J-1182D01*
G03X304703Y1131299I0J-1202D01*
G03X304710Y1131173I1202J4D01*
G01Y1131171D01*
X304714Y1131130D01*
X304688Y1131050D01*
X304461Y1130796D01*
G02X304312Y1130730I-149J134D01*
G01X304034D01*
G03X303795Y1130708I-1J-1302D01*
G02X303789Y1130707I-36J196D01*
G01X303773Y1130704D01*
X303684Y1130732D01*
X303384Y1131020D01*
X303352Y1131108D01*
X303358Y1131155D01*
G03X303367Y1131299I-1193J147D01*
G03X302165Y1130097I-1202J0D01*
G03X302307Y1130106I-5J1202D01*
G01X302309D01*
X302355Y1130111D01*
X302443Y1130079D01*
X302730Y1129779D01*
X302757Y1129690D01*
X302753Y1129663D01*
G03X302732Y1129428I1281J-233D01*
G03X302754Y1129189I1302J-1D01*
G02X302755Y1129183I-196J-36D01*
G01X302758Y1129167D01*
X302730Y1129078D01*
X302443Y1128779D01*
X302355Y1128747D01*
X302308Y1128753D01*
G03X302165Y1128761I-139J-1194D01*
G03X303367Y1127559I0J-1202D01*
G03X303359Y1127702I-1202J4D01*
G01X303353Y1127749D01*
X303385Y1127837D01*
X303684Y1128124D01*
X303773Y1128152D01*
X303792Y1128149D01*
G03X304034Y1128126I244J1279D01*
G01X304312D01*
G02X304461Y1128060I0J-200D01*
G01X304660Y1127839D01*
G02X304710Y1127685I-149J-134D01*
G01Y1127684D01*
G03X304703Y1127559I1195J-130D01*
G03X305905Y1126357I1202J0D01*
G03X306125Y1126378I-4J1202D01*
G01X306127D01*
G02X306304Y1126323I36J-197D01*
G01X306573Y1126053D01*
X306602Y1125960D01*
X306597Y1125932D01*
G03Y1125445I1177J-244D01*
G01Y1125441D01*
X306602Y1125417D01*
X306573Y1125324D01*
X306270Y1125020D01*
X306175Y1124991D01*
X306126Y1125000D01*
G03X305905Y1125020I-218J-1182D01*
G03X304703Y1123818I0J-1202D01*
G03X304710Y1123693I1202J5D01*
G01Y1123691D01*
G02X304660Y1123537I-199J-20D01*
G01X304461Y1123316D01*
G02X304312Y1123250I-149J134D01*
G01X304034D01*
G03X303795Y1123228I-1J-1302D01*
G02X303789Y1123227I-36J196D01*
G01X303773Y1123224D01*
X303684Y1123252D01*
X303418Y1123507D01*
G02X303358Y1123673I139J144D01*
G01Y1123675D01*
G03X303367Y1123818I-1193J147D01*
G03X302165Y1122616I-1202J0D01*
G03X302308Y1122624I4J1202D01*
G01X302355Y1122630D01*
X302443Y1122598D01*
X302730Y1122298D01*
X302758Y1122209D01*
X302754Y1122185D01*
G03X302732Y1121948I1280J-238D01*
G03X302754Y1121713I1302J3D01*
G01Y1121709D01*
X302758Y1121687D01*
X302730Y1121598D01*
X302443Y1121298D01*
X302355Y1121266D01*
X302308Y1121272D01*
G03X302165Y1121280I-139J-1194D01*
G03X303367Y1120078I0J-1202D01*
G03X303358Y1120220I-1202J-5D01*
G01Y1120223D01*
G02X303418Y1120389I199J22D01*
G01X303684Y1120644D01*
X303773Y1120672D01*
X303792Y1120669D01*
G03X304034Y1120646I244J1279D01*
G01X304312D01*
G02X304461Y1120580I0J-200D01*
G01X304660Y1120359D01*
G02X304710Y1120205I-149J-134D01*
G01Y1120204D01*
G03X304703Y1120078I1195J-130D01*
G03X305905Y1118876I1202J0D01*
G03X306126Y1118896I3J1202D01*
G01X306175Y1118905D01*
X306270Y1118876D01*
X306573Y1118572D01*
X306602Y1118479D01*
X306597Y1118453D01*
G03Y1117965I1177J-244D01*
G01Y1117961D01*
X306602Y1117937D01*
X306573Y1117844D01*
X306270Y1117540D01*
X306175Y1117511D01*
X306126Y1117520D01*
G03X305905Y1117540I-218J-1182D01*
G03X304703Y1116338I0J-1202D01*
G03X304710Y1116213I1202J5D01*
G01Y1116211D01*
G02X304660Y1116057I-199J-20D01*
G01X304461Y1115836D01*
G02X304312Y1115770I-149J134D01*
G01X304034D01*
G03X303795Y1115748I-1J-1302D01*
G02X303789Y1115747I-36J196D01*
G01X303773Y1115744D01*
X303684Y1115772D01*
X303418Y1116027D01*
G02X303358Y1116193I139J144D01*
G01Y1116195D01*
G03X303367Y1116338I-1193J147D01*
G03X302165Y1115136I-1202J0D01*
G03X302308Y1115144I4J1202D01*
G01X302355Y1115150D01*
X302443Y1115118D01*
X302730Y1114818D01*
X302758Y1114729D01*
X302754Y1114705D01*
G03X302732Y1114468I1280J-238D01*
G03X302754Y1114233I1302J3D01*
G01Y1114229D01*
X302758Y1114207D01*
X302730Y1114118D01*
X302443Y1113818D01*
X302355Y1113786D01*
X302308Y1113792D01*
G03X302165Y1113800I-139J-1194D01*
G03X303367Y1112598I0J-1202D01*
G03X303358Y1112740I-1202J-5D01*
G01Y1112743D01*
G02X303418Y1112909I199J22D01*
G01X303684Y1113164D01*
X303773Y1113192D01*
X303792Y1113189D01*
G03X304034Y1113166I244J1279D01*
G01X304312D01*
G02X304461Y1113100I0J-200D01*
G01X304660Y1112879D01*
G02X304710Y1112725I-149J-134D01*
G01Y1112724D01*
G03X304703Y1112598I1195J-130D01*
G03X305905Y1111396I1202J0D01*
G03X306126Y1111416I3J1202D01*
G01X306175Y1111425D01*
X306270Y1111396D01*
X306573Y1111092D01*
X306602Y1110999D01*
X306597Y1110973D01*
G03X306595Y1110493I1177J-245D01*
G01Y1110491D01*
X306602Y1110456D01*
X306573Y1110363D01*
X306304Y1110093D01*
G02X306127Y1110038I-141J142D01*
G01X306126D01*
G03X305904Y1110059I-224J-1181D01*
G03Y1107655I0J-1202D01*
G03X306117Y1107674I0J1202D01*
G01X306166Y1107683D01*
X306259Y1107654D01*
X306561Y1107350D01*
X306590Y1107257D01*
X306581Y1107208D01*
G03X306565Y1106890I1183J-219D01*
G03X306584Y1106756I1199J102D01*
G01Y1106754D01*
X306591Y1106718D01*
X306562Y1106625D01*
X306260Y1106321D01*
X306166Y1106291D01*
X306118Y1106300D01*
G03X305905Y1106319I-213J-1183D01*
G03Y1103915I0J-1202D01*
G03X306118Y1103934I0J1202D01*
G01X306167Y1103943D01*
X306260Y1103914D01*
X306562Y1103610D01*
X306591Y1103517D01*
X306585Y1103487D01*
G03X306562Y1103251I1180J-234D01*
G01Y1103250D01*
G03X306585Y1103017I1203J1D01*
G01Y1103015D01*
X306592Y1102977D01*
X306563Y1102884D01*
X306261Y1102580D01*
X306167Y1102550D01*
X306119Y1102559D01*
G03X305907Y1102578I-213J-1183D01*
G01X305905D01*
G03Y1100174I0J-1202D01*
G03X306126Y1100194I3J1202D01*
G01X306174Y1100203D01*
X306269Y1100174D01*
X306572Y1099871D01*
X306601Y1099776D01*
X306592Y1099728D01*
G03X306573Y1099461I1182J-218D01*
G03X306597Y1099264I1201J46D01*
G01Y1099260D01*
X306602Y1099236D01*
X306573Y1099143D01*
X306270Y1098839D01*
X306175Y1098810D01*
X306126Y1098819D01*
G03X305905Y1098839I-218J-1182D01*
G03X304703Y1097637I0J-1202D01*
G03X304712Y1097495I1202J5D01*
G01Y1097493D01*
X304717Y1097447D01*
X304685Y1097359D01*
X304385Y1097072D01*
X304296Y1097044D01*
X304261Y1097050D01*
G03X304034Y1097070I-227J-1283D01*
G01X304033D01*
G03X303793Y1097048I-2J-1303D01*
G02X303787Y1097047I-36J196D01*
G01X303772Y1097044D01*
X303683Y1097072D01*
X303384Y1097359D01*
X303352Y1097447D01*
X303358Y1097494D01*
G03X303366Y1097637I-1194J139D01*
G03X302164Y1096435I-1202J0D01*
G03X302306Y1096443I3J1202D01*
G01X302353Y1096449D01*
X302441Y1096417D01*
X302728Y1096117D01*
X302756Y1096028D01*
X302752Y1096005D01*
G03X302730Y1095767I1281J-238D01*
G01Y1095490D01*
G02X302664Y1095341I-200J0D01*
G01X302412Y1095114D01*
X302330Y1095088D01*
X302289Y1095093D01*
G03X302164Y1095099I-120J-1196D01*
G03X300962Y1093897I0J-1202D01*
G03X300983Y1093675I1202J2D01*
G01X300992Y1093626D01*
X300963Y1093533D01*
X300658Y1093228D01*
X300565Y1093199D01*
X300539Y1093204D01*
G03X300341Y1093228I-243J-1177D01*
G03X300073Y1093209I-50J-1201D01*
G01X300024Y1093200D01*
X299929Y1093229D01*
X299626Y1093533D01*
X299597Y1093626D01*
X299606Y1093675D01*
G03X299627Y1093897I-1181J224D01*
G03X298425Y1095099I-1202J0D01*
G03X298300Y1095092I5J-1202D01*
G01X298298D01*
G02X298144Y1095142I-20J199D01*
G01X297923Y1095341D01*
G02X297857Y1095490I134J149D01*
G01Y1095667D01*
G03X297856Y1095693I-1302J-37D01*
G01Y1095767D01*
G03X297834Y1096000I-1303J-5D01*
G01Y1096006D01*
X297830Y1096029D01*
X297858Y1096118D01*
X298112Y1096384D01*
G02X298280Y1096444I144J-139D01*
G01X298281D01*
G03X298425Y1096435I147J1193D01*
G03X297223Y1097637I0J1202D01*
G03X297232Y1097495I1202J5D01*
G01Y1097493D01*
X297237Y1097447D01*
X297205Y1097359D01*
X296905Y1097072D01*
X296816Y1097044D01*
X296781Y1097050D01*
G03X296554Y1097070I-227J-1283D01*
G01X296553D01*
G03X296313Y1097048I-2J-1303D01*
G02X296307Y1097047I-36J196D01*
G01X296292Y1097044D01*
X296203Y1097072D01*
X295904Y1097359D01*
X295872Y1097447D01*
X295878Y1097494D01*
G03X295886Y1097637I-1194J139D01*
G03X294684Y1096435I-1202J0D01*
G03X294826Y1096443I3J1202D01*
G01X294873Y1096449D01*
X294961Y1096417D01*
X295248Y1096117D01*
X295276Y1096028D01*
X295272Y1096005D01*
G03X295250Y1095767I1281J-238D01*
G01Y1095490D01*
G02X295184Y1095341I-200J0D01*
G01X294932Y1095114D01*
X294850Y1095088D01*
X294809Y1095093D01*
G03X294684Y1095099I-120J-1196D01*
G03X293482Y1093897I0J-1202D01*
G03X293503Y1093676I1202J3D01*
G01Y1093674D01*
G02X293448Y1093497I-197J-36D01*
G01X293178Y1093228D01*
X293085Y1093199D01*
X293049Y1093206D01*
G03X292942Y1093222I-231J-1180D01*
G01X292940D01*
G03X292592Y1093209I-130J-1195D01*
G01X292543Y1093200D01*
X292448Y1093229D01*
X292145Y1093533D01*
X292116Y1093626D01*
X292125Y1093675D01*
G03X292146Y1093897I-1181J224D01*
G03X290944Y1095099I-1202J0D01*
G03X290820Y1095092I6J-1202D01*
G01X290818D01*
G02X290664Y1095142I-20J199D01*
G01X290443Y1095341D01*
G02X290377Y1095490I134J149D01*
G01Y1095667D01*
G03X290376Y1095693I-1302J-37D01*
G01Y1095767D01*
G03X290354Y1096000I-1303J-5D01*
G01Y1096006D01*
X290350Y1096029D01*
X290378Y1096118D01*
X290632Y1096384D01*
G02X290800Y1096444I144J-139D01*
G01X290801D01*
G03X290944Y1096435I147J1193D01*
G03X289742Y1097637I0J1202D01*
G03X289751Y1097495I1202J5D01*
G01Y1097493D01*
X289756Y1097447D01*
X289724Y1097359D01*
X289424Y1097072D01*
X289335Y1097045D01*
X289302Y1097050D01*
G03X289076Y1097070I-227J-1283D01*
G01X289073D01*
G03X288837Y1097048I2J-1303D01*
G01X288833D01*
X288812Y1097044D01*
X288723Y1097072D01*
X288423Y1097359D01*
X288391Y1097447D01*
X288397Y1097494D01*
G03X288405Y1097637I-1194J139D01*
G03X287203Y1096435I-1202J0D01*
G03X287346Y1096443I4J1202D01*
G01X287393Y1096449D01*
X287481Y1096417D01*
X287768Y1096117D01*
X287796Y1096028D01*
X287792Y1096005D01*
G03X287770Y1095767I1281J-238D01*
G01Y1095490D01*
G02X287704Y1095341I-200J0D01*
G01X287483Y1095142D01*
G02X287329Y1095092I-134J149D01*
G01X287328D01*
G03X287203Y1095099I-130J-1195D01*
G03X286001Y1093897I0J-1202D01*
G03X286022Y1093675I1202J2D01*
G01X286031Y1093626D01*
X286002Y1093533D01*
X285697Y1093228D01*
X285604Y1093199D01*
X285578Y1093204D01*
G03X285380Y1093228I-243J-1177D01*
G03X285112Y1093209I-50J-1201D01*
G01X285063Y1093200D01*
X284968Y1093229D01*
X284665Y1093533D01*
X284636Y1093626D01*
X284645Y1093675D01*
G03X284666Y1093897I-1181J224D01*
G03X283464Y1095099I-1202J0D01*
G03X283339Y1095092I5J-1202D01*
G01X283337D01*
G02X283183Y1095142I-20J199D01*
G01X282962Y1095341D01*
G02X282896Y1095490I134J149D01*
G01Y1095705D01*
G03X282895Y1095758I-1303J2D01*
G01X282894Y1095764D01*
Y1095779D01*
G03X282882Y1095944I-1302J-12D01*
G01Y1095946D01*
G03X282877Y1095981I-1292J-167D01*
G01X282869Y1096028D01*
X282897Y1096118D01*
X283184Y1096418D01*
X283272Y1096450D01*
X283319Y1096444D01*
G03X283464Y1096435I147J1193D01*
G03X282262Y1097637I0J1202D01*
G03X282271Y1097495I1202J5D01*
G01Y1097493D01*
X282276Y1097447D01*
X282244Y1097359D01*
X281944Y1097072D01*
X281855Y1097044D01*
X281819Y1097050D01*
G03X281592Y1097070I-227J-1282D01*
G03X281353Y1097048I-1J-1302D01*
G02X281347Y1097047I-36J196D01*
G01X281331Y1097044D01*
X281242Y1097072D01*
X280943Y1097359D01*
X280911Y1097447D01*
X280917Y1097494D01*
G03X280925Y1097637I-1194J139D01*
G03X279723Y1096435I-1202J0D01*
G03X279866Y1096443I4J1202D01*
G01X279913Y1096449D01*
X280001Y1096417D01*
X280288Y1096118D01*
X280316Y1096029D01*
X280313Y1096010D01*
G03X280290Y1095769I1279J-244D01*
G01Y1095490D01*
G02X280224Y1095341I-200J0D01*
G01X280003Y1095142D01*
G02X279849Y1095092I-134J149D01*
G01X279848D01*
G03X279723Y1095099I-130J-1195D01*
G03X278521Y1093897I0J-1202D01*
G03X278542Y1093675I1202J2D01*
G01X278551Y1093626D01*
X278522Y1093533D01*
X278217Y1093228D01*
X278124Y1093199D01*
X278098Y1093204D01*
G03X277900Y1093228I-243J-1177D01*
G03X277632Y1093209I-50J-1201D01*
G01X277583Y1093200D01*
X277488Y1093229D01*
X277185Y1093533D01*
X277156Y1093626D01*
X277165Y1093675D01*
G03X277186Y1093897I-1181J224D01*
G03X275984Y1095099I-1202J0D01*
G03X275859Y1095092I5J-1202D01*
G01X275857D01*
G02X275703Y1095142I-20J199D01*
G01X275482Y1095341D01*
G02X275416Y1095490I134J149D01*
G01Y1095705D01*
G03X275415Y1095758I-1303J2D01*
G01X275414Y1095764D01*
Y1095779D01*
G03X275402Y1095944I-1302J-12D01*
G01Y1095946D01*
G03X275397Y1095981I-1292J-167D01*
G01X275389Y1096028D01*
X275417Y1096118D01*
X275704Y1096418D01*
X275792Y1096450D01*
X275839Y1096444D01*
G03X275984Y1096435I147J1193D01*
G03X274782Y1097637I0J1202D01*
G03X274791Y1097495I1202J5D01*
G01Y1097493D01*
X274796Y1097447D01*
X274764Y1097359D01*
X274464Y1097072D01*
X274375Y1097044D01*
X274339Y1097050D01*
G03X274112Y1097070I-227J-1282D01*
G03X273873Y1097048I-1J-1302D01*
G02X273867Y1097047I-36J196D01*
G01X273851Y1097044D01*
X273762Y1097072D01*
X273463Y1097359D01*
X273431Y1097447D01*
X273437Y1097494D01*
G03X273445Y1097637I-1194J139D01*
G03X272243Y1096435I-1202J0D01*
G03X272386Y1096443I4J1202D01*
G01X272433Y1096449D01*
X272521Y1096417D01*
X272808Y1096118D01*
X272836Y1096029D01*
X272833Y1096010D01*
G03X272810Y1095769I1279J-244D01*
G01Y1095490D01*
G02X272744Y1095341I-200J0D01*
G01X272523Y1095142D01*
G02X272369Y1095092I-134J149D01*
G01X272368D01*
G03X272243Y1095099I-130J-1195D01*
G03X271041Y1093897I0J-1202D01*
G03X271062Y1093676I1202J3D01*
G01Y1093674D01*
G02X271007Y1093497I-197J-36D01*
G01X270737Y1093228D01*
X270644Y1093199D01*
X270608Y1093206D01*
G03X270501Y1093222I-231J-1180D01*
G01X270499D01*
G03X270151Y1093209I-130J-1195D01*
G01X270102Y1093200D01*
X270007Y1093229D01*
X269704Y1093533D01*
X269675Y1093626D01*
X269684Y1093675D01*
G03X269705Y1093897I-1181J224D01*
G03X268503Y1095099I-1202J0D01*
G03X268379Y1095092I6J-1202D01*
G01X268377D01*
G02X268223Y1095142I-20J199D01*
G01X268002Y1095341D01*
G02X267936Y1095490I134J149D01*
G01Y1095705D01*
G03X267935Y1095758I-1303J2D01*
G01X267934Y1095764D01*
Y1095779D01*
G03X267922Y1095944I-1302J-12D01*
G01Y1095946D01*
G03X267917Y1095981I-1292J-167D01*
G01X267909Y1096028D01*
X267937Y1096118D01*
X268224Y1096418D01*
X268312Y1096450D01*
X268359Y1096444D01*
G03X268503Y1096435I147J1193D01*
G03X267301Y1097637I0J1202D01*
G03X267310Y1097495I1202J5D01*
G01Y1097493D01*
X267315Y1097447D01*
X267283Y1097359D01*
X266983Y1097072D01*
X266894Y1097045D01*
X266868Y1097049D01*
G03X266632Y1097070I-233J-1281D01*
G03X266397Y1097048I3J-1302D01*
G01X266393D01*
X266371Y1097044D01*
X266282Y1097072D01*
X265982Y1097359D01*
X265950Y1097447D01*
X265956Y1097494D01*
G03X265964Y1097637I-1194J139D01*
G03X264762Y1096435I-1202J0D01*
G03X264904Y1096444I-5J1202D01*
G01X264907D01*
G02X265073Y1096384I22J-199D01*
G01X265328Y1096118D01*
X265356Y1096029D01*
X265353Y1096010D01*
G03X265330Y1095769I1279J-244D01*
G01Y1095490D01*
G02X265264Y1095341I-200J0D01*
G01X265043Y1095142D01*
G02X264889Y1095092I-134J149D01*
G01X264888D01*
G03X264762Y1095099I-130J-1195D01*
G03X263560Y1093897I0J-1202D01*
G03X263581Y1093675I1202J2D01*
G01X263590Y1093626D01*
X263561Y1093533D01*
X263256Y1093228D01*
X263163Y1093199D01*
X263137Y1093204D01*
G03X262939Y1093228I-243J-1177D01*
G03X262671Y1093209I-50J-1201D01*
G01X262622Y1093200D01*
X262527Y1093229D01*
X262224Y1093533D01*
X262195Y1093626D01*
X262204Y1093675D01*
G03X262225Y1093897I-1181J224D01*
G03X261023Y1095099I-1202J0D01*
G03X260898Y1095092I5J-1202D01*
G01X260896D01*
G02X260742Y1095142I-20J199D01*
G01X260521Y1095341D01*
G02X260455Y1095490I134J149D01*
G01Y1095667D01*
G03X260454Y1095693I-1302J-37D01*
G01Y1095767D01*
G03X260432Y1096000I-1303J-5D01*
G01Y1096006D01*
X260428Y1096029D01*
X260456Y1096118D01*
X260710Y1096384D01*
G02X260878Y1096444I144J-139D01*
G01X260879D01*
G03X261023Y1096435I147J1193D01*
G03X259821Y1097637I0J1202D01*
G03X259830Y1097495I1202J5D01*
G01Y1097493D01*
X259835Y1097447D01*
X259803Y1097359D01*
X259503Y1097072D01*
X259414Y1097044D01*
X259379Y1097050D01*
G03X259152Y1097070I-227J-1283D01*
G01X259151D01*
G03X258911Y1097048I-2J-1303D01*
G02X258905Y1097047I-36J196D01*
G01X258890Y1097044D01*
X258801Y1097072D01*
X258502Y1097359D01*
X258470Y1097447D01*
X258476Y1097494D01*
G03X258484Y1097637I-1194J139D01*
G03X257282Y1096435I-1202J0D01*
G03X257424Y1096443I3J1202D01*
G01X257471Y1096449D01*
X257559Y1096417D01*
X257846Y1096117D01*
X257874Y1096028D01*
X257870Y1096005D01*
G03X257848Y1095767I1281J-238D01*
G01Y1095490D01*
G02X257782Y1095341I-200J0D01*
G01X257530Y1095114D01*
X257448Y1095088D01*
X257407Y1095093D01*
G03X257282Y1095099I-120J-1196D01*
G03X256080Y1093897I0J-1202D01*
G03X256101Y1093675I1202J2D01*
G01X256110Y1093626D01*
X256081Y1093533D01*
X255776Y1093228D01*
X255683Y1093199D01*
X255657Y1093204D01*
G03X255459Y1093228I-243J-1177D01*
G03X255191Y1093209I-50J-1201D01*
G01X255142Y1093200D01*
X255047Y1093229D01*
X254744Y1093533D01*
X254715Y1093626D01*
X254724Y1093675D01*
G03X254745Y1093897I-1181J224D01*
G03X253543Y1095099I-1202J0D01*
G03X253418Y1095092I5J-1202D01*
G01X253416D01*
G02X253262Y1095142I-20J199D01*
G01X253041Y1095341D01*
G02X252975Y1095490I134J149D01*
G01Y1095667D01*
G03X252974Y1095693I-1302J-37D01*
G01Y1095767D01*
G03X252952Y1096000I-1303J-5D01*
G01Y1096006D01*
X252948Y1096029D01*
X252976Y1096118D01*
X253230Y1096384D01*
G02X253398Y1096444I144J-139D01*
G01X253399D01*
G03X253543Y1096435I147J1193D01*
G03X252341Y1097637I0J1202D01*
G03X252350Y1097495I1202J5D01*
G01Y1097493D01*
X252355Y1097447D01*
X252323Y1097359D01*
X252023Y1097072D01*
X251934Y1097044D01*
X251899Y1097050D01*
G03X251672Y1097070I-227J-1283D01*
G01X251671D01*
G03X251431Y1097048I-2J-1303D01*
G02X251425Y1097047I-36J196D01*
G01X251410Y1097044D01*
X251321Y1097072D01*
X251022Y1097359D01*
X250990Y1097447D01*
X250996Y1097494D01*
G03X251004Y1097637I-1194J139D01*
G03X249802Y1096435I-1202J0D01*
G03X249944Y1096443I3J1202D01*
G01X249991Y1096449D01*
X250079Y1096417D01*
X250366Y1096117D01*
X250394Y1096028D01*
X250390Y1096005D01*
G03X250368Y1095767I1281J-238D01*
G01Y1095490D01*
G02X250302Y1095341I-200J0D01*
G01X250050Y1095114D01*
X249968Y1095088D01*
X249927Y1095093D01*
G03X249802Y1095099I-120J-1196D01*
G03X248600Y1093897I0J-1202D01*
G03X248621Y1093675I1202J2D01*
G01X248630Y1093626D01*
X248601Y1093533D01*
X248296Y1093228D01*
X248203Y1093199D01*
X248177Y1093204D01*
G03X247932Y1093229I-244J-1177D01*
G03X247689Y1093204I1J-1202D01*
G01X247685D01*
X247661Y1093199D01*
X247568Y1093228D01*
X247263Y1093533D01*
X247234Y1093626D01*
X247243Y1093675D01*
G03X247264Y1093897I-1181J224D01*
G03X246062Y1095099I-1202J0D01*
G03X245938Y1095092I6J-1202D01*
G01X245936D01*
G02X245782Y1095142I-20J199D01*
G01X245561Y1095341D01*
G02X245495Y1095490I134J149D01*
G01Y1095667D01*
G03X245494Y1095693I-1302J-37D01*
G01Y1095767D01*
G03X245472Y1096000I-1303J-5D01*
G01Y1096006D01*
X245468Y1096029D01*
X245496Y1096118D01*
X245750Y1096384D01*
G02X245918Y1096444I144J-139D01*
G01X245919D01*
G03X246062Y1096435I147J1193D01*
G03X244860Y1097637I0J1202D01*
G03X244869Y1097495I1202J5D01*
G01Y1097493D01*
X244874Y1097447D01*
X244842Y1097359D01*
X244542Y1097072D01*
X244453Y1097045D01*
X244420Y1097050D01*
G03X244194Y1097070I-227J-1283D01*
G01X244191D01*
G03X243955Y1097048I2J-1303D01*
G01X243951D01*
X243930Y1097044D01*
X243841Y1097072D01*
X243541Y1097359D01*
X243509Y1097447D01*
X243515Y1097494D01*
G03X243523Y1097637I-1194J139D01*
G03X242321Y1096435I-1202J0D01*
G03X242464Y1096443I4J1202D01*
G01X242511Y1096449D01*
X242599Y1096417D01*
X242886Y1096117D01*
X242914Y1096028D01*
X242910Y1096005D01*
G03X242888Y1095767I1281J-238D01*
G01Y1095490D01*
G02X242822Y1095341I-200J0D01*
G01X242601Y1095142D01*
G02X242447Y1095092I-134J149D01*
G01X242446D01*
G03X242321Y1095099I-130J-1195D01*
G03X241119Y1093897I0J-1202D01*
G03X241140Y1093675I1202J2D01*
G01X241149Y1093626D01*
X241120Y1093533D01*
X240815Y1093228D01*
X240722Y1093199D01*
X240696Y1093204D01*
G03X240498Y1093228I-243J-1177D01*
G03X240230Y1093209I-50J-1201D01*
G01X240181Y1093200D01*
X240086Y1093229D01*
X239783Y1093533D01*
X239754Y1093626D01*
X239763Y1093675D01*
G03X239784Y1093897I-1181J224D01*
G03X238582Y1095099I-1202J0D01*
G03X238457Y1095092I5J-1202D01*
G01X238455D01*
G02X238301Y1095142I-20J199D01*
G01X238080Y1095341D01*
G02X238014Y1095490I134J149D01*
G01Y1095705D01*
G03X238013Y1095758I-1303J2D01*
G01X238012Y1095764D01*
Y1095779D01*
G03X238000Y1095944I-1302J-12D01*
G01Y1095946D01*
G03X237995Y1095981I-1292J-167D01*
G01X237987Y1096028D01*
X238015Y1096118D01*
X238302Y1096418D01*
X238390Y1096450D01*
X238437Y1096444D01*
G03X238582Y1096435I147J1193D01*
G03X237380Y1097637I0J1202D01*
G03X237389Y1097495I1202J5D01*
G01Y1097493D01*
X237394Y1097447D01*
X237362Y1097359D01*
X237062Y1097072D01*
X236973Y1097044D01*
X236937Y1097050D01*
G03X236710Y1097070I-227J-1282D01*
G03X236471Y1097048I-1J-1302D01*
G02X236465Y1097047I-36J196D01*
G01X236449Y1097044D01*
X236360Y1097072D01*
X236061Y1097359D01*
X236029Y1097447D01*
X236035Y1097494D01*
G03X236043Y1097637I-1194J139D01*
G03X234841Y1096435I-1202J0D01*
G03X234984Y1096443I4J1202D01*
G01X235031Y1096449D01*
X235119Y1096417D01*
X235406Y1096118D01*
X235434Y1096029D01*
X235431Y1096010D01*
G03X235408Y1095769I1279J-244D01*
G01Y1095490D01*
G02X235342Y1095341I-200J0D01*
G01X235121Y1095142D01*
G02X234967Y1095092I-134J149D01*
G01X234966D01*
G03X234841Y1095099I-130J-1195D01*
G03Y1092695I0J-1202D01*
G03X234965Y1092702I-6J1202D01*
G01X234967D01*
G02X235121Y1092652I20J-199D01*
G01X235342Y1092453D01*
G02X235408Y1092304I-134J-149D01*
G01Y1091925D01*
G03X235415Y1091791I1303J1D01*
G01X235420Y1091746D01*
X235390Y1091661D01*
X235104Y1091376D01*
X235019Y1091347D01*
X234974Y1091352D01*
G03X234842Y1091359I-130J-1195D01*
G03X233906Y1090911I0J-1202D01*
G02X233751Y1090837I-155J126D01*
G01X232193D01*
G02X232038Y1090911I0J200D01*
G03X231102Y1091359I-936J-754D01*
G03X230881Y1091338I3J-1202D01*
G01X230879D01*
G02X230702Y1091393I-36J197D01*
G01X230433Y1091661D01*
X230404Y1091756D01*
X230413Y1091805D01*
G03X230433Y1091994I-1182J221D01*
G01Y1092041D01*
G03X230408Y1092271I-1202J-14D01*
G01Y1092275D01*
X230403Y1092298D01*
X230433Y1092393D01*
X230702Y1092661D01*
G02X230879Y1092716I141J-142D01*
G01X230880D01*
G03X231102Y1092695I224J1181D01*
G03X229900Y1093897I0J1202D01*
G03X229921Y1093676I1202J3D01*
G01Y1093674D01*
G02X229866Y1093497I-197J-36D01*
G01X229596Y1093228D01*
X229503Y1093199D01*
X229467Y1093206D01*
G03X229359Y1093222I-230J-1180D01*
G01X229357D01*
G03X229010Y1093209I-129J-1195D01*
G01X228961Y1093200D01*
X228866Y1093229D01*
X228563Y1093533D01*
X228534Y1093626D01*
X228543Y1093675D01*
G03X228564Y1093897I-1181J224D01*
G03X227362Y1095099I-1202J0D01*
G03X227236Y1095092I4J-1202D01*
G01X227234D01*
G02X227080Y1095142I-20J199D01*
G01X226859Y1095341D01*
G02X226793Y1095490I134J149D01*
G01Y1095667D01*
G03X226792Y1095693I-1301J-37D01*
G01Y1095767D01*
G03X226770Y1096000I-1303J-5D01*
G01Y1096006D01*
X226766Y1096029D01*
X226794Y1096118D01*
X227082Y1096418D01*
X227170Y1096450D01*
X227217Y1096444D01*
G03X227362Y1096435I147J1193D01*
G03X226160Y1097637I0J1202D01*
G03X226169Y1097495I1202J5D01*
G01Y1097493D01*
X226174Y1097447D01*
X226142Y1097359D01*
X225842Y1097072D01*
X225752Y1097044D01*
X225705Y1097052D01*
G03X225489Y1097070I-216J-1285D01*
G03X225278Y1097053I-1J-1303D01*
G01X225277D01*
G02X225107Y1097106I-32J197D01*
G01X224842Y1097360D01*
X224810Y1097448D01*
X224816Y1097495D01*
G03X224824Y1097637I-1194J139D01*
G03X223622Y1096435I-1202J0D01*
G03X223762Y1096443I2J1202D01*
G02X223931Y1096382I24J-198D01*
G01X224184Y1096117D01*
X224212Y1096028D01*
X224209Y1096010D01*
G03X224186Y1095767I1280J-244D01*
G01Y1095491D01*
G02X224120Y1095342I-200J0D01*
G01X223900Y1095144D01*
G02X223746Y1095093I-134J148D01*
G01X223745D01*
G03X223622Y1095099I-120J-1196D01*
G03X222420Y1093897I0J-1202D01*
G03X222441Y1093676I1202J3D01*
G01Y1093674D01*
G02X222386Y1093497I-197J-36D01*
G01X222117Y1093228D01*
X222022Y1093199D01*
X221995Y1093204D01*
G03X221878Y1093222I-241J-1178D01*
G01X221876D01*
G03X221529Y1093209I-129J-1195D01*
G01X221480Y1093200D01*
X221385Y1093229D01*
X221082Y1093533D01*
X221053Y1093626D01*
X221062Y1093675D01*
G03X221083Y1093897I-1181J224D01*
G03X219881Y1095099I-1202J0D01*
G03X219755Y1095092I4J-1202D01*
G01X219753D01*
X219712Y1095088D01*
X219632Y1095114D01*
X219378Y1095341D01*
G02X219312Y1095490I134J149D01*
G01Y1095705D01*
G03X219311Y1095758I-1303J2D01*
G01X219310Y1095764D01*
Y1095779D01*
G03X219298Y1095945I-1302J-11D01*
G03X219287Y1096011I-1289J-181D01*
G01Y1096015D01*
X219284Y1096029D01*
X219312Y1096118D01*
X219600Y1096418D01*
X219688Y1096450D01*
X219735Y1096444D01*
G03X219881Y1096435I147J1193D01*
G03X218679Y1097637I0J1202D01*
G03X218688Y1097495I1202J5D01*
G01Y1097493D01*
X218693Y1097447D01*
X218661Y1097359D01*
X218361Y1097072D01*
X218271Y1097044D01*
X218224Y1097052D01*
G03X218008Y1097070I-216J-1284D01*
G03X217797Y1097053I-1J-1302D01*
G01X217796D01*
G02X217626Y1097106I-32J197D01*
G01X217361Y1097360D01*
X217329Y1097448D01*
X217335Y1097495D01*
G03X217343Y1097637I-1194J139D01*
G03X216141Y1096435I-1202J0D01*
G03X216282Y1096443I3J1202D01*
G01X216329Y1096449D01*
X216417Y1096417D01*
X216703Y1096117D01*
X216731Y1096027D01*
X216723Y1095981D01*
G03X216706Y1095769I1285J-210D01*
G01Y1095490D01*
G02X216640Y1095341I-200J0D01*
G01X216388Y1095114D01*
X216306Y1095088D01*
X216265Y1095093D01*
G03X216141Y1095099I-120J-1196D01*
G03X214939Y1093897I0J-1202D01*
G03X214960Y1093676I1202J3D01*
G01Y1093674D01*
G02X214905Y1093497I-197J-36D01*
G01X214635Y1093228D01*
X214542Y1093199D01*
X214506Y1093206D01*
G03X214398Y1093222I-230J-1180D01*
G01X214396D01*
G03X214049Y1093209I-129J-1195D01*
G01X214000Y1093200D01*
X213905Y1093229D01*
X213602Y1093533D01*
X213573Y1093626D01*
X213582Y1093675D01*
G03X213603Y1093897I-1181J224D01*
G03X212401Y1095099I-1202J0D01*
G03X212274Y1095092I3J-1202D01*
G01X212272D01*
X212231Y1095088D01*
X212151Y1095114D01*
X211897Y1095341D01*
G02X211831Y1095490I134J149D01*
G01Y1095667D01*
G03X211830Y1095693I-1302J-37D01*
G01Y1095767D01*
G03X211808Y1096000I-1303J-5D01*
G01Y1096006D01*
X211804Y1096029D01*
X211832Y1096118D01*
X212120Y1096418D01*
X212208Y1096450D01*
X212255Y1096444D01*
G03X212401Y1096435I147J1193D01*
G03X211199Y1097637I0J1202D01*
G03X211208Y1097495I1202J5D01*
G01Y1097492D01*
G02X211148Y1097326I-199J-22D01*
G01X210881Y1097072D01*
X210791Y1097044D01*
X210744Y1097052D01*
G03X210527Y1097070I-216J-1285D01*
G03X210316Y1097053I-1J-1303D01*
G01X210269Y1097045D01*
X210180Y1097073D01*
X209881Y1097360D01*
X209849Y1097448D01*
X209855Y1097495D01*
G03X209863Y1097637I-1194J139D01*
G03X208661Y1096435I-1202J0D01*
G03X208801Y1096443I2J1202D01*
G01X208847Y1096449D01*
X208937Y1096417D01*
X209222Y1096117D01*
X209250Y1096028D01*
X209247Y1096010D01*
G03X209224Y1095767I1280J-244D01*
G01Y1095491D01*
G02X209158Y1095342I-200J0D01*
G01X208938Y1095144D01*
G02X208784Y1095093I-134J148D01*
G01X208783D01*
G03X208661Y1095099I-120J-1196D01*
G03X207459Y1093897I0J-1202D01*
G03X207480Y1093676I1202J3D01*
G01Y1093674D01*
G02X207425Y1093497I-197J-36D01*
G01X207155Y1093228D01*
X207062Y1093199D01*
X207026Y1093206D01*
G03X206918Y1093222I-230J-1180D01*
G01X206916D01*
G03X206569Y1093209I-129J-1195D01*
G01X206520Y1093200D01*
X206425Y1093229D01*
X206122Y1093533D01*
X206093Y1093626D01*
X206102Y1093675D01*
G03X206123Y1093897I-1181J224D01*
G03X204921Y1095099I-1202J0D01*
G03X204794Y1095092I3J-1202D01*
G01X204792D01*
X204751Y1095088D01*
X204671Y1095114D01*
X204417Y1095341D01*
G02X204351Y1095490I134J149D01*
G01Y1095667D01*
G03X204350Y1095693I-1302J-37D01*
G01Y1095767D01*
G03X204328Y1096000I-1303J-5D01*
G01Y1096006D01*
X204324Y1096029D01*
X204352Y1096118D01*
X204640Y1096418D01*
X204728Y1096450D01*
X204775Y1096444D01*
G03X204921Y1096435I147J1193D01*
G03X203719Y1097637I0J1202D01*
G03X203728Y1097495I1202J5D01*
G01Y1097492D01*
G02X203668Y1097326I-199J-22D01*
G01X203401Y1097072D01*
X203311Y1097044D01*
X203264Y1097052D01*
G03X203047Y1097070I-216J-1285D01*
G03X202836Y1097053I-1J-1303D01*
G01X202789Y1097045D01*
X202700Y1097073D01*
X202401Y1097360D01*
X202369Y1097448D01*
X202375Y1097495D01*
G03X202383Y1097637I-1194J139D01*
G03X201181Y1096435I-1202J0D01*
G03X201321Y1096443I2J1202D01*
G01X201367Y1096449D01*
X201457Y1096417D01*
X201742Y1096117D01*
X201770Y1096028D01*
X201767Y1096010D01*
G03X201744Y1095767I1280J-244D01*
G01Y1095491D01*
G02X201678Y1095342I-200J0D01*
G01X201458Y1095144D01*
G02X201304Y1095093I-134J148D01*
G01X201303D01*
G03X201181Y1095099I-120J-1196D01*
G03X199979Y1093897I0J-1202D01*
G03X200000Y1093676I1202J3D01*
G01Y1093674D01*
G02X199945Y1093497I-197J-36D01*
G01X199675Y1093228D01*
X199582Y1093199D01*
X199546Y1093206D01*
G03X199067Y1093204I-235J-1179D01*
G01X199063D01*
X199039Y1093199D01*
X198946Y1093228D01*
X198641Y1093533D01*
X198612Y1093626D01*
X198621Y1093675D01*
G03X198642Y1093897I-1181J224D01*
G03X197440Y1095099I-1202J0D01*
G03X197314Y1095092I4J-1202D01*
G01X197312D01*
G02X197158Y1095142I-20J199D01*
G01X196937Y1095341D01*
G02X196871Y1095490I134J149D01*
G01Y1095667D01*
G03X196870Y1095693I-1301J-37D01*
G01Y1095767D01*
G03X196848Y1096000I-1303J-5D01*
G01Y1096006D01*
X196844Y1096029D01*
X196872Y1096118D01*
X197160Y1096418D01*
X197248Y1096450D01*
X197295Y1096444D01*
G03X197440Y1096435I147J1193D01*
G03X196238Y1097637I0J1202D01*
G03X196247Y1097495I1202J5D01*
G01Y1097493D01*
X196252Y1097447D01*
X196220Y1097359D01*
X195920Y1097072D01*
X195830Y1097044D01*
X195783Y1097052D01*
G03X195567Y1097070I-216J-1285D01*
G03X195356Y1097053I-1J-1303D01*
G01X195355D01*
G02X195185Y1097106I-32J197D01*
G01X194920Y1097360D01*
X194888Y1097448D01*
X194894Y1097495D01*
G03X194902Y1097637I-1194J139D01*
G03X193700Y1096435I-1202J0D01*
G03X193840Y1096443I2J1202D01*
G02X194009Y1096382I24J-198D01*
G01X194262Y1096117D01*
X194290Y1096028D01*
X194287Y1096010D01*
G03X194264Y1095767I1280J-244D01*
G01Y1095491D01*
G02X194198Y1095342I-200J0D01*
G01X193978Y1095144D01*
G02X193824Y1095093I-134J148D01*
G01X193823D01*
G03X193700Y1095099I-120J-1196D01*
G03X192498Y1093897I0J-1202D01*
G03X192519Y1093676I1202J3D01*
G01Y1093674D01*
G02X192464Y1093497I-197J-36D01*
G01X192194Y1093228D01*
X192101Y1093199D01*
X192065Y1093206D01*
G03X191957Y1093222I-230J-1180D01*
G01X191955D01*
G03X191608Y1093209I-129J-1195D01*
G01X191559Y1093200D01*
X191464Y1093229D01*
X191161Y1093533D01*
X191132Y1093626D01*
X191141Y1093675D01*
G03X191162Y1093897I-1181J224D01*
G03X189960Y1095099I-1202J0D01*
G03X189833Y1095092I3J-1202D01*
G01X189831D01*
X189790Y1095088D01*
X189710Y1095114D01*
X189456Y1095341D01*
G02X189390Y1095490I134J149D01*
G01Y1095705D01*
G03X189389Y1095758I-1303J2D01*
G01X189388Y1095764D01*
Y1095779D01*
G03X189376Y1095945I-1302J-11D01*
G03X189365Y1096011I-1289J-181D01*
G01Y1096015D01*
X189362Y1096029D01*
X189390Y1096118D01*
X189645Y1096384D01*
G02X189813Y1096444I144J-139D01*
G01X189814D01*
G03X189960Y1096435I147J1193D01*
G03X188758Y1097637I0J1202D01*
G03X188767Y1097495I1202J5D01*
G01Y1097492D01*
G02X188707Y1097326I-199J-22D01*
G01X188440Y1097072D01*
X188350Y1097044D01*
X188303Y1097052D01*
G03X188086Y1097070I-216J-1284D01*
G03X187875Y1097053I-1J-1302D01*
G01X187828Y1097045D01*
X187739Y1097073D01*
X187440Y1097360D01*
X187408Y1097448D01*
X187414Y1097495D01*
G03X187422Y1097637I-1194J139D01*
G03X186220Y1096435I-1202J0D01*
G03X186360Y1096443I2J1202D01*
G01X186407Y1096449D01*
X186495Y1096417D01*
X186781Y1096117D01*
X186809Y1096027D01*
X186801Y1095981D01*
G03X186784Y1095769I1285J-210D01*
G01Y1095491D01*
G02X186718Y1095342I-200J0D01*
G01X186498Y1095144D01*
G02X186344Y1095093I-134J148D01*
G01X186343D01*
G03X186220Y1095099I-120J-1196D01*
G03X185018Y1093897I0J-1202D01*
G03X185039Y1093676I1202J3D01*
G01Y1093674D01*
G02X184984Y1093497I-197J-36D01*
G01X184714Y1093228D01*
X184621Y1093199D01*
X184585Y1093206D01*
G03X184477Y1093222I-230J-1180D01*
G01X184475D01*
G03X184128Y1093209I-129J-1195D01*
G01X184079Y1093200D01*
X183984Y1093229D01*
X183681Y1093533D01*
X183652Y1093626D01*
X183661Y1093675D01*
G03X183682Y1093897I-1181J224D01*
G03X182480Y1095099I-1202J0D01*
G03X182353Y1095092I3J-1202D01*
G01X182351D01*
X182310Y1095088D01*
X182230Y1095114D01*
X181976Y1095341D01*
G02X181910Y1095490I134J149D01*
G01Y1095705D01*
G03X181909Y1095758I-1303J2D01*
G01X181908Y1095764D01*
Y1095779D01*
G03X181896Y1095945I-1302J-11D01*
G03X181885Y1096011I-1289J-181D01*
G01Y1096015D01*
X181882Y1096029D01*
X181910Y1096118D01*
X182165Y1096384D01*
G02X182333Y1096444I144J-139D01*
G01X182334D01*
G03X182480Y1096435I147J1193D01*
G03X181278Y1097637I0J1202D01*
G03X181287Y1097495I1202J5D01*
G01Y1097492D01*
G02X181227Y1097326I-199J-22D01*
G01X180960Y1097072D01*
X180870Y1097044D01*
X180823Y1097052D01*
G03X180606Y1097070I-216J-1284D01*
G03X180395Y1097053I-1J-1302D01*
G01X180348Y1097045D01*
X180259Y1097073D01*
X179960Y1097360D01*
X179928Y1097448D01*
X179934Y1097495D01*
G03X179942Y1097637I-1194J139D01*
G03X178740Y1096435I-1202J0D01*
G03X178880Y1096443I2J1202D01*
G01X178927Y1096449D01*
X179015Y1096417D01*
X179301Y1096117D01*
X179329Y1096027D01*
X179321Y1095981D01*
G03X179304Y1095769I1285J-210D01*
G01Y1095491D01*
G02X179238Y1095342I-200J0D01*
G01X179018Y1095144D01*
G02X178864Y1095093I-134J148D01*
G01X178863D01*
G03X178740Y1095099I-120J-1196D01*
G03X177538Y1093897I0J-1202D01*
G03X177559Y1093676I1202J3D01*
G01Y1093674D01*
G02X177504Y1093497I-197J-36D01*
G01X177234Y1093228D01*
X177141Y1093199D01*
X177105Y1093206D01*
G03X176626Y1093204I-235J-1179D01*
G01X176622D01*
X176598Y1093199D01*
X176505Y1093228D01*
X176200Y1093533D01*
X176171Y1093626D01*
X176180Y1093675D01*
G03X176201Y1093897I-1181J224D01*
G03X174999Y1095099I-1202J0D01*
G03X174873Y1095092I4J-1202D01*
G01X174871D01*
X174830Y1095088D01*
X174750Y1095114D01*
X174496Y1095341D01*
G02X174430Y1095490I134J149D01*
G01Y1095705D01*
G03X174429Y1095758I-1303J2D01*
G01X174428Y1095764D01*
Y1095779D01*
G03X174416Y1095945I-1302J-11D01*
G03X174405Y1096011I-1289J-181D01*
G01Y1096015D01*
X174402Y1096029D01*
X174430Y1096118D01*
X174718Y1096418D01*
X174806Y1096450D01*
X174853Y1096444D01*
G03X174999Y1096435I147J1193D01*
G03X173797Y1097637I0J1202D01*
G03X173806Y1097495I1202J5D01*
G01Y1097493D01*
X173811Y1097447D01*
X173779Y1097359D01*
X173479Y1097072D01*
X173389Y1097044D01*
X173342Y1097052D01*
G03X173126Y1097070I-216J-1284D01*
G37*
G36*
G01X240020Y54588D02*
X268877D01*
X269414Y54051D01*
Y53128D01*
X268877Y52591D01*
X240020D01*
G03X234083Y46654I0J-5937D01*
G01Y7874D01*
G02X228209Y2000I-5874J0D01*
G01X180965D01*
G02X175091Y7874I0J5874D01*
G01Y46167D01*
X177088D01*
Y7874D01*
G03X180963Y3998I3876J0D01*
G01X228209D01*
G03X232086Y7874I0J3877D01*
G01Y46654D01*
G02X240020Y54588I7934J0D01*
G37*
G36*
G01X271876Y1197968D02*
X272621D01*
G02X272793Y1197870I0J-200D01*
G01X272996Y1197529D01*
X272998Y1197423D01*
X272972Y1197376D01*
G03X272812Y1196751I1141J-625D01*
G03X274114Y1195449I1302J0D01*
G03X274956Y1195758I0J1302D01*
G01X274957Y1195759D01*
G02X275170Y1195787I128J-153D01*
G01X275499Y1195635D01*
G02X275506Y1195632I-75J-185D01*
G02X275614Y1195472I-91J-178D01*
G02X275615Y1195453I-199J-20D01*
G01Y1184953D01*
G02X275556Y1184811I-200J0D01*
G01X274282Y1183537D01*
X274254Y1183508D01*
X274180Y1183478D01*
X268949D01*
G03X268807Y1183419I0J-200D01*
G01X268720Y1183332D01*
G03X268661Y1183190I141J-142D01*
G01Y1170910D01*
G03X268720Y1170768I200J0D01*
G01X269056Y1170432D01*
X269085Y1170377D01*
X269090Y1170347D01*
G03X270373Y1169268I1283J223D01*
G03X271630Y1170231I0J1302D01*
G01Y1170232D01*
G02X271823Y1170379I193J-53D01*
G01X272664D01*
G02X272857Y1170232I0J-200D01*
G01Y1170231D01*
G03X275371I1257J339D01*
G01Y1170232D01*
G02X275564Y1170379I193J-53D01*
G01X276404D01*
G02X276597Y1170232I0J-200D01*
G01Y1170231D01*
G03X277695Y1169278I1257J339D01*
G01X277698D01*
G02X277822Y1169212I-26J-198D01*
G02X277872Y1169079I-150J-132D01*
G01Y1168321D01*
G02X277822Y1168188I-200J-1D01*
G02X277698Y1168122I-150J132D01*
G01X277695D01*
G03Y1165538I159J-1292D01*
G01X277698D01*
G02X277822Y1165472I-26J-198D01*
G02X277872Y1165339I-150J-132D01*
G01Y1160841D01*
G02X277822Y1160708I-200J-1D01*
G02X277698Y1160642I-150J132D01*
G01X277695D01*
G03Y1158058I159J-1292D01*
G01X277698D01*
G02X277822Y1157992I-26J-198D01*
G02X277872Y1157859I-150J-132D01*
G01Y1157101D01*
G02X277822Y1156968I-200J-1D01*
G02X277698Y1156902I-150J132D01*
G01X277695D01*
G03Y1154318I159J-1292D01*
G01X277698D01*
G02X277822Y1154252I-26J-198D01*
G02X277872Y1154119I-150J-132D01*
G01Y1153361D01*
G02X277822Y1153228I-200J-1D01*
G02X277698Y1153162I-150J132D01*
G01X277695D01*
G03Y1150578I159J-1292D01*
G01X277698D01*
G02X277822Y1150512I-26J-198D01*
G02X277872Y1150379I-150J-132D01*
G01Y1149620D01*
G02X277822Y1149487I-200J-1D01*
G02X277698Y1149421I-150J132D01*
G01X277695D01*
G03Y1146837I159J-1292D01*
G01X277698D01*
G02X277822Y1146771I-26J-198D01*
G02X277872Y1146638I-150J-132D01*
G01Y1145880D01*
G02X277822Y1145747I-200J-1D01*
G02X277698Y1145681I-150J132D01*
G01X277695D01*
G03Y1143097I159J-1292D01*
G01X277698D01*
G02X277822Y1143031I-26J-198D01*
G02X277872Y1142898I-150J-132D01*
G01Y1142140D01*
G02X277822Y1142007I-200J-1D01*
G02X277698Y1141941I-150J132D01*
G01X277695D01*
G03Y1139357I159J-1292D01*
G01X277698D01*
G02X277822Y1139291I-26J-198D01*
G02X277872Y1139158I-150J-132D01*
G01Y1138400D01*
G02X277822Y1138267I-200J-1D01*
G02X277698Y1138201I-150J132D01*
G01X277695D01*
G03X276552Y1136922I159J-1292D01*
G01Y1136908D01*
G03X276602Y1136549I1302J-2D01*
G01X276606Y1136537D01*
X276610Y1136507D01*
G02X276554Y1136337I-198J-29D01*
G01X275703Y1135486D01*
G02X275561Y1135427I-142J141D01*
G01X271687D01*
X271674D01*
G02X271524Y1135511I13J200D01*
G02X271506Y1135542I163J115D01*
G01X271359Y1135854D01*
G02X271351Y1136007I181J86D01*
G01X271378Y1136080D01*
X271398Y1136105D01*
G03X271675Y1136909I-1026J803D01*
G03X269071I-1302J0D01*
G03X269086Y1136709I1302J-3D01*
G03X269348Y1136104I1288J198D01*
G01X269368Y1136079D01*
X269395Y1136006D01*
G02X269387Y1135853I-189J-67D01*
G01X269240Y1135542D01*
G02X269222Y1135511I-181J84D01*
G02X269072Y1135427I-163J116D01*
G01X267947D01*
G02X267766Y1135541I0J200D01*
G01X267612Y1135868D01*
G02X267638Y1136081I180J86D01*
G03X267935Y1136909I-1006J828D01*
G03X265331I-1302J0D01*
G03X265628Y1136081I1303J0D01*
G02X265654Y1135868I-154J-127D01*
G01X265500Y1135541D01*
G02X265319Y1135427I-181J86D01*
G01X264207D01*
G02X264026Y1135541I0J200D01*
G01X263872Y1135868D01*
G02X263898Y1136081I180J86D01*
G03X264195Y1136909I-1006J828D01*
G03X261591I-1302J0D01*
G03X261888Y1136081I1303J0D01*
G02X261914Y1135868I-154J-127D01*
G01X261760Y1135541D01*
G02X261579Y1135427I-181J86D01*
G01X260467D01*
G02X260286Y1135541I0J200D01*
G01X260132Y1135868D01*
G02X260158Y1136081I180J86D01*
G03X260455Y1136909I-1006J828D01*
G03X257851I-1302J0D01*
G03X258148Y1136081I1303J0D01*
G02X258174Y1135868I-154J-127D01*
G01X258020Y1135541D01*
G02X257839Y1135427I-181J86D01*
G01X256727D01*
G02X256546Y1135541I0J200D01*
G01X256392Y1135868D01*
G02X256418Y1136081I180J86D01*
G03X256715Y1136909I-1006J828D01*
G03X254111I-1302J0D01*
G03X254408Y1136081I1303J0D01*
G02X254434Y1135868I-154J-127D01*
G01X254280Y1135541D01*
G02X254099Y1135427I-181J86D01*
G01X252987D01*
G02X252806Y1135541I0J200D01*
G01X252652Y1135868D01*
G02X252678Y1136081I180J86D01*
G03X252975Y1136909I-1006J828D01*
G03X250371I-1302J0D01*
G03X250668Y1136081I1303J0D01*
G02X250694Y1135868I-154J-127D01*
G01X250540Y1135541D01*
G02X250359Y1135427I-181J86D01*
G01X249247D01*
G02X249066Y1135541I0J200D01*
G01X248912Y1135868D01*
G02X248938Y1136081I180J86D01*
G03X249235Y1136909I-1006J828D01*
G03X246631I-1302J0D01*
G03X246928Y1136081I1303J0D01*
G02X246954Y1135868I-154J-127D01*
G01X246800Y1135541D01*
G02X246619Y1135427I-181J86D01*
G01X245506D01*
G02X245325Y1135541I0J200D01*
G01X245171Y1135868D01*
G02X245197Y1136081I180J86D01*
G03X245494Y1136909I-1006J828D01*
G03X242890I-1302J0D01*
G03X243187Y1136081I1303J0D01*
G02X243213Y1135868I-154J-127D01*
G01X243059Y1135541D01*
G02X242878Y1135427I-181J86D01*
G01X241766D01*
G02X241585Y1135541I0J200D01*
G01X241431Y1135868D01*
G02X241457Y1136081I180J86D01*
G03X241754Y1136909I-1006J828D01*
G03X239150I-1302J0D01*
G03X239447Y1136081I1303J0D01*
G02X239473Y1135868I-154J-127D01*
G01X239319Y1135541D01*
G02X239138Y1135427I-181J86D01*
G01X238026D01*
G02X237845Y1135541I0J200D01*
G01X237691Y1135868D01*
G02X237717Y1136081I180J86D01*
G03X238014Y1136909I-1006J828D01*
G03X235410I-1302J0D01*
G03X235707Y1136081I1303J0D01*
G02X235733Y1135868I-154J-127D01*
G01X235579Y1135541D01*
G02X235398Y1135427I-181J86D01*
G01X230546D01*
G02X230365Y1135541I0J200D01*
G01X230211Y1135868D01*
G02X230237Y1136081I180J86D01*
G03X230534Y1136909I-1006J828D01*
G03X227930I-1302J0D01*
G03X228227Y1136081I1303J0D01*
G02X228253Y1135868I-154J-127D01*
G01X228099Y1135541D01*
G02X227918Y1135427I-181J86D01*
G01X226806D01*
G02X226625Y1135541I0J200D01*
G01X226471Y1135868D01*
G02X226497Y1136081I180J86D01*
G03X226794Y1136909I-1006J828D01*
G03X224190I-1302J0D01*
G03X224487Y1136081I1303J0D01*
G02X224513Y1135868I-154J-127D01*
G01X224359Y1135541D01*
G02X224178Y1135427I-181J86D01*
G01X223065D01*
G02X222884Y1135541I0J200D01*
G01X222730Y1135868D01*
G02X222756Y1136081I180J86D01*
G03X223053Y1136909I-1006J828D01*
G03X220449I-1302J0D01*
G03X220746Y1136081I1303J0D01*
G02X220772Y1135868I-154J-127D01*
G01X220618Y1135541D01*
G02X220437Y1135427I-181J86D01*
G01X219325D01*
G02X219144Y1135541I0J200D01*
G01X218990Y1135868D01*
G02X219016Y1136081I180J86D01*
G03X219313Y1136909I-1006J828D01*
G03X216709I-1302J0D01*
G03X217006Y1136081I1303J0D01*
G02X217032Y1135868I-154J-127D01*
G01X216878Y1135541D01*
G02X216697Y1135427I-181J86D01*
G01X215585D01*
G02X215404Y1135541I0J200D01*
G01X215250Y1135868D01*
G02X215276Y1136081I180J86D01*
G03X215573Y1136909I-1006J828D01*
G03X212969I-1302J0D01*
G03X213266Y1136081I1303J0D01*
G02X213292Y1135868I-154J-127D01*
G01X213138Y1135541D01*
G02X212957Y1135427I-181J86D01*
G01X211845D01*
G02X211664Y1135541I0J200D01*
G01X211510Y1135868D01*
G02X211536Y1136081I180J86D01*
G03X211833Y1136909I-1006J828D01*
G03X209229I-1302J0D01*
G03X209526Y1136081I1303J0D01*
G02X209552Y1135868I-154J-127D01*
G01X209398Y1135541D01*
G02X209217Y1135427I-181J86D01*
G01X208105D01*
G02X207924Y1135541I0J200D01*
G01X207770Y1135868D01*
G02X207796Y1136081I180J86D01*
G03X208093Y1136909I-1006J828D01*
G03X205489I-1302J0D01*
G03X205786Y1136081I1303J0D01*
G02X205812Y1135868I-154J-127D01*
G01X205658Y1135541D01*
G02X205477Y1135427I-181J86D01*
G01X204365D01*
G02X204184Y1135541I0J200D01*
G01X204030Y1135868D01*
G02X204056Y1136081I180J86D01*
G03X204353Y1136909I-1006J828D01*
G03X201749I-1302J0D01*
G03X202046Y1136081I1303J0D01*
G02X202072Y1135868I-154J-127D01*
G01X201918Y1135541D01*
G02X201737Y1135427I-181J86D01*
G01X200625D01*
G02X200444Y1135541I0J200D01*
G01X200290Y1135868D01*
G02X200316Y1136081I180J86D01*
G03X200613Y1136909I-1006J828D01*
G03X198009I-1302J0D01*
G03X198306Y1136081I1303J0D01*
G02X198332Y1135868I-154J-127D01*
G01X198178Y1135541D01*
G02X197997Y1135427I-181J86D01*
G01X197176D01*
G02X197034Y1135486I0J200D01*
G01X196588Y1135932D01*
X196576Y1136079D01*
X196620Y1136139D01*
G03X196872Y1136909I-1050J770D01*
G03X195570Y1138211I-1302J0D01*
G03X194800Y1137959I0J-1302D01*
G01X194740Y1137915D01*
X194593Y1137927D01*
X193371Y1139149D01*
G03X193229Y1139208I-142J-141D01*
G01X193177D01*
G02X192997Y1139320I0J200D01*
G01X192839Y1139642D01*
G02X192859Y1139851I179J88D01*
G01X192860Y1139853D01*
Y1139854D01*
G03X193132Y1140649I-1028J796D01*
G03X190528I-1302J0D01*
G03X190800Y1139854I1300J1D01*
G01Y1139853D01*
X190801Y1139851D01*
G02X190821Y1139642I-159J-121D01*
G01X190663Y1139320D01*
G02X190483Y1139208I-180J88D01*
G01X189437D01*
G02X189257Y1139320I0J200D01*
G01X189099Y1139642D01*
G02X189119Y1139851I179J88D01*
G01X189120Y1139853D01*
Y1139854D01*
G03X189392Y1140649I-1028J796D01*
G03X186788I-1302J0D01*
G03X187060Y1139854I1300J1D01*
G01Y1139853D01*
X187061Y1139851D01*
G02X187081Y1139642I-159J-121D01*
G01X186923Y1139320D01*
G02X186743Y1139208I-180J88D01*
G01X185697D01*
G02X185517Y1139320I0J200D01*
G01X185359Y1139642D01*
G02X185379Y1139851I179J88D01*
G01X185380Y1139853D01*
Y1139854D01*
G03X185652Y1140649I-1028J796D01*
G03X183048I-1302J0D01*
G03X183320Y1139854I1300J1D01*
G01Y1139853D01*
X183321Y1139851D01*
G02X183341Y1139642I-159J-121D01*
G01X183183Y1139320D01*
G02X183003Y1139208I-180J88D01*
G01X181957D01*
G02X181777Y1139320I0J200D01*
G01X181619Y1139642D01*
G02X181639Y1139851I179J88D01*
G01X181640Y1139853D01*
Y1139854D01*
G03X181912Y1140649I-1028J796D01*
G03X179308I-1302J0D01*
G03X179580Y1139854I1300J1D01*
G01Y1139853D01*
X179581Y1139851D01*
G02X179601Y1139642I-159J-121D01*
G01X179443Y1139320D01*
G02X179263Y1139208I-180J88D01*
G01X178217D01*
G02X178037Y1139320I0J200D01*
G01X177879Y1139642D01*
G02X177899Y1139851I179J88D01*
G01X177900Y1139853D01*
Y1139854D01*
G03X178172Y1140649I-1028J796D01*
G03X175568I-1302J0D01*
G03X175840Y1139854I1300J1D01*
G01Y1139853D01*
X175841Y1139851D01*
G02X175861Y1139642I-159J-121D01*
G01X175703Y1139320D01*
G02X175523Y1139208I-180J88D01*
G01X174476D01*
G02X174296Y1139320I0J200D01*
G01X174138Y1139642D01*
G02X174158Y1139851I179J88D01*
G01X174159Y1139853D01*
Y1139854D01*
G03X174431Y1140649I-1028J796D01*
G03X171827I-1302J0D01*
G03X172099Y1139854I1300J1D01*
G01Y1139853D01*
X172100Y1139851D01*
G02X172120Y1139642I-159J-121D01*
G01X171962Y1139320D01*
G02X171782Y1139208I-180J88D01*
G01X170284D01*
G02X170142Y1139267I0J200D01*
G01X170122Y1139287D01*
G02Y1139569I142J141D01*
G01X170137Y1139584D01*
G03X170691Y1140649I-747J1065D01*
G03X169910Y1141842I-1302J0D01*
G02X169790Y1142025I80J183D01*
G01Y1142306D01*
G03X169760Y1142411I-200J0D01*
G01X169746Y1142435D01*
X169731Y1142487D01*
Y1142988D01*
G02X169767Y1143102I200J0D01*
G01X169784Y1143127D01*
X169831Y1143164D01*
X169859Y1143175D01*
G03Y1145603I-470J1214D01*
G01X169831Y1145614D01*
X169784Y1145651D01*
X169767Y1145676D01*
G02X169731Y1145790I164J114D01*
G01Y1146728D01*
G02X169767Y1146842I200J0D01*
G01X169784Y1146867D01*
X169831Y1146904D01*
X169859Y1146915D01*
G03Y1149343I-470J1214D01*
G01X169831Y1149354D01*
X169784Y1149391D01*
X169767Y1149416D01*
G02X169731Y1149530I164J114D01*
G01Y1150469D01*
G02X169767Y1150583I200J0D01*
G01X169784Y1150608D01*
X169831Y1150645D01*
X169859Y1150656D01*
G03Y1153084I-470J1214D01*
G01X169831Y1153095D01*
X169784Y1153132D01*
X169767Y1153157D01*
G02X169731Y1153271I164J114D01*
G01Y1153996D01*
G02X169769Y1154113I200J0D01*
G01Y1154114D01*
G02X169866Y1154186I162J-117D01*
G01X169867D01*
G03X169868Y1157034I-478J1424D01*
G01X169866D01*
G02X169769Y1157106I65J189D01*
G01Y1157107D01*
G02X169731Y1157224I162J117D01*
G01Y1157949D01*
G02X169767Y1158063I200J0D01*
G01X169784Y1158088D01*
X169831Y1158125D01*
X169859Y1158136D01*
G03Y1160564I-470J1214D01*
G01X169831Y1160575D01*
X169784Y1160612D01*
X169767Y1160637D01*
G02X169731Y1160751I164J114D01*
G01Y1169096D01*
G02X169790Y1169238I200J0D01*
G01X171293Y1170741D01*
G02X171346Y1170779I141J-141D01*
G01X171347Y1170780D01*
G02X171569Y1170749I88J-180D01*
G01X171570Y1170748D01*
X171796Y1170544D01*
X171829Y1170479D01*
X171833Y1170441D01*
G03X174425I1296J130D01*
G01X174429Y1170479D01*
X174462Y1170544D01*
X174688Y1170748D01*
G02X174823Y1170800I135J-148D01*
G01X175176D01*
G02X175249Y1170786I0J-200D01*
G01X175283Y1170773D01*
X175311Y1170748D01*
X175537Y1170544D01*
X175570Y1170479D01*
X175574Y1170441D01*
G03X178166I1296J130D01*
G01X178170Y1170479D01*
X178203Y1170544D01*
X178429Y1170748D01*
G02X178564Y1170800I135J-148D01*
G01X178916D01*
G02X178989Y1170786I0J-200D01*
G01X179023Y1170773D01*
X179051Y1170748D01*
X179277Y1170544D01*
X179310Y1170479D01*
X179314Y1170441D01*
G03X180610Y1169268I1296J129D01*
G03X181912Y1170570I0J1302D01*
G03X180892Y1171841I-1302J0D01*
G01X180823Y1171856D01*
X180735Y1171966D01*
Y1172914D01*
X180823Y1173024D01*
X180892Y1173039D01*
G03Y1175581I-282J1271D01*
G01X180823Y1175596D01*
X180735Y1175706D01*
Y1176655D01*
X180823Y1176765D01*
X180892Y1176780D01*
G03Y1179322I-282J1271D01*
G01X180823Y1179337D01*
X180735Y1179447D01*
Y1180395D01*
X180823Y1180505D01*
X180892Y1180520D01*
G03Y1183062I-282J1271D01*
G01X180823Y1183077D01*
X180735Y1183187D01*
Y1184135D01*
X180823Y1184245D01*
X180892Y1184260D01*
G03X181894Y1185745I-282J1271D01*
G01X181886Y1185792D01*
X181914Y1185881D01*
X182201Y1186182D01*
X182289Y1186213D01*
X182337Y1186208D01*
G03X182480Y1186199I147J1193D01*
G03Y1188603I0J1202D01*
G03X182337Y1188594I4J-1202D01*
G01X182289Y1188589D01*
X182201Y1188620D01*
X181914Y1188921D01*
X181887Y1189010D01*
X181895Y1189057D01*
G03X181912Y1189248I-1285J211D01*
G01X181913Y1189287D01*
X181942Y1189357D01*
X182496Y1189911D01*
X182559Y1189941D01*
X182594Y1189944D01*
G03X183352Y1190314I-115J1197D01*
G02X183497Y1190376I145J-138D01*
G01X193199D01*
G03X193341Y1190435I0J200D01*
G01X194454Y1191548D01*
G03X194512Y1191673I-141J141D01*
G01X194517Y1191725D01*
X194573Y1191809D01*
X194717Y1191884D01*
G02X194861Y1191899I91J-178D01*
G01X194917Y1191884D01*
X194939Y1191872D01*
G03X195570Y1191709I631J1140D01*
G03Y1194313I0J1302D01*
G03X195067Y1194212I0J-1303D01*
G01X195020Y1194193D01*
X194922Y1194202D01*
X194602Y1194415D01*
G02X194513Y1194581I111J166D01*
G01Y1195181D01*
G02X194602Y1195347I200J0D01*
G01X194922Y1195560D01*
X195020Y1195569D01*
X195067Y1195550D01*
G03X195570Y1195449I503J1202D01*
G03X196872Y1196751I0J1302D01*
G03X196712Y1197376I-1301J0D01*
G01X196686Y1197423D01*
X196688Y1197529D01*
X196891Y1197870D01*
G02X197063Y1197968I172J-102D01*
G01X197818D01*
G02X197990Y1197870I0J-200D01*
G01X198193Y1197529D01*
X198195Y1197423D01*
X198169Y1197376D01*
G03X198009Y1196751I1141J-625D01*
G03X200613I1302J0D01*
G03X200453Y1197376I-1301J0D01*
G01X200427Y1197423D01*
X200429Y1197529D01*
X200632Y1197870D01*
G02X200804Y1197968I172J-102D01*
G01X201558D01*
G02X201730Y1197870I0J-200D01*
G01X201933Y1197529D01*
X201935Y1197423D01*
X201909Y1197376D01*
G03X201749Y1196751I1141J-625D01*
G03X204353I1302J0D01*
G03X204193Y1197376I-1301J0D01*
G01X204167Y1197423D01*
X204169Y1197529D01*
X204372Y1197870D01*
G02X204544Y1197968I172J-102D01*
G01X205298D01*
G02X205470Y1197870I0J-200D01*
G01X205673Y1197529D01*
X205675Y1197423D01*
X205649Y1197376D01*
G03X205489Y1196751I1141J-625D01*
G03X208093I1302J0D01*
G03X207933Y1197376I-1301J0D01*
G01X207907Y1197423D01*
X207909Y1197529D01*
X208112Y1197870D01*
G02X208284Y1197968I172J-102D01*
G01X209038D01*
G02X209210Y1197870I0J-200D01*
G01X209413Y1197529D01*
X209415Y1197423D01*
X209389Y1197376D01*
G03X209229Y1196751I1141J-625D01*
G03X211833I1302J0D01*
G03X211673Y1197376I-1301J0D01*
G01X211647Y1197423D01*
X211649Y1197529D01*
X211852Y1197870D01*
G02X212024Y1197968I172J-102D01*
G01X212778D01*
G02X212950Y1197870I0J-200D01*
G01X213153Y1197529D01*
X213155Y1197423D01*
X213129Y1197376D01*
G03X212969Y1196751I1141J-625D01*
G03X215573I1302J0D01*
G03X215413Y1197376I-1301J0D01*
G01X215387Y1197423D01*
X215389Y1197529D01*
X215592Y1197870D01*
G02X215764Y1197968I172J-102D01*
G01X216518D01*
G02X216690Y1197870I0J-200D01*
G01X216893Y1197529D01*
X216895Y1197423D01*
X216869Y1197376D01*
G03X216709Y1196751I1141J-625D01*
G03X219313I1302J0D01*
G03X219153Y1197376I-1301J0D01*
G01X219127Y1197423D01*
X219129Y1197529D01*
X219332Y1197870D01*
G02X219504Y1197968I172J-102D01*
G01X220258D01*
G02X220430Y1197870I0J-200D01*
G01X220633Y1197529D01*
X220635Y1197423D01*
X220609Y1197376D01*
G03X220449Y1196751I1141J-625D01*
G03X223053I1302J0D01*
G03X222893Y1197376I-1301J0D01*
G01X222867Y1197423D01*
X222869Y1197529D01*
X223072Y1197870D01*
G02X223244Y1197968I172J-102D01*
G01X223999D01*
G02X224171Y1197870I0J-200D01*
G01X224374Y1197529D01*
X224376Y1197423D01*
X224350Y1197376D01*
G03X224190Y1196751I1141J-625D01*
G03X226794I1302J0D01*
G03X226634Y1197376I-1301J0D01*
G01X226608Y1197423D01*
X226610Y1197529D01*
X226813Y1197870D01*
G02X226985Y1197968I172J-102D01*
G01X227739D01*
G02X227911Y1197870I0J-200D01*
G01X228114Y1197529D01*
X228116Y1197423D01*
X228090Y1197376D01*
G03X227930Y1196751I1141J-625D01*
G03X230534I1302J0D01*
G03X230374Y1197376I-1301J0D01*
G01X230348Y1197423D01*
X230350Y1197529D01*
X230553Y1197870D01*
G02X230725Y1197968I172J-102D01*
G01X235219D01*
G02X235391Y1197870I0J-200D01*
G01X235594Y1197529D01*
X235596Y1197423D01*
X235570Y1197376D01*
G03X235410Y1196751I1141J-625D01*
G03X238014I1302J0D01*
G03X237854Y1197376I-1301J0D01*
G01X237828Y1197423D01*
X237830Y1197529D01*
X238033Y1197870D01*
G02X238205Y1197968I172J-102D01*
G01X238959D01*
G02X239131Y1197870I0J-200D01*
G01X239334Y1197529D01*
X239336Y1197423D01*
X239310Y1197376D01*
G03X239150Y1196751I1141J-625D01*
G03X241754I1302J0D01*
G03X241594Y1197376I-1301J0D01*
G01X241568Y1197423D01*
X241570Y1197529D01*
X241773Y1197870D01*
G02X241945Y1197968I172J-102D01*
G01X242699D01*
G02X242871Y1197870I0J-200D01*
G01X243074Y1197529D01*
X243076Y1197423D01*
X243050Y1197376D01*
G03X242890Y1196751I1141J-625D01*
G03X245494I1302J0D01*
G03X245334Y1197376I-1301J0D01*
G01X245308Y1197423D01*
X245310Y1197529D01*
X245513Y1197870D01*
G02X245685Y1197968I172J-102D01*
G01X246440D01*
G02X246612Y1197870I0J-200D01*
G01X246815Y1197529D01*
X246817Y1197423D01*
X246791Y1197376D01*
G03X246631Y1196751I1141J-625D01*
G03X249235I1302J0D01*
G03X249075Y1197376I-1301J0D01*
G01X249049Y1197423D01*
X249051Y1197529D01*
X249254Y1197870D01*
G02X249426Y1197968I172J-102D01*
G01X250180D01*
G02X250352Y1197870I0J-200D01*
G01X250555Y1197529D01*
X250557Y1197423D01*
X250531Y1197376D01*
G03X250371Y1196751I1141J-625D01*
G03X252975I1302J0D01*
G03X252815Y1197376I-1301J0D01*
G01X252789Y1197423D01*
X252791Y1197529D01*
X252994Y1197870D01*
G02X253166Y1197968I172J-102D01*
G01X253920D01*
G02X254092Y1197870I0J-200D01*
G01X254295Y1197529D01*
X254297Y1197423D01*
X254271Y1197376D01*
G03X254111Y1196751I1141J-625D01*
G03X256715I1302J0D01*
G03X256555Y1197376I-1301J0D01*
G01X256529Y1197423D01*
X256531Y1197529D01*
X256734Y1197870D01*
G02X256906Y1197968I172J-102D01*
G01X257660D01*
G02X257832Y1197870I0J-200D01*
G01X258035Y1197529D01*
X258037Y1197423D01*
X258011Y1197376D01*
G03X257851Y1196751I1141J-625D01*
G03X260455I1302J0D01*
G03X260295Y1197376I-1301J0D01*
G01X260269Y1197423D01*
X260271Y1197529D01*
X260474Y1197870D01*
G02X260646Y1197968I172J-102D01*
G01X261400D01*
G02X261572Y1197870I0J-200D01*
G01X261775Y1197529D01*
X261777Y1197423D01*
X261751Y1197376D01*
G03X261591Y1196751I1141J-625D01*
G03X264195I1302J0D01*
G03X264035Y1197376I-1301J0D01*
G01X264009Y1197423D01*
X264011Y1197529D01*
X264214Y1197870D01*
G02X264386Y1197968I172J-102D01*
G01X265140D01*
G02X265312Y1197870I0J-200D01*
G01X265515Y1197529D01*
X265517Y1197423D01*
X265491Y1197376D01*
G03X265331Y1196751I1141J-625D01*
G03X267935I1302J0D01*
G03X267775Y1197376I-1301J0D01*
G01X267749Y1197423D01*
X267751Y1197529D01*
X267954Y1197870D01*
G02X268126Y1197968I172J-102D01*
G01X268910D01*
G02X269083Y1197869I0J-200D01*
G01X269285Y1197525D01*
Y1197419D01*
X269259Y1197372D01*
G03X269091Y1196732I1135J-640D01*
G03X271695I1302J0D01*
G03X271527Y1197372I-1303J0D01*
G01X271501Y1197419D01*
Y1197525D01*
X271703Y1197869D01*
G02X271876Y1197968I173J-101D01*
G37*
G36*
G01X605356Y1551880D02*
Y1539665D01*
G02X605297Y1539523I-200J0D01*
G01X600976Y1535201D01*
G03X600124Y1533927I2775J-2778D01*
G01X598532Y1530083D01*
G02X598489Y1530018I-185J76D01*
G01X594962Y1526491D01*
G03X594903Y1526349I141J-142D01*
G01Y1521357D01*
G02X594888Y1521280I-200J-1D01*
G01X593890Y1518868D01*
G02X593718Y1518745I-185J77D01*
G01X593302Y1518718D01*
X593201Y1518772D01*
X593173Y1518821D01*
G03X591872Y1519573I-1301J-749D01*
G03Y1516569I0J-1502D01*
G03X592956Y1517032I-1J1502D01*
G02X593300Y1516881I144J-138D01*
G01Y1516880D01*
G03X593294Y1516649I3920J-217D01*
G01Y1510587D01*
G02X593166Y1510400I-200J0D01*
G01X592816Y1510266D01*
G02X592596Y1510319I-71J187D01*
G03X591481Y1510815I-1115J-1005D01*
G03Y1507811I0J-1502D01*
G03X592596Y1508307I0J1501D01*
G02X592816Y1508360I149J-134D01*
G01X593166Y1508226D01*
G02X593294Y1508039I-72J-187D01*
G01Y1502967D01*
G02X593166Y1502781I-200J1D01*
G01X592759Y1502624D01*
X592640Y1502652D01*
X592598Y1502698D01*
G03X591487Y1503189I-1111J-1011D01*
G03Y1500185I0J-1502D01*
G03X592598Y1500676I0J1502D01*
G01X592640Y1500722D01*
X592759Y1500750D01*
X593166Y1500593D01*
G02X593294Y1500407I-72J-187D01*
G01Y1484367D01*
G02X593235Y1484225I-200J0D01*
G01X592591Y1483581D01*
G02X592449Y1483522I-142J141D01*
G01X584614D01*
G02X584427Y1483652I0J200D01*
G01X582637Y1488474D01*
G02X582625Y1488544I188J68D01*
G01Y1490576D01*
G03X582566Y1490718I-200J0D01*
G01X581766Y1491518D01*
G02X581718Y1491724I141J142D01*
G01X581852Y1492119D01*
X581940Y1492191D01*
X581997Y1492198D01*
G03X583305Y1493687I-194J1489D01*
G03X581803Y1495189I-1502J0D01*
G03X580843Y1494842I0J-1501D01*
G01X580842D01*
G02X580663Y1494803I-127J154D01*
G01X580348Y1494887D01*
G02X580212Y1495011I52J193D01*
G01X579717Y1496345D01*
G02X579782Y1496573I187J70D01*
G03X580361Y1497758I-923J1185D01*
G03X578859Y1499260I-1502J0D01*
G03X578785Y1499258I4J-1502D01*
G01X578719Y1499255D01*
X578611Y1499326D01*
X576944Y1503816D01*
G02X576932Y1503886I188J68D01*
G01Y1504184D01*
G02X577132Y1504384I200J0D01*
G01X577182D01*
X577225Y1504361D01*
X577227D01*
G03X577931Y1504185I705J1326D01*
G03Y1507189I0J1502D01*
G01X577929D01*
G03X577458Y1507113I1J-1502D01*
G01X577412Y1507097D01*
X577317Y1507112D01*
X577015Y1507330D01*
G02X576932Y1507492I117J162D01*
G01Y1512669D01*
G03X576873Y1512811I-200J0D01*
G01X573093Y1516591D01*
G02X573040Y1516783I141J142D01*
G01X573127Y1517117D01*
G02X573264Y1517259I194J-50D01*
G01X573265D01*
G03X574351Y1518702I-416J1443D01*
G03X573693Y1519944I-1501J0D01*
G01X573658Y1519968D01*
X573614Y1520037D01*
X573564Y1520370D01*
G02X573605Y1520524I198J30D01*
G01X573606Y1520525D01*
G03X573934Y1521462I-1174J937D01*
G03X570930I-1502J0D01*
G03X571588Y1520220I1501J0D01*
G01X571623Y1520196D01*
X571667Y1520127D01*
X571717Y1519794D01*
G02X571676Y1519640I-198J-30D01*
G01X571675Y1519639D01*
G03X571518Y1519399I1173J-939D01*
G01X571501Y1519367D01*
X571446Y1519317D01*
X571411Y1519304D01*
G02X571153Y1519422I-70J187D01*
G01X568374Y1526913D01*
G02X568415Y1527119I187J70D01*
G01X568416Y1527120D01*
G03X568826Y1528151I-1091J1031D01*
G03X567479Y1529645I-1502J0D01*
G02X567312Y1529775I21J199D01*
G01X567072Y1530424D01*
X567067Y1530477D01*
X567073Y1530505D01*
G03X567102Y1530797I-1473J294D01*
G01Y1530800D01*
G03X566628Y1531895I-1502J0D01*
G02X566565Y1532041I137J146D01*
G01Y1532553D01*
G03X566506Y1532695I-200J0D01*
G01X566062Y1533139D01*
X566047Y1533176D01*
G03X565996Y1533292I-3620J-1522D01*
G01X565980Y1533327D01*
X565976Y1533399D01*
X566068Y1533690D01*
G02X566158Y1533803I191J-60D01*
G03X566902Y1535100I-759J1297D01*
G03X565400Y1536602I-1502J0D01*
G03X564631Y1536390I0J-1501D01*
G01X564596Y1536369D01*
X564519Y1536358D01*
X564206Y1536437D01*
G02X564083Y1536528I48J194D01*
G01X560583Y1542362D01*
G03X559477Y1543552I-3367J-2020D01*
G01X559038Y1543861D01*
X559001Y1543909D01*
X558991Y1543937D01*
G03X557606Y1544913I-1407J-526D01*
G02X557494Y1544949I3J200D01*
G01X546715Y1552540D01*
G02X546689Y1552562I116J163D01*
G01X535746Y1563505D01*
G02X535687Y1563640I141J142D01*
G01X535677Y1563952D01*
X535703Y1564024D01*
X535728Y1564052D01*
G03X536204Y1565314I-1436J1262D01*
G01Y1565315D01*
G03X534292Y1567227I-1912J0D01*
G01X534291D01*
G03X533029Y1566751I0J-1912D01*
G01X533001Y1566726D01*
X532929Y1566700D01*
X532617Y1566710D01*
G02X532482Y1566769I7J200D01*
G01X527940Y1571311D01*
X527911Y1571374D01*
X527908Y1571410D01*
G03X525819Y1573499I-2278J-189D01*
G01X525783Y1573502D01*
X525720Y1573531D01*
X525402Y1573849D01*
G03X525260Y1573908I-142J-141D01*
G01X518848D01*
G02X518757Y1573930I0J200D01*
G03X516969Y1574360I-1787J-3496D01*
G03X515264Y1573971I-1J-3926D01*
G02X515124Y1573958I-87J180D01*
G03X514755Y1574008I-371J-1352D01*
G03X514267Y1573920I1J-1402D01*
G01X514234Y1573908D01*
X510119D01*
G02X509919Y1574108I0J200D01*
G01Y1574118D01*
G03X509920Y1574129I-201J24D01*
G01Y1575255D01*
G02X509948Y1575358I200J1D01*
G03Y1577320I-1642J981D01*
G02X509920Y1577423I172J102D01*
G01Y1580373D01*
G02X509948Y1580476I200J1D01*
G03Y1582438I-1642J981D01*
G02X509920Y1582541I172J102D01*
G01Y1583667D01*
G03X509717Y1583870I-203J0D01*
G01X506897D01*
G03X506694Y1583667I0J-203D01*
G01Y1582541D01*
G02X506666Y1582438I-200J-1D01*
G03Y1580476I1642J-981D01*
G02X506694Y1580373I-172J-102D01*
G01Y1577423D01*
G02X506666Y1577320I-200J-1D01*
G03Y1575358I1642J-981D01*
G02X506694Y1575255I-172J-102D01*
G01Y1574129D01*
G03X506695Y1574118I202J13D01*
G01Y1574108D01*
G02X506495Y1573908I-200J0D01*
G01X501525D01*
G02X501434Y1573930I0J200D01*
G03X499646Y1574360I-1787J-3496D01*
G03X497941Y1573971I-1J-3926D01*
G02X497801Y1573958I-87J180D01*
G03X497432Y1574008I-371J-1352D01*
G03X496944Y1573920I1J-1402D01*
G01X496911Y1573908D01*
X492797D01*
G02X492597Y1574108I0J200D01*
G01Y1574118D01*
G03X492598Y1574129I-201J24D01*
G01Y1575255D01*
G02X492626Y1575358I200J1D01*
G03Y1577320I-1642J981D01*
G02X492598Y1577423I172J102D01*
G01Y1580373D01*
G02X492626Y1580476I200J1D01*
G03Y1582438I-1642J981D01*
G02X492598Y1582541I172J102D01*
G01Y1583667D01*
G03X492395Y1583870I-203J0D01*
G01X489575D01*
G03X489372Y1583667I0J-203D01*
G01Y1582541D01*
G02X489344Y1582438I-200J-1D01*
G03Y1580476I1642J-981D01*
G02X489372Y1580373I-172J-102D01*
G01Y1577423D01*
G02X489344Y1577320I-200J-1D01*
G03Y1575358I1642J-981D01*
G02X489372Y1575255I-172J-102D01*
G01Y1574129D01*
G03X489373Y1574118I202J13D01*
G01Y1574108D01*
G02X489173Y1573908I-200J0D01*
G01X484202D01*
G02X484111Y1573930I0J200D01*
G03X482323Y1574360I-1787J-3496D01*
G03X480618Y1573971I-1J-3926D01*
G02X480478Y1573958I-87J180D01*
G03X480109Y1574008I-371J-1352D01*
G03X479621Y1573920I1J-1402D01*
G01X479588Y1573908D01*
X475474D01*
G02X475274Y1574108I0J200D01*
G01Y1575255D01*
G02X475302Y1575358I200J1D01*
G03X475574Y1576339I-1640J983D01*
G03X475302Y1577320I-1912J-2D01*
G02X475274Y1577423I172J102D01*
G01Y1580373D01*
G02X475302Y1580476I200J1D01*
G03X475574Y1581457I-1640J983D01*
G03X475302Y1582438I-1912J-2D01*
G02X475274Y1582541I172J102D01*
G01Y1583667D01*
G03X475072Y1583870I-203J0D01*
G01X472252D01*
G03X472050Y1583667I0J-202D01*
G01Y1582541D01*
G02X472022Y1582438I-200J-1D01*
G03X471750Y1581457I1640J-983D01*
G03X472022Y1580476I1912J2D01*
G02X472050Y1580373I-172J-102D01*
G01Y1577423D01*
G02X472022Y1577320I-200J-1D01*
G03X471750Y1576339I1640J-983D01*
G03X472022Y1575358I1912J2D01*
G02X472050Y1575255I-172J-102D01*
G01Y1574108D01*
G02X471850Y1573908I-200J0D01*
G01X466879D01*
G02X466788Y1573930I0J200D01*
G03X465000Y1574360I-1787J-3496D01*
G03X463295Y1573971I-1J-3926D01*
G02X463155Y1573958I-87J180D01*
G03X462786Y1574008I-371J-1352D01*
G03X462298Y1573920I1J-1402D01*
G01X462265Y1573908D01*
X461219D01*
G03X461077Y1573849I0J-200D01*
G01X457210Y1569982D01*
X457115Y1569953D01*
X457066Y1569962D01*
G03X456339Y1570030I-728J-3859D01*
G03X454634Y1569640I1J-3927D01*
G02X454494Y1569627I-87J180D01*
G03X454125Y1569677I-371J-1352D01*
G03X452723Y1568275I0J-1402D01*
G01Y1568273D01*
G03X452779Y1567880I1402J-1D01*
G02X452769Y1567741I-192J-56D01*
G03X452412Y1566105I3570J-1636D01*
G01Y1565268D01*
G02X452354Y1565126I-200J-1D01*
G01X451892Y1564664D01*
G03Y1564382I142J-141D01*
G01X452460Y1563814D01*
G02X452513Y1563718I-142J-141D01*
G03X452543Y1563595I3829J869D01*
G02Y1563493I-193J-51D01*
G03X452412Y1562488I3796J-1006D01*
G01Y1560985D01*
G03X452713Y1559479I3927J2D01*
G02X452716Y1559333I-184J-77D01*
G03X452623Y1558813I1409J-520D01*
G03X452942Y1557887I1504J0D01*
G02X452985Y1557764I-157J-124D01*
G01Y1512854D01*
G02X452952Y1512744I-200J0D01*
G03Y1511208I1173J-768D01*
G02X452985Y1511098I-167J-110D01*
G01Y1508123D01*
G02X452952Y1508013I-200J0D01*
G03Y1506477I1173J-768D01*
G02X452985Y1506367I-167J-110D01*
G01Y1503563D01*
G02X452942Y1503440I-200J1D01*
G03Y1501588I1183J-926D01*
G02X452985Y1501465I-157J-124D01*
G01Y1497499D01*
G02X452952Y1497389I-200J0D01*
G03Y1495853I1173J-768D01*
G02X452985Y1495743I-167J-110D01*
G01Y1492768D01*
G02X452952Y1492658I-200J0D01*
G03Y1491122I1173J-768D01*
G02X452985Y1491012I-167J-110D01*
G01Y1488208D01*
G02X452942Y1488085I-200J1D01*
G03Y1486233I1183J-926D01*
G02X452985Y1486110I-157J-124D01*
G01Y1482145D01*
G02X452952Y1482035I-200J0D01*
G03X452723Y1481267I1173J-768D01*
G03X452780Y1480871I1402J0D01*
G02X452770Y1480731I-192J-57D01*
G03X452412Y1479095I3569J-1638D01*
G01Y1477591D01*
G03X452543Y1476587I3927J2D01*
G02Y1476485I-193J-51D01*
G03X452412Y1475481I3796J-1006D01*
G01Y1473977D01*
G03X452713Y1472471I3927J2D01*
G02X452716Y1472325I-184J-77D01*
G03X452623Y1471805I1409J-520D01*
G03X452942Y1470879I1504J0D01*
G02X452985Y1470756I-157J-124D01*
G01Y1466791D01*
G02X452952Y1466681I-200J0D01*
G03Y1465145I1173J-768D01*
G02X452985Y1465035I-167J-110D01*
G01Y1462863D01*
G03X453044Y1462721I200J0D01*
G01X454667Y1461098D01*
G02X454726Y1460956I-141J-142D01*
G01Y1459706D01*
G02X454698Y1459603I-200J-1D01*
G03Y1457641I1642J-981D01*
G02X454726Y1457538I-172J-102D01*
G01Y1456413D01*
G03X454929Y1456210I203J0D01*
G01X455607D01*
G02X455799Y1456064I-1J-200D01*
G01X457594Y1449703D01*
G03X458025Y1448717I3779J1065D01*
G01X458280Y1448301D01*
G02X458310Y1448196I-170J-105D01*
G01Y1328152D01*
G03X458369Y1328010I200J0D01*
G01X482296Y1304083D01*
G02X482339Y1303866I-142J-141D01*
G01X482316Y1303809D01*
X482215Y1303742D01*
X462700D01*
G02X462500Y1303942I0J200D01*
G01Y1310617D01*
G03X462441Y1310759I-200J0D01*
G01X457159Y1316041D01*
G02X457100Y1316183I141J142D01*
G01Y1318817D01*
G03X457041Y1318959I-200J0D01*
G01X438159Y1337841D01*
G03X438017Y1337900I-142J-141D01*
G01X428083D01*
G02X427941Y1337959I0J200D01*
G01X416959Y1348941D01*
G02X416900Y1349083I141J142D01*
G01Y1354417D01*
G03X416841Y1354559I-200J0D01*
G01X411759Y1359641D01*
G03X411617Y1359700I-142J-141D01*
G01X409809D01*
G02X409677Y1359750I0J200D01*
G03X408144Y1360326I-1533J-1752D01*
G01X399857D01*
G02X399715Y1360385I0J200D01*
G01X392594Y1367506D01*
G02X392540Y1367691I141J142D01*
G01X392614Y1368020D01*
G02X392742Y1368165I195J-43D01*
G03X393736Y1369579I-509J1414D01*
G03X392234Y1371081I-1502J0D01*
G03X390877Y1370223I0J-1502D01*
G01X390856Y1370179D01*
X390780Y1370121D01*
X390363Y1370046D01*
X390271Y1370075D01*
X390237Y1370108D01*
G03X389675Y1370454I-1049J-1075D01*
G01X389631Y1370469D01*
X389159Y1370941D01*
G02X389100Y1371083I141J142D01*
G01Y1390825D01*
G02X389300Y1391025I200J0D01*
G01X390081D01*
G02X390247Y1390938I1J-200D01*
G01X390433Y1390664D01*
G02X390454Y1390479I-165J-112D01*
G03X390350Y1389931I1398J-549D01*
G03X393354I1502J0D01*
G03X393250Y1390479I-1502J-1D01*
G01X393232Y1390526D01*
X393243Y1390622D01*
X393457Y1390938D01*
G02X393623Y1391025I165J-113D01*
G01X394048D01*
G02X394217Y1390932I0J-200D01*
G01X394398Y1390648D01*
G02X394410Y1390455I-169J-107D01*
G03X394268Y1389818I1360J-638D01*
G01Y1389817D01*
G03X397272I1502J0D01*
G03X396780Y1390929I-1503J0D01*
G01X396750Y1390956D01*
X396716Y1391030D01*
X396708Y1391361D01*
G02X396767Y1391508I200J5D01*
G01X397452Y1392193D01*
Y1392359D01*
X397433Y1392378D01*
X397403Y1392451D01*
Y1397955D01*
G02X397483Y1398115I200J0D01*
G01X397740Y1398306D01*
G02X397916Y1398338I120J-160D01*
G03X398339Y1398277I424J1441D01*
G01X398340D01*
G03Y1401281I0J1502D01*
G03X397073Y1400585I0J-1501D01*
G01Y1400584D01*
G02X396926Y1400494I-168J109D01*
G01X396615Y1400459D01*
G02X396452Y1400517I-21J199D01*
G01X395740Y1401229D01*
G02X395681Y1401371I141J142D01*
G01Y1402926D01*
G02X395740Y1403068I200J0D01*
G01X395743Y1403071D01*
X395773Y1403144D01*
Y1420070D01*
G02X395973Y1420270I200J0D01*
G01X396744D01*
G03X396886Y1420329I0J200D01*
G01X398535Y1421978D01*
G03X398594Y1422120I-141J142D01*
G01Y1424236D01*
G03X398535Y1424378I-200J0D01*
G01X395832Y1427081D01*
G02X395773Y1427223I141J142D01*
G01Y1429244D01*
G03X395714Y1429386I-200J0D01*
G01X390775Y1434326D01*
G02X390716Y1434468I141J142D01*
G01Y1443823D01*
G03X390658Y1443963I-200J-1D01*
G01X390634Y1443988D01*
G02X390576Y1444128I142J141D01*
G01Y1535581D01*
G02X390650Y1535736I200J0D01*
G03Y1538064I-950J1164D01*
G02X390576Y1538219I126J155D01*
G01Y1538788D01*
G02X390667Y1538955I200J-1D01*
G01X390947Y1539138D01*
G02X391136Y1539154I109J-167D01*
G03X391740Y1539027I604J1375D01*
G03Y1542031I0J1502D01*
G03X391136Y1541904I0J-1502D01*
G01X391089Y1541884D01*
X390989Y1541892D01*
X390667Y1542103D01*
G02X390576Y1542270I109J168D01*
G01Y1543888D01*
G02X390667Y1544055I200J-1D01*
G01X390947Y1544238D01*
G02X391136Y1544254I109J-167D01*
G03X391740Y1544127I604J1375D01*
G03Y1547131I0J1502D01*
G03X391136Y1547004I0J-1502D01*
G01X391089Y1546984D01*
X390989Y1546992D01*
X390667Y1547203D01*
G02X390576Y1547370I109J168D01*
G01Y1548988D01*
G02X390667Y1549155I200J-1D01*
G01X390947Y1549338D01*
G02X391136Y1549354I109J-167D01*
G03X391740Y1549227I604J1375D01*
G03Y1552231I0J1502D01*
G03X391136Y1552104I0J-1502D01*
G01X391089Y1552084D01*
X390989Y1552092D01*
X390667Y1552303D01*
G02X390576Y1552470I109J168D01*
G01Y1554088D01*
G02X390667Y1554255I200J-1D01*
G01X390947Y1554438D01*
G02X391136Y1554454I109J-167D01*
G03X391740Y1554327I604J1375D01*
G03X393242Y1555829I0J1502D01*
G03X392568Y1557082I-1502J0D01*
G01X392531Y1557107D01*
X392484Y1557184D01*
X392448Y1557537D01*
G02X392506Y1557698I199J19D01*
G01X394477Y1559670D01*
X394601Y1559691D01*
X394658Y1559664D01*
G03X395295Y1559522I638J1360D01*
G01X395296D01*
G03X396767Y1560720I0J1502D01*
G02X396963Y1560880I196J-40D01*
G01X398729D01*
G02X398925Y1560720I0J-200D01*
G03X401867I1471J304D01*
G02X402063Y1560880I196J-40D01*
G01X403829D01*
G02X404025Y1560720I0J-200D01*
G03X406967I1471J304D01*
G02X407163Y1560880I196J-40D01*
G01X408929D01*
G02X409125Y1560720I0J-200D01*
G03X412067I1471J304D01*
G02X412263Y1560880I196J-40D01*
G01X419849D01*
G03X419991Y1560939I0J200D01*
G01X424147Y1565095D01*
G03X424206Y1565237I-141J142D01*
G01Y1572046D01*
G03X424147Y1572188I-200J0D01*
G01X422227Y1574109D01*
G03X422085Y1574168I-142J-141D01*
G01X387381D01*
G03X387239Y1574109I0J-200D01*
G01X372917Y1559787D01*
G03X372858Y1559645I141J-142D01*
G01Y1452724D01*
G02X372735Y1452540I-200J0D01*
G01X372679Y1452516D01*
X372560Y1452540D01*
X369285Y1455815D01*
G02X369226Y1455957I141J142D01*
G01Y1508999D01*
G03X368545Y1510644I-2327J0D01*
G01X365399Y1513790D01*
G03X364704Y1514269I-1646J-1644D01*
G01X364670Y1514284D01*
X364635Y1514319D01*
G02X364576Y1514461I141J142D01*
G01Y1515545D01*
G03X364517Y1515687I-200J0D01*
G01X364488Y1515716D01*
Y1548359D01*
G03X364429Y1548501I-200J0D01*
G01X354073Y1558858D01*
G02X354014Y1559000I141J142D01*
G01Y1559901D01*
G02X354042Y1560004I200J1D01*
G03Y1561966I-1642J981D01*
G02X354014Y1562069I172J102D01*
G01Y1565019D01*
G02X354042Y1565122I200J1D01*
G03Y1567084I-1642J981D01*
G02X354014Y1567187I172J102D01*
G01Y1568313D01*
G03X353811Y1568516I-203J0D01*
G01X352490D01*
G02X352290Y1568716I0J200D01*
G01Y1574149D01*
G02X352345Y1574287I200J0D01*
G01X352427Y1574372D01*
G02X352555Y1574434I146J-137D01*
G03Y1578244I-154J1905D01*
G02X352427Y1578306I18J199D01*
G01X352345Y1578391D01*
G02X352290Y1578529I145J138D01*
G01Y1579267D01*
G02X352345Y1579405I200J0D01*
G01X352427Y1579490D01*
G02X352555Y1579552I146J-137D01*
G03X354313Y1581457I-153J1905D01*
G03X352401Y1583369I-1912J0D01*
G01X352399D01*
G03X352207Y1583359I3J-1912D01*
G02X352001Y1583483I-20J199D01*
G03X351491Y1584378I-3637J-1479D01*
G02X351478Y1584397I158J122D01*
G03X351104Y1584819I-1291J-767D01*
G02X351085Y1584836I124J157D01*
G01X349361Y1586560D01*
G03X347282Y1587648I-2777J-2776D01*
G02X347144Y1587746I36J197D01*
G03X343742Y1589714I-3403J-1959D01*
G01X343740D01*
G03X342165Y1589385I-2J-3926D01*
G02X342020Y1589379I-80J183D01*
G03X341529Y1589462I-492J-1419D01*
G01X341527D01*
G03X340025Y1587960I0J-1502D01*
G01Y1587959D01*
G03X340117Y1587441I1502J0D01*
G02X340114Y1587295I-187J-69D01*
G03X339814Y1585790I3626J-1505D01*
G01Y1584280D01*
G03X339869Y1583627I3926J2D01*
G02X339802Y1583441I-197J-34D01*
G01X339541Y1583218D01*
G02X339349Y1583180I-130J152D01*
G03X338611Y1583348I-1236J-3727D01*
G02X338464Y1583445I25J198D01*
G03X335078Y1585384I-3386J-1987D01*
G03X333652Y1585116I0J-3928D01*
G02X333438Y1585161I-73J186D01*
G01X332038Y1586560D01*
G03X329959Y1587648I-2777J-2776D01*
G02X329821Y1587746I36J197D01*
G03X326419Y1589714I-3403J-1959D01*
G01X326417D01*
G03X324842Y1589385I-1J-3927D01*
G02X324697Y1589379I-80J183D01*
G03X324206Y1589462I-492J-1419D01*
G01X324204D01*
G03X322702Y1587960I0J-1502D01*
G01Y1587959D01*
G03X322794Y1587441I1502J0D01*
G02X322791Y1587295I-187J-69D01*
G03X322490Y1585788I3626J-1508D01*
G01Y1584284D01*
G03X322546Y1583627I3927J4D01*
G01X322555Y1583575D01*
X322519Y1583477D01*
X322179Y1583184D01*
X322076Y1583164D01*
X322026Y1583181D01*
G03X321289Y1583348I-1232J-3728D01*
G02X321142Y1583445I25J198D01*
G03X317756Y1585384I-3386J-1987D01*
G03X316330Y1585115I2J-3927D01*
G01X316329D01*
G02X316116Y1585160I-72J187D01*
G01X314715Y1586560D01*
G03X312636Y1587648I-2777J-2776D01*
G02X312498Y1587746I36J197D01*
G03X309096Y1589714I-3403J-1959D01*
G01X309094D01*
G03X307519Y1589385I-2J-3926D01*
G02X307374Y1589379I-80J183D01*
G03X306883Y1589462I-492J-1419D01*
G01X306881D01*
G03X305379Y1587960I0J-1502D01*
G01Y1587959D01*
G03X305471Y1587441I1502J0D01*
G02X305468Y1587295I-187J-69D01*
G03X305168Y1585790I3626J-1505D01*
G01Y1584280D01*
G03X305223Y1583627I3926J2D01*
G01X305232Y1583575D01*
X305196Y1583477D01*
X304856Y1583184D01*
X304753Y1583164D01*
X304703Y1583181D01*
G03X303966Y1583348I-1232J-3728D01*
G02X303819Y1583445I25J198D01*
G03X300433Y1585384I-3386J-1987D01*
G03X299007Y1585115I2J-3927D01*
G01X299006D01*
G02X298793Y1585160I-72J187D01*
G01X297392Y1586560D01*
G03X295313Y1587648I-2777J-2776D01*
G02X295175Y1587746I36J197D01*
G03X291773Y1589714I-3403J-1959D01*
G01X291771D01*
G03X290196Y1589385I-1J-3927D01*
G02X290051Y1589379I-80J183D01*
G03X289560Y1589462I-492J-1419D01*
G01X289558D01*
G03X288056Y1587960I0J-1502D01*
G01Y1587959D01*
G03X288148Y1587441I1502J0D01*
G02X288145Y1587295I-187J-69D01*
G03X287844Y1585788I3626J-1508D01*
G01Y1584284D01*
G03X287900Y1583627I3927J4D01*
G01X287909Y1583575D01*
X287873Y1583477D01*
X287533Y1583184D01*
X287430Y1583164D01*
X287380Y1583181D01*
G03X286643Y1583348I-1232J-3728D01*
G02X286496Y1583445I25J198D01*
G03X283110Y1585384I-3386J-1987D01*
G03X281534Y1585054I0J-3928D01*
G02X281389Y1585048I-80J183D01*
G03X280897Y1585131I-492J-1417D01*
G03X279395Y1583629I0J-1502D01*
G01Y1583628D01*
G03X279487Y1583110I1502J0D01*
G02X279484Y1582964I-187J-69D01*
G03X279184Y1581459I3626J-1505D01*
G01Y1579950D01*
G03X279314Y1578949I3926J1D01*
G02Y1578847I-193J-51D01*
G03X279184Y1577846I3796J-1002D01*
G01Y1576338D01*
G03X279484Y1574832I3927J-1D01*
G02X279487Y1574686I-184J-77D01*
G03X279395Y1574168I1410J-518D01*
G01Y1574167D01*
G03X280897Y1572665I1502J0D01*
G01X280898D01*
G03X280951Y1572666I-2J1502D01*
G02X281131Y1572366I7J-200D01*
G03X280824Y1571223I1979J-1144D01*
G01Y1571221D01*
G03X282545Y1569006I2286J0D01*
G02X282696Y1568812I-49J-194D01*
G01Y1568716D01*
G02X282496Y1568516I-200J0D01*
G01X281700D01*
G03X281498Y1568313I0J-202D01*
G01Y1567187D01*
G02X281470Y1567084I-200J-1D01*
G03X281198Y1566103I1640J-983D01*
G03X281470Y1565122I1912J2D01*
G02X281498Y1565019I-172J-102D01*
G01Y1562069D01*
G02X281470Y1561966I-200J-1D01*
G03X281198Y1560985I1640J-983D01*
G03X281470Y1560004I1912J2D01*
G02X281498Y1559901I-172J-102D01*
G01Y1558775D01*
G03X281700Y1558572I203J0D01*
G01X282496D01*
G02X282696Y1558372I0J-200D01*
G01Y1558351D01*
G02X282681Y1558274I-200J-1D01*
G01X282657Y1558217D01*
G02X282614Y1558152I-185J76D01*
G01X282581Y1558119D01*
G02X282496Y1558069I-141J142D01*
G01X282494Y1558068D01*
G03X280909Y1556484I616J-2201D01*
G01Y1556482D01*
X280908Y1556481D01*
G02X280858Y1556396I-192J56D01*
G01X278384Y1553922D01*
G02X278354Y1553897I-142J140D01*
G01X264195Y1544437D01*
G03X263600Y1543948I2183J-3263D01*
G01X253297Y1533645D01*
G03X252955Y1533256I2771J-2781D01*
G01X252923Y1533213D01*
X252824Y1533172D01*
X252425Y1533226D01*
G02X252267Y1533348I27J198D01*
G03X250876Y1534284I-1391J-566D01*
G03Y1531280I0J-1502D01*
G03X251312Y1531345I-1J1502D01*
G01X251313D01*
G02X251519Y1531288I58J-191D01*
G01X251762Y1531020D01*
G02X251799Y1530809I-148J-135D01*
G01X249357Y1524917D01*
G02X249314Y1524852I-185J76D01*
G01X247888Y1523426D01*
G03X247829Y1523284I141J-142D01*
G01Y1521268D01*
G02X247814Y1521191I-200J-1D01*
G01X247209Y1519733D01*
G03X246929Y1518614I3628J-1502D01*
G01X246927Y1518593D01*
G02X246815Y1518433I-199J20D01*
G01X246461Y1518261D01*
X246357Y1518268D01*
X246313Y1518296D01*
G03X245500Y1518535I-813J-1263D01*
G03Y1515531I0J-1502D01*
G03X246051Y1515636I-1J1502D01*
G01X246100Y1515655D01*
X246202Y1515641D01*
X246517Y1515404D01*
G02X246596Y1515224I-120J-160D01*
G01X243926Y1488091D01*
G02X243868Y1487969I-199J20D01*
G01X241110Y1485211D01*
G03X241051Y1485069I141J-142D01*
G01Y1458882D01*
G02X241050Y1458862I-200J0D01*
G01X240289Y1451120D01*
G02X240276Y1451068I-199J22D01*
G01X221739Y1403020D01*
G02X221553Y1402892I-187J72D01*
G01X211014D01*
G02X210814Y1403092I0J200D01*
G01Y1409042D01*
G03X210515Y1410544I-3927J-1D01*
G01X209673Y1412578D01*
G03X209310Y1413257I-3628J-1503D01*
G01X208244Y1414853D01*
G03X208014Y1415163I-3265J-2182D01*
G01X183469Y1445070D01*
G02X183424Y1445197I155J126D01*
G01Y1513168D01*
G02X183483Y1513310I200J0D01*
G01X183730Y1513557D01*
G03X183789Y1513699I-141J142D01*
G01Y1549888D01*
G03X183730Y1550030I-200J0D01*
G01X182630Y1551130D01*
G02X182571Y1551272I141J142D01*
G01Y1637276D01*
G02X182630Y1637418I200J0D01*
G01X187451Y1642239D01*
G02X187593Y1642298I142J-141D01*
G01X206968D01*
G02X207110Y1642239I0J-200D01*
G01X208351Y1640997D01*
G02X208410Y1640855I-141J-142D01*
G01Y1552275D01*
G03X208469Y1552133I200J0D01*
G01X208752Y1551850D01*
G03X208894Y1551791I142J141D01*
G01X261719D01*
G03X261861Y1551850I0J200D01*
G01X262235Y1552224D01*
G03X262294Y1552366I-141J142D01*
G01Y1639838D01*
G02X262353Y1639980I200J0D01*
G01X264612Y1642239D01*
G02X264754Y1642298I142J-141D01*
G01X555010D01*
G02X555210Y1642098I0J-200D01*
G01Y1552383D01*
G03X555513Y1552080I303J0D01*
G01X605156D01*
G02X605356Y1551880I0J-200D01*
G37*
G36*
G01X371504Y1316010D02*
X371503Y1316011D01*
G03X370202Y1316566I-1301J-1247D01*
G03X368400Y1314764I0J-1802D01*
G01Y1311364D01*
G03X370202Y1309562I1802J0D01*
G03X371503Y1310117I0J1802D01*
G01X371504Y1310118D01*
G02X371722Y1310164I143J-140D01*
G01X372067Y1310025D01*
G02X372192Y1309840I-75J-185D01*
G01Y1214319D01*
G03X372251Y1214177I200J0D01*
G01X377781Y1208647D01*
G02X377834Y1208545I-143J-139D01*
G02X377838Y1208507I-196J-40D01*
G01Y1174647D01*
G02X377793Y1174521I-200J0D01*
G02X377780Y1174506I-157J123D01*
G01X371795Y1168521D01*
G03X371736Y1168379I141J-142D01*
G01Y1157406D01*
G02X371691Y1157280I-200J0D01*
G02X371678Y1157265I-157J123D01*
G01X359588Y1145175D01*
G02X359521Y1145131I-141J142D01*
G01X359487Y1145117D01*
X330927D01*
G03X330785Y1145058I0J-200D01*
G01X330680Y1144953D01*
G02X330398I-141J142D01*
G01X329529Y1145822D01*
G02X329485Y1145889I142J141D01*
G01X329471Y1145923D01*
Y1165022D01*
G02X329475Y1165061I200J-1D01*
G02X329528Y1165162I196J-39D01*
G01X333382Y1169016D01*
G02X333484Y1169069I139J-143D01*
G02X333522Y1169073I40J-196D01*
G01X351258D01*
G02X351277Y1169072I-1J-200D01*
G02X351417Y1168996I-18J-200D01*
G02X351430Y1168975I-163J-115D01*
G01X351606Y1168681D01*
G02X351612Y1168670I-172J-101D01*
G02X351618Y1168499I-178J-92D01*
G01X351610Y1168484D01*
G03X351429Y1167770I1322J-715D01*
G01Y1167768D01*
G03X354433I1502J0D01*
G01X354434D01*
G03X354252Y1168484I-1503J-1D01*
G01X354246Y1168496D01*
G02X354250Y1168670I182J83D01*
G02X354256Y1168681I178J-90D01*
G01X354432Y1168975D01*
G02X354445Y1168996I176J-94D01*
G02X354585Y1169072I158J-124D01*
G02X354604Y1169073I20J-199D01*
G01X356277D01*
G02X356296Y1169072I-1J-200D01*
G02X356436Y1168996I-18J-200D01*
G02X356449Y1168975I-163J-115D01*
G01X356625Y1168681D01*
G02X356631Y1168670I-172J-101D01*
G02X356637Y1168499I-178J-92D01*
G01X356629Y1168484D01*
G03X356448Y1167770I1322J-715D01*
G01Y1167768D01*
G03X359452I1502J0D01*
G03X358261Y1169238I-1503J0D01*
G02X358181Y1169283I55J192D01*
G01X358180D01*
G02X358125Y1169368I135J148D01*
G01X358066Y1169570D01*
X358025Y1169710D01*
G02X358023Y1169717I191J58D01*
G01Y1169719D01*
G02X358042Y1169863I194J48D01*
G02X358076Y1169908I175J-97D01*
G01X368543Y1180375D01*
G02X368658Y1180432I142J-141D01*
G03X368989Y1180516I-202J1490D01*
G03X368993Y1180518I-87J179D01*
G01X368996Y1180519D01*
X369025Y1180530D01*
X370001D01*
G02X370143Y1180471I0J-200D01*
G01X370275Y1180339D01*
G02X370334Y1180197I-141J-142D01*
G01Y1177556D01*
G02X370275Y1177415I-200J1D01*
G01X369029Y1176168D01*
G03X368970Y1176027I141J-142D01*
G01Y1174315D01*
G03X369029Y1174174I200J1D01*
G01X370239Y1172964D01*
G03X370380Y1172905I142J141D01*
G01X372092D01*
G03X372233Y1172964I-1J200D01*
G01X374807Y1175538D01*
G03X374866Y1175679I-141J142D01*
G01Y1199641D01*
G03X374807Y1199782I-200J-1D01*
G01X368508Y1206081D01*
G03X368367Y1206140I-142J-141D01*
G01X359385D01*
X359377D01*
G03X359301Y1206142I-99J-2304D01*
G01X340253D01*
G02X340148Y1206188I24J198D01*
G01X338498Y1207838D01*
G03X338468Y1207867I-1618J-1644D01*
G02X338464Y1207871I139J143D01*
G01X334466Y1211868D01*
X333379Y1212955D01*
G03X333237Y1213014I-142J-141D01*
G01X326199D01*
G02X326050Y1213080I0J200D01*
G01X325851Y1213301D01*
G02X325801Y1213455I149J134D01*
G01Y1213456D01*
G03X325808Y1213582I-1195J130D01*
G03X324606Y1214784I-1202J0D01*
G03X324489Y1214778I3J-1202D01*
G01X324487D01*
X324445Y1214774D01*
X324367Y1214800D01*
X324115Y1215028D01*
G02X324049Y1215177I134J148D01*
G01Y1217487D01*
G02X324108Y1217629I200J0D01*
G01X324310Y1217831D01*
G02X324452Y1217890I142J-141D01*
G01X326476D01*
G03Y1220494I0J1302D01*
G01X326199D01*
G02X326050Y1220560I0J200D01*
G01X325851Y1220781D01*
G02X325801Y1220935I149J134D01*
G01Y1220936D01*
G03X325808Y1221062I-1195J130D01*
G03X324606Y1222264I-1202J0D01*
G03X324491Y1222259I-5J-1202D01*
G01X324449Y1222255D01*
X324369Y1222281D01*
X324119Y1222508D01*
G02X324053Y1222657I134J148D01*
G01Y1225001D01*
G02X324112Y1225143I200J0D01*
G01X324280Y1225311D01*
G02X324422Y1225370I142J-141D01*
G01X326476D01*
G03Y1227976I0J1303D01*
G01X326199D01*
G02X326050Y1228042I0J200D01*
G01X325851Y1228263D01*
G02X325801Y1228417I149J134D01*
G01Y1228418D01*
G03X325808Y1228543I-1195J130D01*
G03X324606Y1229745I-1202J0D01*
G03X323431Y1228794I0J-1201D01*
G02X323420Y1228760I-195J44D01*
G02X323060Y1228740I-185J76D01*
G03X323025Y1228786I-175J-97D01*
G01X323024Y1228787D01*
X320130Y1231681D01*
G03X319988Y1231740I-142J-141D01*
G01X319405D01*
G02X319263Y1231799I0J200D01*
G01X319131Y1231931D01*
G03X318411Y1232419I-1631J-1631D01*
G02X318295Y1232557I79J184D01*
G03X317125Y1233485I-1170J-274D01*
G03X316010Y1232732I0J-1202D01*
G01Y1232731D01*
G02X315824Y1232606I-185J75D01*
G01X314793D01*
G02X314605Y1232736I-1J200D01*
G03X312165I-1220J-453D01*
G02X311977Y1232606I-187J70D01*
G01X310946D01*
G02X310760Y1232731I-1J200D01*
G01Y1232732D01*
G03X308530I-1115J-449D01*
G01Y1232731D01*
G02X308344Y1232606I-185J75D01*
G01X307313D01*
G02X307125Y1232736I-1J200D01*
G03X304685I-1220J-453D01*
G02X304497Y1232606I-187J70D01*
G01X303466D01*
G02X303280Y1232731I-1J200D01*
G01Y1232732D01*
G03X301050I-1115J-449D01*
G01Y1232731D01*
G02X300864Y1232606I-185J75D01*
G01X299833D01*
G02X299645Y1232736I-1J200D01*
G03X297205I-1220J-453D01*
G02X297017Y1232606I-187J70D01*
G01X295986D01*
G02X295800Y1232731I-1J200D01*
G01Y1232732D01*
G03X293570I-1115J-449D01*
G01Y1232731D01*
G02X293384Y1232606I-185J75D01*
G01X292352D01*
G02X292164Y1232736I-1J200D01*
G03X289724I-1220J-453D01*
G02X289536Y1232606I-187J70D01*
G01X288505D01*
G02X288319Y1232731I-1J200D01*
G01Y1232732D01*
G03X286089I-1115J-449D01*
G01Y1232731D01*
G02X285903Y1232606I-185J75D01*
G01X284872D01*
G02X284684Y1232736I-1J200D01*
G03X282244I-1220J-453D01*
G02X282056Y1232606I-187J70D01*
G01X281025D01*
G02X280839Y1232731I-1J200D01*
G01Y1232732D01*
G03X279724Y1233485I-1115J-449D01*
G03X278593Y1232689I0J-1201D01*
G02X278444Y1232561I-188J68D01*
G03X277269Y1231931I456J-2261D01*
G01X276369Y1231031D01*
G03X275735Y1229835I1631J-1631D01*
G02X275602Y1229683I-197J38D01*
G03X274782Y1228543I382J-1140D01*
G03X275563Y1227417I1202J0D01*
G01X275564D01*
G02X275694Y1227229I-70J-187D01*
G01Y1226117D01*
G02X275564Y1225929I-200J-1D01*
G01X275563D01*
G03Y1223677I421J-1126D01*
G01X275564D01*
G02X275694Y1223489I-70J-187D01*
G01Y1222482D01*
G02X275559Y1222292I-200J-1D01*
G03X274682Y1221062I424J-1230D01*
G01Y1221060D01*
G03X274701Y1220840I1302J2D01*
G02X274513Y1220606I-197J-34D01*
G01X272489D01*
G03X272347Y1220547I0J-200D01*
G01X271068Y1219268D01*
X271021Y1219241D01*
X271000Y1219236D01*
G03X270899Y1219181I41J-196D01*
G01X270599Y1218881D01*
X270585Y1218871D01*
G03X270265Y1218605I1308J-1899D01*
G01X269333Y1217673D01*
G02X269306Y1217671I-28J198D01*
G01X250746D01*
G02X250620Y1217716I0J200D01*
G02X250605Y1217729I123J157D01*
G01X250035Y1218299D01*
G02X249991Y1218366I142J141D01*
G01X249977Y1218400D01*
Y1219607D01*
G02X250127Y1219801I200J0D01*
G03Y1222323I-324J1261D01*
G02X249977Y1222517I50J194D01*
G01Y1223348D01*
G02X250127Y1223542I200J0D01*
G03Y1226064I-324J1261D01*
G02X249977Y1226258I50J194D01*
G01Y1227088D01*
G02X250127Y1227282I200J0D01*
G03Y1229804I-324J1261D01*
G02X249977Y1229998I50J194D01*
G01Y1230932D01*
G02X250123Y1231125I200J0D01*
G01X250124D01*
G03X251005Y1232283I-321J1158D01*
G03X250996Y1232425I-1202J-5D01*
G01Y1232427D01*
X250991Y1232473D01*
X251023Y1232561D01*
X251323Y1232848D01*
X251412Y1232876D01*
X251442Y1232871D01*
G03X251674Y1232850I233J1282D01*
G03X252976Y1234151I0J1302D01*
G01Y1237893D01*
G03X251674Y1239196I-1303J0D01*
G01X251672D01*
G03X251538Y1239189I1J-1303D01*
G02X251376Y1239246I-21J199D01*
G01X251123Y1239498D01*
X251093Y1239583D01*
X251098Y1239628D01*
G03X251105Y1239763I-1295J135D01*
G03X250127Y1241024I-1302J0D01*
G02X249977Y1241218I50J194D01*
G01Y1241772D01*
G02X249981Y1241811I200J-1D01*
G02X250034Y1241912I196J-39D01*
G01X250581Y1242459D01*
X250591Y1242467D01*
G03X250839Y1242715I-788J1036D01*
G01X250847Y1242725D01*
X251675Y1243553D01*
G02X251879Y1243601I141J-142D01*
G01X252219Y1243489D01*
G02X252354Y1243328I-63J-190D01*
G03X253543Y1242301I1189J175D01*
G03X254745Y1243503I0J1202D01*
G01Y1243505D01*
G03X254685Y1243879I-1202J-1D01*
G01X254675Y1243909D01*
Y1243941D01*
G02X254875Y1244141I200J0D01*
G01X254947D01*
G02X254974Y1244139I-1J-200D01*
G01X255014Y1244133D01*
X255023Y1244131D01*
G03X255403Y1244070I394J1241D01*
G01X255410D01*
G03X255969Y1243288I3368J1817D01*
G02X256017Y1243199I-146J-136D01*
G03X256979Y1242237I1266J304D01*
G02X257068Y1242189I-47J-194D01*
G03X257567Y1241799I2598J2810D01*
G02X257635Y1241725I-109J-168D01*
G03X259596Y1239952I3388J1777D01*
G02X259721Y1239767I-75J-185D01*
G01Y1239763D01*
G03X262325I1302J0D01*
G01Y1239767D01*
G02X262450Y1239952I200J0D01*
G03X263199Y1240355I-1428J3551D01*
G02X263257Y1240382I112J-165D01*
G03X264144Y1241269I-364J1251D01*
G02X264171Y1241327I192J-54D01*
G03X264400Y1241703I-3148J2175D01*
G01X264420Y1241741D01*
X264487Y1241793D01*
X264861Y1241884D01*
X264944Y1241869D01*
X264979Y1241845D01*
G03X265047Y1241799I2178J3146D01*
G02X265115Y1241725I-109J-168D01*
G03X267076Y1239952I3388J1777D01*
G02X267201Y1239767I-75J-185D01*
G01Y1239763D01*
G03X269805I1302J0D01*
G01Y1239767D01*
G02X269930Y1239952I200J0D01*
G03X270677Y1240355I-1432J3548D01*
G02X270735Y1240383I115J-164D01*
G03X271625Y1241272I-360J1251D01*
G02X271652Y1241330I192J-54D01*
G03X271880Y1241704I-3148J2175D01*
G01X271900Y1241742D01*
X271967Y1241794D01*
X272299Y1241875D01*
G02X272460Y1241845I47J-194D01*
G03X272528Y1241799I2178J3146D01*
G02X272596Y1241725I-109J-168D01*
G03X274557Y1239952I3388J1777D01*
G02X274682Y1239767I-75J-185D01*
G01Y1239763D01*
G03X277286I1302J0D01*
G01Y1239767D01*
G02X277411Y1239952I200J0D01*
G03X278160Y1240355I-1428J3551D01*
G02X278218Y1240382I112J-165D01*
G03X279105Y1241269I-364J1251D01*
G02X279132Y1241327I192J-54D01*
G03X279361Y1241703I-3148J2175D01*
G01X279381Y1241741D01*
X279448Y1241793D01*
X279822Y1241884D01*
X279905Y1241869D01*
X279940Y1241845D01*
G03X280008Y1241799I2178J3146D01*
G02X280076Y1241725I-109J-168D01*
G03X282037Y1239952I3388J1777D01*
G02X282162Y1239767I-75J-185D01*
G01Y1239763D01*
G03X284766I1302J0D01*
G01Y1239767D01*
G02X284891Y1239952I200J0D01*
G03X285640Y1240355I-1428J3551D01*
G02X285698Y1240382I112J-165D01*
G03X286584Y1241269I-365J1250D01*
G02X286612Y1241327I192J-57D01*
G03X286941Y1241905I-3149J2175D01*
G02X287033Y1242000I182J-84D01*
G03X287375Y1242195I-1697J3374D01*
G02X287446Y1242224I110J-167D01*
G03X288483Y1243261I-242J1279D01*
G02X288512Y1243332I196J-39D01*
G03X288829Y1243943I-3179J2037D01*
G01X288831Y1243948D01*
X288840Y1243967D01*
G02X289023Y1244072I176J-95D01*
G01X289024D01*
G03X289074Y1244071I51J1301D01*
G03X289466Y1244132I-2J1302D01*
G01X289495Y1244141D01*
X289612D01*
G02X289812Y1243941I0J-200D01*
G01Y1243909D01*
X289802Y1243879D01*
G03X289742Y1243505I1142J-375D01*
G01Y1243503D01*
G03X292146I1202J0D01*
G03X292137Y1243645I-1202J-5D01*
G01Y1243647D01*
X292132Y1243693D01*
X292164Y1243781D01*
X292464Y1244068D01*
X292553Y1244096D01*
X292588Y1244090D01*
G03X292815Y1244070I227J1282D01*
G03X294118Y1245373I0J1303D01*
G01Y1249116D01*
G03X294098Y1249341I-1303J-2D01*
G01Y1249343D01*
X294093Y1249375D01*
X294120Y1249464D01*
X294375Y1249730D01*
G02X294541Y1249791I145J-138D01*
G01X294542D01*
G03X294685Y1249782I147J1193D01*
G03Y1252186I0J1202D01*
G03X294541Y1252177I3J-1202D01*
G01X294540D01*
G02X294372Y1252237I-24J199D01*
G01X294118Y1252503D01*
X294091Y1252592D01*
X294095Y1252619D01*
G03X294116Y1252854I-1281J233D01*
G03X294094Y1253087I-1302J-5D01*
G01Y1253093D01*
X294090Y1253116D01*
X294118Y1253205D01*
X294372Y1253471D01*
G02X294540Y1253531I144J-139D01*
G01X294541D01*
G03X294685Y1253522I147J1193D01*
G03Y1255926I0J1202D01*
G03X294541Y1255917I3J-1202D01*
G01X294540D01*
G02X294372Y1255977I-24J199D01*
G01X294118Y1256243D01*
X294090Y1256332D01*
X294094Y1256358D01*
G03X294116Y1256594I-1280J238D01*
G03X292814Y1257896I-1302J0D01*
G03X292763Y1257895I0J-1302D01*
G02X292639Y1257933I-7J200D01*
G02X292581Y1257998I117J162D01*
G02X292575Y1258010I176J95D01*
G03X291785Y1259223I-3501J-1416D01*
G02X291772Y1259472I150J133D01*
G01X302979Y1273833D01*
X302984Y1273839D01*
X306417Y1277699D01*
X306423Y1277704D01*
X344841Y1316122D01*
G02X344852Y1316132I140J-143D01*
G01X351727Y1322062D01*
G02X351857Y1322111I131J-151D01*
G01X368294D01*
G02X368333Y1322107I-1J-200D01*
G02X368434Y1322054I-39J-196D01*
G01X372135Y1318353D01*
G02X372188Y1318251I-143J-139D01*
G02X372192Y1318213I-196J-40D01*
G01Y1316288D01*
G02X372067Y1316103I-200J0D01*
G01X371722Y1315964D01*
G02X371504Y1316010I-75J186D01*
G37*
G36*
G01X342382Y54588D02*
X371080D01*
X371204Y54464D01*
Y52932D01*
X370863Y52591D01*
X342382D01*
G03X336445Y46654I0J-5937D01*
G01Y7874D01*
G02X330571Y2000I-5874J0D01*
G01X283327D01*
G02X277453Y7874I0J5874D01*
G01Y46126D01*
X279450D01*
Y7874D01*
G03X283325Y3998I3876J0D01*
G01X330571D01*
G03X334448Y7874I0J3877D01*
G01Y46654D01*
G02X342382Y54588I7934J0D01*
G37*
G36*
G01X299286Y447603D02*
X299157Y447501D01*
X299033Y447404D01*
G02X298953Y447366I-124J157D01*
G01X298907Y447356D01*
X298886Y447361D01*
G03X298507Y447410I-380J-1453D01*
G03Y444406I0J-1502D01*
G03X298862Y444449I-2J1502D01*
G01X298863D01*
G02X298953Y444450I47J-194D01*
G01X298997Y444440D01*
X299214Y444269D01*
G03X299216Y444267I141J139D01*
G01X299286Y444213D01*
G02X299356Y444075I-129J-152D01*
G02X299357Y444060I-199J-21D01*
G01Y443297D01*
G02X299343Y443222I-200J-1D01*
G01X299328Y443186D01*
X297351Y441209D01*
G02X297301Y441173I-140J142D01*
G03X297114Y441054I590J-1133D01*
G02X297067Y441028I-119J160D01*
G01X297054Y441022D01*
G02X296979Y441008I-74J186D01*
G01X296916D01*
X296907Y441007D01*
X296874Y441012D01*
X296771D01*
X296749Y441031D01*
X296737Y441104D01*
Y441105D01*
G03X295253Y442372I-1484J-236D01*
G01X295241D01*
X295209Y442371D01*
G03X294175Y441915I45J-1502D01*
G01X294146Y441886D01*
X294031Y441835D01*
G02X293958Y441821I-73J186D01*
G01X293748D01*
G02X293675Y441835I0J200D01*
G01X293560Y441886D01*
X293531Y441915D01*
G03X292572Y442367I-1079J-1046D01*
G01X292509Y442372D01*
X292453D01*
G03X290969Y441105I0J-1503D01*
G01Y441104D01*
X290957Y441031D01*
X290934Y441012D01*
X290836D01*
G02X290801Y441007I-35J123D01*
G01X290790Y441008D01*
X285407D01*
G02X285352Y441020I-1J127D01*
G03X285074Y441265I-1179J-1057D01*
G02X284989Y441445I115J164D01*
G01X285007Y441688D01*
G02X285038Y441780I199J-16D01*
G01X285051Y441801D01*
X285090Y441836D01*
X285114Y441849D01*
G03X285919Y443180I-698J1331D01*
G03X282915I-1502J0D01*
G03X283527Y441970I1502J0D01*
G01X283528Y441969D01*
G02X283591Y441893I-118J-162D01*
G01X283601Y441871D01*
X283610Y441821D01*
X283590Y441551D01*
G02X283478Y441386I-200J15D01*
G03X282994Y441020I696J-1423D01*
G02X282939Y441008I-54J115D01*
G01X280065D01*
G03X279954Y441002I13J-1277D01*
G01X279931Y441031D01*
X279919Y441059D01*
G03X277139I-1390J-571D01*
G01X277127Y441031D01*
X277101Y440999D01*
G03X276953Y441008I-151J-1269D01*
G01X271604D01*
G02X271530Y441032I0J127D01*
G01X271396Y441134D01*
G03X271341Y441163I-120J-160D01*
G01X271310Y441174D01*
G02X271234Y441222I66J189D01*
G01X269660Y442796D01*
G02X269624Y442846I142J140D01*
G02X269602Y442937I178J91D01*
G01Y457290D01*
G02X269606Y457328I200J-2D01*
G02X269659Y457430I196J-37D01*
G01X269664Y457435D01*
G02X269766Y457488I139J-143D01*
G02X269804Y457492I40J-196D01*
G01X281071D01*
G02X281139Y457480I0J-200D01*
G01X281241Y457441D01*
X281266Y457420D01*
G03X281678Y457175I964J1153D01*
G03X282782I552J1396D01*
G03X283194Y457420I-552J1398D01*
G01X283219Y457441D01*
X283321Y457480D01*
G02X283389Y457492I68J-188D01*
G01X290986D01*
G02X291070Y457474I1J-200D01*
G01X291177Y457424D01*
X291205Y457394D01*
G03X293427I1111J1011D01*
G01X293455Y457424D01*
X293562Y457474D01*
G02X293646Y457492I83J-182D01*
G01X298075D01*
G02X298107Y457489I-3J-200D01*
G01X298109D01*
G02X298215Y457435I-34J-197D01*
G01X299300Y456350D01*
G02X299353Y456248I-143J-139D01*
G02X299357Y456210I-196J-40D01*
G01Y447756D01*
G02X299356Y447741I-200J6D01*
G02X299286Y447603I-199J14D01*
G37*
G36*
G01X312272Y295043D02*
X312329Y295066D01*
X312446Y295043D01*
X314593Y292896D01*
G02X314652Y292755I-141J-142D01*
G01Y250263D01*
G02X314585Y250114I-200J0D01*
G01X314333Y249886D01*
X314253Y249860D01*
X314210Y249865D01*
G03X314053Y249873I-155J-1494D01*
G03Y246869I0J-1502D01*
G03X314210Y246877I2J1502D01*
G01X314253Y246882D01*
X314333Y246856D01*
X314585Y246628D01*
G02X314652Y246479I-133J-149D01*
G01Y246411D01*
G02X314593Y246270I-200J1D01*
G01X313700Y245378D01*
G03X313330Y244485I897J-895D01*
G01Y211771D01*
G02X313271Y211630I-200J1D01*
G01X312437Y210797D01*
G02X312155I-141J141D01*
G01X305503Y217448D01*
G02X305444Y217589I141J142D01*
G01Y222776D01*
G02X305533Y222942I200J0D01*
G01X305851Y223156D01*
X305949Y223165D01*
X305996Y223146D01*
G03X306564Y223034I569J1390D01*
G01X306566D01*
G03X308020Y224160I0J1502D01*
G01X308027Y224187D01*
X308053Y224232D01*
X308704Y224882D01*
G03X309074Y225775I-897J895D01*
G01Y226920D01*
G03X310145Y227800I-509J1711D01*
G01X310882Y228537D01*
Y233610D01*
X310737Y233755D01*
Y257442D01*
X312148Y258853D01*
Y261795D01*
Y294858D01*
G02X312272Y295043I200J0D01*
G37*
G36*
G01X373478Y529585D02*
X404019D01*
G02X404161Y529526I0J-200D01*
G01X409697Y523990D01*
G03X409839Y523931I142J141D01*
G01X468115D01*
G02X468257Y523872I0J-200D01*
G01X468895Y523234D01*
G02X468954Y523092I-141J-142D01*
G01Y518511D01*
G02X468896Y518370I-200J0D01*
G01X468667Y518141D01*
X468596Y518111D01*
X468555D01*
G03Y515107I3J-1502D01*
G01X468596D01*
X468667Y515077D01*
X468896Y514848D01*
G02X468954Y514707I-142J-141D01*
G01Y501571D01*
G02X468896Y501430I-200J0D01*
G01X468667Y501201D01*
X468596Y501171D01*
X468555D01*
G03Y498167I3J-1502D01*
G01X468596D01*
X468667Y498137D01*
X468896Y497908D01*
G02X468954Y497767I-142J-141D01*
G01Y497571D01*
G02X468896Y497430I-200J0D01*
G01X468667Y497201D01*
X468596Y497171D01*
X468555D01*
G03Y494167I3J-1502D01*
G01X468596D01*
X468667Y494137D01*
X468896Y493908D01*
G02X468954Y493767I-142J-141D01*
G01Y478301D01*
G02X468866Y478135I-200J0D01*
G01X468550Y477922D01*
X468452Y477911D01*
X468406Y477930D01*
G03X467848Y478037I-557J-1395D01*
G03X466663Y477458I0J-1502D01*
G02X466506Y477381I-158J123D01*
G01X466190D01*
G02X466033Y477458I1J200D01*
G03X464848Y478037I-1185J-923D01*
G03Y475033I0J-1502D01*
G03X466033Y475612I0J1502D01*
G02X466190Y475689I158J-123D01*
G01X466506D01*
G02X466663Y475612I-1J-200D01*
G03X467848Y475033I1185J923D01*
G03X468406Y475140I1J1502D01*
G01X468452Y475159D01*
X468550Y475148D01*
X468866Y474935D01*
G02X468954Y474769I-112J-166D01*
G01Y466332D01*
G02X468866Y466166I-200J0D01*
G01X468550Y465953D01*
X468452Y465942D01*
X468406Y465961D01*
G03X467848Y466068I-557J-1395D01*
G03X466663Y465489I0J-1502D01*
G02X466506Y465412I-158J123D01*
G01X466190D01*
G02X466033Y465489I1J200D01*
G03X464848Y466068I-1185J-923D01*
G03Y463064I0J-1502D01*
G03X466033Y463643I0J1502D01*
G02X466190Y463720I158J-123D01*
G01X466506D01*
G02X466663Y463643I-1J-200D01*
G03X467848Y463064I1185J923D01*
G03X468406Y463171I1J1502D01*
G01X468452Y463190D01*
X468550Y463179D01*
X468866Y462966D01*
G02X468954Y462800I-112J-166D01*
G01Y407360D01*
G02X468895Y407218I-200J0D01*
G01X447467Y385790D01*
G03X447084Y384866I923J-924D01*
G01Y383409D01*
X447073Y383362D01*
X447062Y383340D01*
G03X446889Y382641I1329J-700D01*
G03X447440Y381478I1503J0D01*
G01X447476Y381449D01*
X447515Y381365D01*
X447505Y380957D01*
X447463Y380876D01*
X447426Y380848D01*
G03X446821Y379643I898J-1205D01*
G03X449825I1502J0D01*
G03X449274Y380806I-1503J0D01*
G01X449238Y380835D01*
X449199Y380919D01*
X449209Y381327D01*
X449251Y381408D01*
X449288Y381436D01*
G03X449893Y382641I-898J1205D01*
G03X449720Y383340I-1502J-1D01*
G01X449709Y383362D01*
X449698Y383409D01*
Y384242D01*
G02X449756Y384383I200J0D01*
G01X464452Y399080D01*
G02X464670Y399123I141J-142D01*
G01X464727Y399099D01*
X464794Y399000D01*
Y390828D01*
G02X464735Y390687I-200J1D01*
G01X464345Y390297D01*
G03X464286Y390155I141J-142D01*
G01Y373912D01*
G02X464227Y373770I-200J0D01*
G01X458061Y367604D01*
G02X457852Y367557I-142J141D01*
G01X457456Y367699D01*
X457386Y367789D01*
X457380Y367848D01*
G03X455885Y369204I-1495J-146D01*
G03X454383Y367702I0J-1502D01*
G03X455739Y366207I1502J0D01*
G01X455798Y366201D01*
X455888Y366131D01*
X456030Y365735D01*
G02X455983Y365526I-188J-67D01*
G01X455280Y364823D01*
G02X455138Y364764I-142J141D01*
G01X392251D01*
G02X392066Y364887I0J200D01*
G01X392042Y364944D01*
X392066Y365062D01*
X393082Y366077D01*
G03X393638Y367422I-1346J1344D01*
G01Y377581D01*
G03X393636Y377679I-1901J10D01*
G01X393634Y377723D01*
X393666Y377804D01*
X393951Y378074D01*
X394034Y378102D01*
X394078Y378097D01*
G03X394237Y378089I155J1494D01*
G03Y381093I0J1502D01*
G03X392744Y379756I0J-1502D01*
G01X392739Y379712D01*
X392694Y379638D01*
X392369Y379417D01*
X392283Y379403D01*
X392241Y379415D01*
G03X391737Y379482I-500J-1834D01*
G03X389836Y377581I0J-1901D01*
G01Y368292D01*
G02X389777Y368151I-200J1D01*
G01X386448Y364823D01*
G02X386307Y364764I-142J141D01*
G01X336705D01*
G02X336563Y364823I0J200D01*
G01X327428Y373958D01*
G02X327370Y374099I142J141D01*
G01Y427037D01*
G03X326987Y427961I-1306J0D01*
G01X326266Y428682D01*
G02X326207Y428824I141J142D01*
G01Y429646D01*
G03X326148Y429788I-200J0D01*
G01X324819Y431117D01*
G02X324760Y431258I141J142D01*
G01Y448216D01*
G02X324960Y448416I200J0D01*
G01X333751D01*
G03X334675Y448799I0J1306D01*
G01X340811Y454935D01*
G02X340952Y454994I142J-141D01*
G01X343166D01*
G02X343317Y454925I0J-200D01*
G01X343544Y454665D01*
X343568Y454583D01*
X343562Y454539D01*
G03X343548Y454334I1488J-205D01*
G03X345050Y452832I1502J0D01*
G03X345749Y453005I-1J1502D01*
G01X345771Y453016D01*
X345818Y453028D01*
X349034D01*
G03X349958Y453410I1J1306D01*
G01X351082Y454534D01*
G03X351464Y455458I-924J923D01*
G01Y458818D01*
G02X351523Y458959I200J-1D01*
G01X351584Y459021D01*
G02X351867I141J-142D01*
G01X351886Y459002D01*
X351911Y458958D01*
X351919Y458932D01*
G03X353367Y457828I1448J398D01*
G03X354869Y459330I0J1502D01*
G03X354008Y460688I-1501J0D01*
G01X353963Y460709D01*
X353905Y460786D01*
X353841Y461157D01*
G02X353896Y461333I197J35D01*
G01X366294Y473730D01*
G02X366435Y473788I141J-142D01*
G01X372844D01*
G03X373768Y474171I0J1306D01*
G01X385512Y485915D01*
X385554Y485940D01*
X385577Y485948D01*
G03X385626Y485964I-442J1435D01*
G02X385862Y485670I66J-189D01*
G03X385639Y484882I1279J-788D01*
G03X387141Y483380I1502J0D01*
G03X387298Y483388I2J1502D01*
G01X387341Y483393D01*
X387421Y483367D01*
X387673Y483139D01*
G02X387740Y482990I-133J-149D01*
G01Y478982D01*
G03X388122Y478058I1306J-1D01*
G01X392179Y474001D01*
X392204Y473959D01*
X392212Y473936D01*
G03X393646Y472880I1434J446D01*
G03X395148Y474382I0J1502D01*
G03X394092Y475816I-1502J0D01*
G01X394069Y475824D01*
X394027Y475849D01*
X390411Y479465D01*
G02X390352Y479606I141J142D01*
G01Y486162D01*
G03X389970Y487086I-1306J1D01*
G01X368686Y508370D01*
G02X368627Y508512I141J142D01*
G01Y524734D01*
G02X368686Y524876I200J0D01*
G01X373336Y529526D01*
G02X373478Y529585I142J-141D01*
G37*
G36*
G01X321009Y448423D02*
X321806Y449221D01*
G02X322024Y449264I141J-142D01*
G01X322081Y449240D01*
X322148Y449141D01*
Y434271D01*
G02X322024Y434086I-200J0D01*
G01X321967Y434063D01*
X321850Y434086D01*
X321009Y434927D01*
G02X320950Y435068I141J142D01*
G01Y448282D01*
G02X321009Y448423I200J-1D01*
G37*
G36*
G01X341785Y457904D02*
X346204Y462324D01*
G02X346422Y462367I141J-142D01*
G01X346479Y462343D01*
X346546Y462244D01*
Y458076D01*
G02X346487Y457935I-200J1D01*
G01X346217Y457665D01*
G02X346076Y457606I-142J141D01*
G01X341970D01*
G02X341785Y457730I0J200D01*
G01X341762Y457787D01*
X341785Y457904D01*
G37*
G36*
G01X368627Y495358D02*
Y504251D01*
G02X368750Y504435I200J-1D01*
G01X368807Y504459D01*
X368925Y504436D01*
X375708Y497653D01*
G02X375763Y497475I-142J-141D01*
G01X375695Y497102D01*
X375635Y497026D01*
X375589Y497005D01*
G03X374705Y495636I618J-1369D01*
G03X375190Y494530I1502J-1D01*
G02X375255Y494383I-135J-148D01*
G01Y494089D01*
G02X375190Y493942I-200J1D01*
G03X374705Y492836I1017J-1105D01*
G03X377709I1502J0D01*
G03X377224Y493942I-1502J1D01*
G02X377159Y494089I135J148D01*
G01Y494383D01*
G02X377224Y494530I200J-1D01*
G03X377576Y495018I-1018J1105D01*
G01X377597Y495064D01*
X377673Y495124D01*
X378046Y495192D01*
G02X378224Y495137I37J-197D01*
G01X384217Y489143D01*
G02X384275Y488991I-141J-141D01*
G01X384258Y488651D01*
X384219Y488577D01*
X384186Y488549D01*
G03X383697Y487828I945J-1167D01*
G01X383689Y487805D01*
X383664Y487763D01*
X372361Y476460D01*
G02X372220Y476402I-141J142D01*
G01X368195D01*
G02X368030Y476488I-1J200D01*
G01X367815Y476802D01*
X367803Y476898D01*
X367821Y476945D01*
G03X367922Y477486I-1401J541D01*
G03X367552Y478473I-1501J0D01*
G01X367528Y478501D01*
X367503Y478568D01*
Y478904D01*
X367528Y478971D01*
X367552Y478999D01*
G03X367922Y479986I-1131J987D01*
G03X366420Y481488I-1502J0D01*
G03X364947Y480281I0J-1502D01*
G01X364938Y480235D01*
X364881Y480161D01*
X364508Y479981D01*
X364415Y479982D01*
X364372Y480004D01*
G03X363686Y480170I-686J-1336D01*
G03X362184Y478668I0J-1502D01*
G03X362554Y477681I1501J0D01*
G01X362578Y477653D01*
X362603Y477586D01*
Y477250D01*
X362578Y477183D01*
X362554Y477155D01*
G03X362184Y476168I1131J-987D01*
G03X362980Y474842I1502J0D01*
G01X363022Y474820D01*
X363077Y474743D01*
X363131Y474377D01*
G02X363075Y474206I-198J-30D01*
G01X349500Y460631D01*
G02X349282Y460588I-141J142D01*
G01X349225Y460612D01*
X349158Y460711D01*
Y463123D01*
G02X349217Y463264I200J-1D01*
G01X352014Y466061D01*
G03X352396Y466985I-924J923D01*
G01Y469575D01*
G02X352455Y469716I200J-1D01*
G01X354428Y471689D01*
G03X354487Y471831I-141J142D01*
G01Y472206D01*
G02X354567Y472367I200J1D01*
G03X355172Y473571I-897J1205D01*
G03X354802Y474558I-1501J0D01*
G01X354778Y474586D01*
X354753Y474653D01*
Y474989D01*
X354778Y475056D01*
X354802Y475084D01*
G03Y477058I-1131J987D01*
G01X354778Y477086D01*
X354753Y477153D01*
Y477489D01*
X354778Y477556D01*
X354802Y477584D01*
G03Y479558I-1131J987D01*
G01X354778Y479586D01*
X354753Y479653D01*
Y479989D01*
X354778Y480056D01*
X354802Y480084D01*
G03X355172Y481071I-1131J987D01*
G03X354567Y482275I-1502J-1D01*
G02X354487Y482436I120J160D01*
G01Y482937D01*
G02X354687Y483137I200J0D01*
G01X356406D01*
G03X356548Y483196I0J200D01*
G01X368568Y495216D01*
G03X368627Y495358I-141J142D01*
G37*
G36*
G01X368020Y1145535D02*
G03X368557Y1145435I539J1402D01*
G03X368586I14J1502D01*
G02X368598I6J-200D01*
G03X368657Y1145434I55J1502D01*
G03X370160Y1146937I0J1503D01*
G03X369401Y1148243I-1503J0D01*
G02X369323Y1148323I99J174D01*
G01X369311Y1148346D01*
Y1148628D01*
G02X369335Y1148722I200J-1D01*
G01X369352Y1148754D01*
G03X370160Y1150087I-696J1333D01*
G03X369215Y1151483I-1504J0D01*
G01X369166Y1151502D01*
X369100Y1151584D01*
X369046Y1151908D01*
G02X369102Y1152083I197J33D01*
G01X373452Y1156433D01*
G03X373511Y1156575I-141J142D01*
G01Y1167362D01*
G02X373570Y1167504I200J0D01*
G01X379369Y1173303D01*
G03X379428Y1173445I-141J142D01*
G01Y1209045D01*
G03X379369Y1209187I-200J0D01*
G01X373570Y1214986D01*
G02X373511Y1215128I141J142D01*
G01Y1324020D01*
G02X373570Y1324162I200J0D01*
G01X378859Y1329451D01*
G02X379001Y1329510I142J-141D01*
G01X398894D01*
G02X399036Y1329451I0J-200D01*
G01X401478Y1327009D01*
G02X401537Y1326867I-141J-142D01*
G01Y1320274D01*
X401529Y1320245D01*
G03X401465Y1319815I1437J-434D01*
G03X401529Y1319385I1501J4D01*
G01X401537Y1319356D01*
Y1311525D01*
G02X401478Y1311383I-200J0D01*
G01X395683Y1305588D01*
X395583Y1305559D01*
X395533Y1305571D01*
G03X395194Y1305610I-340J-1463D01*
G01X395192D01*
G03X393690Y1304108I0J-1502D01*
G01Y1304106D01*
G03X393729Y1303767I1502J1D01*
G01X393741Y1303717D01*
X393712Y1303617D01*
X391638Y1301543D01*
G03X391579Y1301401I141J-142D01*
G01Y1154701D01*
G02Y1154690I-200J-5D01*
G02X391525Y1154564I-200J11D01*
G02X391516Y1154555I-146J137D01*
G01X391273Y1154327D01*
X391197Y1154299D01*
X391155Y1154302D01*
G03X390359Y1154326I-799J-13278D01*
G01X390354D01*
G03Y1127722I0J-13302D01*
G01X390359D01*
G03X391155Y1127746I-3J13302D01*
G01X391197Y1127749D01*
X391273Y1127721D01*
X391516Y1127493D01*
G02X391525Y1127484I-137J-146D01*
G02X391579Y1127358I-146J-137D01*
G02Y1127347I-200J-6D01*
G01Y1120468D01*
G02X391520Y1120326I-200J0D01*
G01X390138Y1118944D01*
X374984D01*
X372766Y1121162D01*
Y1122217D01*
G03X372501Y1125197I-267J1478D01*
G01X372500D01*
G03X371705Y1124969I1J-1502D01*
G01X371704Y1124968D01*
G02X371502Y1124964I-104J171D01*
G01X371196Y1125133D01*
G02X371093Y1125308I97J175D01*
G01Y1137204D01*
G03X371034Y1137346I-200J0D01*
G01X367535Y1140845D01*
X367506Y1140873D01*
X367476Y1140947D01*
Y1145161D01*
G02X367563Y1145326I200J0D01*
G01X367876Y1145541D01*
X367973Y1145553D01*
X368020Y1145535D01*
G37*
G36*
G01X387796Y1573166D02*
X421670D01*
G02X421812Y1573107I0J-200D01*
G01X423146Y1571773D01*
G02X423205Y1571631I-141J-142D01*
G01Y1565652D01*
G02X423146Y1565510I-200J0D01*
G01X419576Y1561940D01*
G02X419434Y1561881I-142J141D01*
G01X411930D01*
G02X411773Y1561957I0J200D01*
G03X409419I-1177J-933D01*
G02X409262Y1561881I-157J124D01*
G01X406830D01*
G02X406673Y1561957I0J200D01*
G03X404319I-1177J-933D01*
G02X404162Y1561881I-157J124D01*
G01X401730D01*
G02X401573Y1561957I0J200D01*
G03X399219I-1177J-933D01*
G02X399062Y1561881I-157J124D01*
G01X396630D01*
G02X396473Y1561957I0J200D01*
G03X395296Y1562526I-1177J-933D01*
G03X393794Y1561024I0J-1502D01*
G03X393853Y1560608I1502J1D01*
G01X393868Y1560555D01*
X393841Y1560450D01*
X389633Y1556242D01*
G03X389574Y1556100I141J-142D01*
G01Y1538498D01*
X389484Y1538388D01*
X389412Y1538374D01*
G03Y1535426I288J-1474D01*
G01X389484Y1535412D01*
X389574Y1535302D01*
Y1443715D01*
G03X389632Y1443575I200J1D01*
G01X389656Y1443550D01*
G02X389714Y1443410I-142J-141D01*
G01Y1431866D01*
G03X389773Y1431724I200J0D01*
G01X397533Y1423963D01*
G02X397592Y1423821I-141J-142D01*
G01Y1422535D01*
G02X397533Y1422393I-200J0D01*
G01X396471Y1421331D01*
G02X396329Y1421272I-142J141D01*
G01X386734D01*
G02X386568Y1421361I0J200D01*
G01X376874Y1435868D01*
G02X376855Y1435902I164J114D01*
G01X373875Y1443097D01*
G02X373860Y1443173I185J76D01*
G01Y1559230D01*
G02X373919Y1559372I200J0D01*
G01X387654Y1573107D01*
G02X387796Y1573166I142J-141D01*
G37*
G36*
G01X492382Y54588D02*
X520615D01*
X520833Y54370D01*
Y52809D01*
X520615Y52591D01*
X492382D01*
G03X486445Y46654I0J-5937D01*
G01Y7874D01*
G02X480571Y2000I-5874J0D01*
G01X385689D01*
G02X379815Y7874I0J5874D01*
G01Y46160D01*
X381812D01*
Y7874D01*
G03X385687Y3998I3876J0D01*
G01X480571D01*
G03X484448Y7874I0J3877D01*
G01Y46654D01*
G02X492382Y54588I7934J0D01*
G37*
G36*
G01X444867Y795700D02*
X466417D01*
G02X466559Y795641I0J-200D01*
G01X483741Y778459D01*
G02X483800Y778317I-141J-142D01*
G01Y734230D01*
G02X483741Y734088I-200J0D01*
G01X470812Y721159D01*
G03X470753Y721017I141J-142D01*
G01Y609556D01*
G03X470768Y609479I200J-1D01*
G01X470797Y609411D01*
G02X470812Y609334I-185J-76D01*
G01Y526626D01*
G02X470753Y526484I-200J0D01*
G01X469524Y525255D01*
X469496Y525226D01*
X469422Y525196D01*
X411642D01*
G02X411500Y525255I0J200D01*
G01X396421Y540334D01*
Y540355D01*
X379516Y557260D01*
X379487Y557356D01*
X379498Y557407D01*
G03X379526Y557678I-1278J269D01*
G01Y696096D01*
G02X379585Y696237I200J-1D01*
G01X385026Y701678D01*
G03X385408Y702602I-924J923D01*
G01Y716279D01*
G02X385467Y716420I200J-1D01*
G01X400424Y731377D01*
G03X400806Y732301I-924J923D01*
G01Y747342D01*
G02X400865Y747483I200J-1D01*
G01X403048Y749666D01*
G02X403189Y749724I141J-142D01*
G01X416571D01*
G03X417495Y750107I0J1306D01*
G01X427112Y759724D01*
G02X427310Y759775I142J-141D01*
G01X427700Y759660D01*
X427774Y759581D01*
X427786Y759527D01*
G03X429253Y758345I1467J319D01*
G03Y761349I0J1502D01*
G03X428686Y761238I0J-1502D01*
G02X428500Y761257I-75J185D01*
G01X428304Y761387D01*
G03X428306Y761460I-1304J72D01*
G01Y784876D01*
G02X428365Y785017I200J-1D01*
G01X430083Y786735D01*
G02X430224Y786794I142J-141D01*
G01X430940D01*
G02X431124Y786671I-1J-200D01*
G01X431291Y786276D01*
X431269Y786158D01*
X431227Y786115D01*
G03X430801Y785067I1076J-1048D01*
G03X432303Y783565I1502J0D01*
G03X433737Y784621I0J1502D01*
G01X433745Y784644D01*
X433770Y784686D01*
X444725Y795641D01*
G02X444867Y795700I142J-141D01*
G37*
G36*
G01X457638Y1300792D02*
X468675D01*
G02X468817Y1300733I0J-200D01*
G01X469414Y1300136D01*
G02X469473Y1299994I-141J-142D01*
G01Y1219244D01*
G03X469532Y1219102I200J0D01*
G01X469931Y1218703D01*
G02X469988Y1218563I-143J-140D01*
G01Y1218535D01*
G03X470047Y1218393I200J0D01*
G01X470323Y1218117D01*
X470325Y1218114D01*
G03X470339Y1218100I857J843D01*
G01X470340Y1218099D01*
X474097Y1214342D01*
X474098Y1214341D01*
G03X474111Y1214328I856J843D01*
G01X474114Y1214326D01*
X474391Y1214049D01*
G03X474533Y1213990I142J141D01*
G01X474561D01*
G02X474701Y1213933I0J-200D01*
G01X475142Y1213492D01*
G03X475284Y1213433I142J141D01*
G01X527434D01*
G02X527576Y1213374I0J-200D01*
G01X530243Y1210707D01*
G02X530302Y1210565I-141J-142D01*
G01Y1123941D01*
G02X530179Y1123756I-200J0D01*
G01X530122Y1123733D01*
X530004Y1123756D01*
X526507Y1127254D01*
G02X526448Y1127395I141J142D01*
G01Y1159576D01*
G02X526577Y1159763I200J0D01*
G01X526691Y1159806D01*
X526987Y1159917D01*
X527106Y1159887D01*
X527148Y1159840D01*
G03X528274Y1159332I1126J994D01*
G03Y1162336I0J1502D01*
G03X526927Y1161499I0J-1502D01*
G01X526926Y1161498D01*
G02X526863Y1161424I-179J89D01*
G01X526785Y1161369D01*
G02X526685Y1161333I-115J163D01*
G01X526391Y1161310D01*
G02X526209Y1161399I-15J199D01*
G01X526207Y1161401D01*
X526206Y1161402D01*
G03X526009Y1161645I-1259J-819D01*
G01X524224Y1163430D01*
G02X524165Y1163572I141J142D01*
G01Y1163660D01*
G02X524181Y1163738I200J0D01*
G01X524222Y1163835D01*
X524246Y1163861D01*
G03X524648Y1164863I-1101J1023D01*
G01Y1164885D01*
G03X524324Y1165817I-1502J0D01*
G01X524323D01*
X524311Y1165833D01*
X524302Y1165850D01*
G02X524278Y1165945I176J95D01*
G01Y1166072D01*
X524234D01*
Y1166308D01*
X524259Y1166375D01*
X524283Y1166403D01*
G03X524648Y1167363I-1137J982D01*
G01Y1167385D01*
G03X524324Y1168317I-1502J0D01*
G01X524323D01*
X524311Y1168333D01*
X524302Y1168350D01*
G02X524278Y1168445I176J95D01*
G01Y1168572D01*
X524234D01*
Y1168808D01*
X524259Y1168875D01*
X524283Y1168903D01*
G03X524648Y1169863I-1137J982D01*
G01Y1169885D01*
G03X524324Y1170817I-1502J0D01*
G01X524323D01*
X524311Y1170833D01*
X524302Y1170850D01*
G02X524278Y1170945I176J95D01*
G01Y1171072D01*
X524234D01*
Y1171308D01*
X524259Y1171375D01*
X524283Y1171403D01*
G03X524648Y1172363I-1137J982D01*
G01Y1172385D01*
G03X524324Y1173317I-1502J0D01*
G01X524323D01*
X524311Y1173333D01*
X524302Y1173350D01*
G02X524278Y1173445I176J95D01*
G01Y1173572D01*
X524234D01*
Y1173808D01*
X524259Y1173875D01*
X524283Y1173903D01*
G03X524648Y1174884I-1136J981D01*
G03X523167Y1176386I-1502J0D01*
G01X523145D01*
G03X522213Y1176062I0J-1502D01*
G01Y1176061D01*
X522197Y1176049D01*
X522180Y1176040D01*
G02X522085Y1176016I-95J176D01*
G01X521958D01*
Y1175972D01*
X521722D01*
X521655Y1175997D01*
X521627Y1176021D01*
G03X520646Y1176386I-981J-1136D01*
G03X519144Y1174905I0J-1502D01*
G01Y1174883D01*
G03X519468Y1173951I1502J0D01*
G01X519469D01*
X519481Y1173935D01*
X519490Y1173918D01*
G02X519514Y1173823I-176J-95D01*
G01Y1173696D01*
X519558D01*
Y1173460D01*
X519533Y1173393D01*
X519509Y1173365D01*
G03X519144Y1172405I1137J-982D01*
G01Y1172383D01*
G03X519468Y1171451I1502J0D01*
G01X519469D01*
X519481Y1171435D01*
X519490Y1171418D01*
G02X519514Y1171323I-176J-95D01*
G01Y1171196D01*
X519558D01*
Y1170960D01*
X519533Y1170893D01*
X519509Y1170865D01*
G03X519144Y1169905I1137J-982D01*
G01Y1169883D01*
G03X519468Y1168951I1502J0D01*
G01X519469D01*
X519481Y1168935D01*
X519490Y1168918D01*
G02X519514Y1168823I-176J-95D01*
G01Y1168696D01*
X519558D01*
Y1168460D01*
X519533Y1168393D01*
X519509Y1168365D01*
G03X519144Y1167405I1137J-982D01*
G01Y1167383D01*
G03X519468Y1166451I1502J0D01*
G01X519469D01*
X519481Y1166435D01*
X519490Y1166418D01*
G02X519514Y1166323I-176J-95D01*
G01Y1166196D01*
X519558D01*
Y1165960D01*
X519533Y1165893D01*
X519509Y1165865D01*
G03X519144Y1164905I1137J-982D01*
G01Y1164883D01*
G03X519468Y1163951I1502J0D01*
G01X519469D01*
X519481Y1163935D01*
X519490Y1163918D01*
G02X519514Y1163823I-176J-95D01*
G01Y1163696D01*
X519558D01*
Y1163460D01*
X519533Y1163393D01*
X519509Y1163365D01*
G03X519144Y1162384I1136J-981D01*
G03X520646Y1160882I1502J0D01*
G03X521670Y1161285I0J1502D01*
G01X521697Y1161310D01*
X521798Y1161351D01*
G02X521873Y1161365I74J-186D01*
G01X522043D01*
G03X522084Y1161322I1107J1015D01*
G01X523385Y1160021D01*
G02X523444Y1159879I-141J-142D01*
G01Y1119812D01*
G02X523355Y1119645I-200J-1D01*
G03X523126Y1119458I831J-1251D01*
G01X522221Y1118552D01*
G02X522079Y1118494I-141J142D01*
G01X513707D01*
G02X513565Y1118552I-1J200D01*
G01X510134Y1121984D01*
G03X509072Y1122424I-1062J-1062D01*
G01X504307D01*
G03X503245Y1121984I0J-1502D01*
G01X501218Y1119956D01*
G02X501076Y1119898I-141J142D01*
G01X497063D01*
G03X495562Y1118396I0J-1501D01*
G03X495931Y1117409I1501J-1D01*
G01X495956Y1117381D01*
X495981Y1117315D01*
X495980Y1116978D01*
X495955Y1116911D01*
X495931Y1116883D01*
G03X495561Y1115896I1131J-987D01*
G03X495565Y1115790I1502J4D01*
G01X495569Y1115728D01*
X495505Y1115620D01*
X495107Y1115439D01*
G02X494883Y1115480I-82J182D01*
G01X494378Y1115984D01*
G02X494320Y1116126I142J141D01*
G01Y1127264D01*
G02X494399Y1127423I200J0D01*
G01X494691Y1127644D01*
X494782Y1127661D01*
X494828Y1127648D01*
G03X495236Y1127592I406J1446D01*
G03Y1130596I0J1502D01*
G03X494828Y1130540I-2J-1502D01*
G01X494782Y1130527D01*
X494691Y1130544D01*
X494399Y1130765D01*
G02X494320Y1130924I121J159D01*
G01Y1160579D01*
G02X494402Y1160741I200J1D01*
G01X494704Y1160959D01*
X494800Y1160974D01*
X494845Y1160958D01*
G03X495318Y1160882I472J1426D01*
G03X496820Y1162384I0J1502D01*
G03X496450Y1163371I-1501J0D01*
G01X496426Y1163399D01*
X496401Y1163466D01*
Y1163802D01*
X496426Y1163869D01*
X496450Y1163897D01*
G03Y1165871I-1131J987D01*
G01X496426Y1165899D01*
X496401Y1165966D01*
Y1166302D01*
X496426Y1166369D01*
X496450Y1166397D01*
G03Y1168371I-1131J987D01*
G01X496426Y1168399D01*
X496401Y1168466D01*
Y1168802D01*
X496426Y1168869D01*
X496450Y1168897D01*
G03Y1170871I-1131J987D01*
G01X496426Y1170899D01*
X496401Y1170966D01*
Y1171302D01*
X496426Y1171369D01*
X496450Y1171397D01*
G03Y1173371I-1131J987D01*
G01X496426Y1173399D01*
X496401Y1173466D01*
Y1173802D01*
X496426Y1173869D01*
X496450Y1173897D01*
G03X496820Y1174884I-1131J987D01*
G03X495318Y1176386I-1502J0D01*
G03X494331Y1176016I0J-1501D01*
G01X494303Y1175992D01*
X494236Y1175967D01*
X493900D01*
X493833Y1175992D01*
X493805Y1176016D01*
G03X492818Y1176386I-987J-1131D01*
G03X491316Y1174884I0J-1502D01*
G03X491686Y1173897I1501J0D01*
G01X491710Y1173869D01*
X491735Y1173802D01*
Y1173466D01*
X491710Y1173399D01*
X491686Y1173371D01*
G03Y1171397I1131J-987D01*
G01X491710Y1171369D01*
X491735Y1171302D01*
Y1170966D01*
X491710Y1170899D01*
X491686Y1170871D01*
G03Y1168897I1131J-987D01*
G01X491710Y1168869D01*
X491735Y1168802D01*
Y1168466D01*
X491710Y1168399D01*
X491686Y1168371D01*
G03Y1166397I1131J-987D01*
G01X491710Y1166369D01*
X491735Y1166302D01*
Y1165966D01*
X491710Y1165899D01*
X491686Y1165871D01*
G03Y1163897I1131J-987D01*
G01X491710Y1163869D01*
X491735Y1163802D01*
X491736Y1163465D01*
X491711Y1163399D01*
X491686Y1163371D01*
G03X491316Y1162384I1131J-987D01*
G01Y1115421D01*
G03X491756Y1114359I1502J0D01*
G01X493846Y1112270D01*
G02X493886Y1112044I-141J-142D01*
G01X493700Y1111645D01*
X493592Y1111583D01*
X493528Y1111588D01*
G03X493397Y1111594I-134J-1496D01*
G03Y1108590I0J-1502D01*
G03X494245Y1108852I0J1503D01*
G01X494291Y1108884D01*
X494401Y1108890D01*
X494764Y1108699D01*
G02X494870Y1108522I-94J-176D01*
G01Y1106298D01*
G03X497874I1502J0D01*
G01Y1111867D01*
G03X497434Y1112929I-1502J0D01*
G01X496647Y1113716D01*
G02X496606Y1113940I141J142D01*
G01X496787Y1114338D01*
X496895Y1114402D01*
X496957Y1114398D01*
G03X497063Y1114394I110J1498D01*
G03X498565Y1115896I0J1502D01*
G03X498489Y1116369I-1502J1D01*
G01X498473Y1116414D01*
X498488Y1116510D01*
X498706Y1116812D01*
G02X498868Y1116894I161J-118D01*
G01X501781D01*
G03X502843Y1117334I0J1502D01*
G01X504870Y1119362D01*
G02X505012Y1119420I141J-142D01*
G01X505057D01*
G02X505206Y1119354I1J-200D01*
G01X505434Y1119098D01*
X505459Y1119018D01*
X505454Y1118974D01*
G03X505444Y1118801I1491J-173D01*
G03X505888Y1117735I1502J0D01*
G01X505917Y1117707D01*
X505947Y1117633D01*
Y1117269D01*
X505917Y1117195D01*
X505888Y1117167D01*
G03X505444Y1116101I1058J-1066D01*
G03X505517Y1115639I1502J1D01*
G01X505530Y1115598D01*
X505521Y1115513D01*
X505324Y1115180D01*
X505254Y1115131D01*
X505212Y1115123D01*
G03X504020Y1113929I283J-1475D01*
G01X504010Y1113881D01*
X503948Y1113803D01*
X503554Y1113632D01*
X503455Y1113640D01*
X503413Y1113666D01*
G03X502610Y1113899I-803J-1269D01*
G03X502328Y1113872I2J-1502D01*
G01X502291Y1113865D01*
X502216Y1113880D01*
X501920Y1114068D01*
X501875Y1114130D01*
X501866Y1114167D01*
G03X500410Y1115299I-1456J-370D01*
G03X498908Y1113797I0J-1502D01*
G03X499438Y1112652I1502J0D01*
G02X499509Y1112499I-129J-153D01*
G01Y1112195D01*
G02X499438Y1112042I-200J0D01*
G03Y1109752I972J-1145D01*
G02X499509Y1109599I-129J-153D01*
G01Y1109295D01*
G02X499438Y1109142I-200J0D01*
G03X498908Y1107997I972J-1145D01*
G03X500410Y1106495I1502J0D01*
G03X501863Y1107615I0J1503D01*
G01X501872Y1107650D01*
X501914Y1107710D01*
X502197Y1107898D01*
X502268Y1107914D01*
X502304Y1107909D01*
G03X502510Y1107895I205J1488D01*
G03X502716Y1107909I1J1502D01*
G01X502752Y1107914D01*
X502823Y1107898D01*
X503106Y1107710D01*
X503148Y1107650D01*
X503157Y1107615D01*
G03X504610Y1106495I1453J383D01*
G03X506112Y1107997I0J1502D01*
G03X505744Y1108982I-1502J0D01*
G01X505719Y1109011D01*
X505694Y1109081D01*
X505708Y1109433D01*
X505738Y1109501D01*
X505765Y1109528D01*
G03X506212Y1110597I-1055J1069D01*
G03X505835Y1111592I-1502J0D01*
G01X505802Y1111630D01*
X505779Y1111726D01*
X505886Y1112144D01*
X505953Y1112217D01*
X506000Y1112234D01*
G03X506997Y1113648I-504J1414D01*
G03X506924Y1114110I-1502J-1D01*
G01X506911Y1114151D01*
X506920Y1114236D01*
X507117Y1114569D01*
X507187Y1114618D01*
X507229Y1114626D01*
G03X508448Y1116101I-283J1475D01*
G03X508004Y1117167I-1502J0D01*
G01X507975Y1117195D01*
X507945Y1117269D01*
Y1117633D01*
X507975Y1117707D01*
X508004Y1117735D01*
G03X508427Y1118550I-1058J1066D01*
G01X508436Y1118606D01*
X508509Y1118690D01*
X508902Y1118816D01*
G02X509104Y1118766I60J-191D01*
G01X511940Y1115930D01*
G03X513002Y1115490I1062J1062D01*
G01X522784D01*
G03X523019Y1115509I-3J1502D01*
G01X523058Y1115515D01*
X523132Y1115498D01*
X523424Y1115295D01*
X523466Y1115231D01*
X523473Y1115193D01*
G03X523884Y1114426I1472J295D01*
G01X526939Y1111371D01*
G02X526998Y1111229I-141J-142D01*
G01Y1111221D01*
G02X526914Y1111058I-200J0D01*
G01X526875Y1111031D01*
X526780Y1111017D01*
X526708Y1111042D01*
X526666Y1111069D01*
X526648Y1111089D01*
G03X525525Y1111594I-1123J-996D01*
G03X524023Y1110092I0J-1502D01*
G03X525506Y1108590I1502J0D01*
G01X525526D01*
G03X526370Y1108850I-1J1502D01*
G01X526371Y1108851D01*
X526375Y1108853D01*
G02X526480Y1108886I110J-167D01*
G01X526536Y1108887D01*
X526796Y1108749D01*
X526803Y1108753D01*
X526900Y1108695D01*
G02X526998Y1108523I-102J-172D01*
G01Y1106365D01*
G03X528456Y1104864I1502J0D01*
G01X528495Y1104863D01*
G03X529583Y1105324I5J1503D01*
G01X529611Y1105353D01*
X529698Y1105391D01*
G02X529771Y1105407I79J-184D01*
G01X529813Y1105409D01*
X530057Y1105313D01*
X530175Y1105266D01*
G02X530302Y1105080I-73J-186D01*
G01Y1098588D01*
G02X530196Y1098411I-200J0D01*
G03X523116Y1086654I6222J-11757D01*
G03X530170Y1074910I13303J0D01*
G01X530197Y1074896D01*
X536384Y1068709D01*
G02X536386Y1068707I-140J-142D01*
G02X536443Y1068567I-143J-140D01*
G01Y1041135D01*
G02X536384Y1040993I-200J0D01*
G01X532342Y1036951D01*
X532314Y1036922D01*
X532240Y1036892D01*
X522554D01*
G03X522412Y1036833I0J-200D01*
G01X516855Y1031276D01*
G02X516833Y1031257I-141J141D01*
G02X516678Y1031220I-120J160D01*
G01X516306Y1031287D01*
X516229Y1031347D01*
X516209Y1031392D01*
G03X514843Y1032268I-1366J-627D01*
G03X513409Y1031212I0J-1502D01*
G01X513401Y1031189D01*
X513376Y1031147D01*
X511263Y1029034D01*
G03X510880Y1028110I923J-924D01*
G01Y1014540D01*
G03X510915Y1014243I1307J3D01*
G01X510920Y1014220D01*
Y1008724D01*
G03X511291Y1007828I1267J0D01*
G01X513325Y1005793D01*
G02X513384Y1005652I-141J-142D01*
G01Y1005534D01*
X513372Y1005487D01*
X513361Y1005465D01*
G03X513188Y1004766I1329J-700D01*
G01Y1004728D01*
G03X514244Y1003332I1502J38D01*
G01X514268Y1003324D01*
X514309Y1003299D01*
X514704Y1002904D01*
G02X514750Y1002693I-141J-141D01*
G01X514640Y1002397D01*
G02X514606Y1002338I-188J69D01*
G01X514578Y1002305D01*
X514506Y1002268D01*
X514464Y1002265D01*
G03X513064Y1000766I103J-1499D01*
G03X514566Y999264I1502J0D01*
G03X514813Y999284I3J1502D01*
G01X514823Y999286D01*
X514840Y999287D01*
G02X514983Y999241I15J-199D01*
G01X515173Y999081D01*
G03X515220Y999052I128J154D01*
G01X515224Y999050D01*
X515288Y998952D01*
Y998658D01*
G02X515221Y998509I-200J0D01*
G01X514999Y998310D01*
G02X514847Y998260I-133J149D01*
G01X514844D01*
G03X514690Y998268I-155J-1494D01*
G01X514681D01*
G03X513236Y997142I9J-1502D01*
G01X513229Y997115D01*
X513203Y997070D01*
X510549Y994415D01*
G03X510490Y994273I141J-142D01*
G01Y982586D01*
G02X510431Y982444I-200J0D01*
G01X507963Y979976D01*
X507800Y979975D01*
X507741Y980031D01*
G03X506702Y980449I-1040J-1084D01*
G03X505200Y978947I0J-1502D01*
G03X505568Y977962I1502J0D01*
G02X505617Y977829I-151J-131D01*
G01X505616Y977709D01*
G02X505557Y977570I-200J3D01*
G01X497248Y969261D01*
G02X497106Y969202I-142J141D01*
G01X491226D01*
G02X491084Y969261I0J200D01*
G01X490728Y969617D01*
G02X490670Y969758I142J141D01*
G01Y977163D01*
G03X489933Y978458I-1506J0D01*
G01X489892Y978482D01*
X489842Y978559D01*
X489805Y978863D01*
G02X489862Y979028I198J24D01*
G01X499448Y988614D01*
G03X499830Y989538I-924J923D01*
G01Y996822D01*
X499842Y996869D01*
X499853Y996891D01*
G03X500026Y997590I-1329J700D01*
G03X497022I-1502J0D01*
G03X497195Y996891I1502J1D01*
G01X497206Y996869D01*
X497218Y996822D01*
Y990162D01*
G02X497159Y990021I-200J1D01*
G01X486103Y978965D01*
G02X485961Y978906I-142J141D01*
G01X485793D01*
G03X485651Y978847I0J-200D01*
G01X484138Y977334D01*
G03X484079Y977192I141J-142D01*
G01Y956176D01*
G02X484020Y956034I-200J0D01*
G01X482005Y954018D01*
X481977Y953989D01*
X481903Y953959D01*
X481128D01*
X481066Y953981D01*
X481039Y954002D01*
G03X479613Y954496I-1427J-1813D01*
G03X478187Y954002I1J-2307D01*
G02X478063Y953959I-124J157D01*
G01X474502D01*
X474471Y953969D01*
G03X473992Y954048I-481J-1423D01*
G03X473513Y953969I2J-1502D01*
G01X473482Y953959D01*
X472727D01*
G03X472585Y953900I0J-200D01*
G01X469958Y951273D01*
G03X469899Y951131I141J-142D01*
G01Y934515D01*
G02X469840Y934373I-200J0D01*
G01X469553Y934086D01*
G03X469494Y933944I141J-142D01*
G01Y930518D01*
G02X469467Y930418I-200J0D01*
G03X469294Y929767I1133J-650D01*
G01Y925237D01*
G02X469235Y925096I-200J1D01*
G01X467414Y923275D01*
G03X467355Y923133I141J-142D01*
G01Y920198D01*
G03X467401Y920071I200J1D01*
G01X467423Y920043D01*
X467446Y919979D01*
Y898645D01*
G02X467387Y898503I-200J0D01*
G01X446795Y877911D01*
G03X446736Y877769I141J-142D01*
G01Y842047D01*
G02X446677Y841905I-200J0D01*
G01X427462Y822690D01*
X427434Y822661D01*
X427360Y822631D01*
X391739D01*
G02X391597Y822690I0J200D01*
G01X385514Y828773D01*
X385485Y828801D01*
X385455Y828875D01*
Y859025D01*
G03X385396Y859167I-200J0D01*
G01X384826Y859737D01*
X384804Y859858D01*
X384830Y859916D01*
G03X384964Y860535I-1368J620D01*
G03X383908Y861969I-1502J0D01*
G01X383885Y861977D01*
X383843Y862002D01*
X380165Y865680D01*
G02X380106Y865821I141J142D01*
G01Y948185D01*
X380193Y948294D01*
X380262Y948309D01*
G03X381430Y949774I-335J1465D01*
G03X379951Y951276I-1502J0D01*
G01X379927D01*
G03X379425Y951189I2J-1502D01*
G01X379423D01*
G02X379330Y951179I-67J188D01*
G01X379281Y951186D01*
X378974Y951402D01*
G02X378889Y951566I115J164D01*
G01Y952248D01*
G02X378912Y952341I200J0D01*
G01X378964Y952439D01*
X378993Y952473D01*
X379011Y952487D01*
G03X379621Y953669I-893J1209D01*
G01Y953691D01*
Y953696D01*
G03X379348Y954560I-1502J0D01*
G01X379347Y954561D01*
G02X379324Y954747I164J115D01*
G01X379461Y955104D01*
X379535Y955168D01*
X379584Y955180D01*
G03X380747Y956643I-339J1463D01*
G03X380734Y956843I-1502J3D01*
G03X379279Y958145I-1489J-200D01*
G01X379239Y958146D01*
X379168Y958177D01*
X378946Y958405D01*
G02X378889Y958545I143J140D01*
G01Y960250D01*
X378988Y960362D01*
X379064Y960372D01*
G03Y963352I-189J1490D01*
G01X378988Y963362D01*
X378889Y963474D01*
Y966040D01*
G02X378941Y966175I200J0D01*
G01X378996Y966236D01*
G02X379051Y966278I147J-136D01*
G01X379139Y966325D01*
X379171Y966330D01*
G03Y969294I-243J1482D01*
G01X379139Y969299D01*
X379051Y969346D01*
G02X378996Y969388I92J178D01*
G01X378941Y969449D01*
G02X378889Y969584I148J135D01*
G01Y987050D01*
G02X378904Y987126I200J0D01*
G01X388440Y1010149D01*
G03X388514Y1010394I-1207J498D01*
G01X388525Y1010446D01*
G02X388536Y1010484I197J-36D01*
G01X388989Y1011577D01*
G03X389061Y1011815I-1170J484D01*
G01X399377Y1063681D01*
G03X399402Y1063928I-1242J250D01*
G01Y1077047D01*
G03X399305Y1077532I-1267J-1D01*
G01X394505Y1089120D01*
Y1089121D01*
X393496Y1091555D01*
X393244Y1092165D01*
Y1092166D01*
G03X393237Y1092182I-1164J-500D01*
G01X392880Y1093041D01*
G02X392865Y1093118I185J76D01*
G01Y1114828D01*
G02X393065Y1115028I200J0D01*
G01X400984D01*
G02X401154Y1114935I1J-200D01*
G01X401361Y1114603D01*
X401367Y1114500D01*
X401344Y1114454D01*
G03X401193Y1113797I1351J-656D01*
G03X401723Y1112652I1502J0D01*
G02X401794Y1112499I-129J-153D01*
G01Y1112195D01*
G02X401723Y1112042I-200J0D01*
G03Y1109752I972J-1145D01*
G02X401794Y1109599I-129J-153D01*
G01Y1109295D01*
G02X401723Y1109142I-200J0D01*
G03X401193Y1107997I972J-1145D01*
G03X402695Y1106495I1502J0D01*
G03X404148Y1107615I0J1503D01*
G01X404157Y1107650D01*
X404199Y1107710D01*
X404482Y1107898D01*
X404553Y1107914D01*
X404589Y1107909D01*
G03X404795Y1107895I205J1488D01*
G03X405001Y1107909I1J1502D01*
G01X405037Y1107914D01*
X405108Y1107898D01*
X405391Y1107710D01*
X405433Y1107650D01*
X405442Y1107615D01*
G03X406895Y1106495I1453J383D01*
G03X408397Y1107997I0J1502D01*
G03X408029Y1108982I-1502J0D01*
G01X408004Y1109011D01*
X407979Y1109081D01*
X407993Y1109433D01*
X408023Y1109501D01*
X408050Y1109528D01*
G03X408497Y1110597I-1055J1069D01*
G03X408120Y1111592I-1502J0D01*
G01X408087Y1111630D01*
X408064Y1111726D01*
X408171Y1112144D01*
X408238Y1112217D01*
X408285Y1112234D01*
G03X409282Y1113648I-504J1414D01*
G03X409264Y1113877I-1502J-3D01*
G01X409258Y1113921D01*
X409282Y1114005D01*
X409508Y1114269D01*
G02X409660Y1114338I151J-131D01*
G01X410200D01*
G02X410352Y1114269I1J-200D01*
G01X410578Y1114005D01*
X410602Y1113921D01*
X410596Y1113877D01*
G03X410578Y1113648I1484J-232D01*
G03X412080Y1112146I1502J0D01*
G03X413067Y1112516I0J1501D01*
G01X413095Y1112540D01*
X413162Y1112565D01*
X413498D01*
X413565Y1112540D01*
X413593Y1112516D01*
G03X414580Y1112146I987J1131D01*
G03X416082Y1113648I0J1502D01*
G03X415938Y1114290I-1503J0D01*
G01X415916Y1114337D01*
X415922Y1114438D01*
X416131Y1114768D01*
G02X416300Y1114860I168J-108D01*
G01X424297D01*
G03X425642Y1115417I0J1902D01*
G01X426865Y1116641D01*
G02X427083Y1116684I141J-142D01*
G01X427140Y1116661D01*
X427206Y1116561D01*
Y1113944D01*
G03X427646Y1112882I1502J0D01*
G01X428259Y1112270D01*
G02X428299Y1112044I-141J-142D01*
G01X428113Y1111645D01*
X428005Y1111583D01*
X427941Y1111588D01*
G03X427810Y1111594I-134J-1496D01*
G03Y1108590I0J-1502D01*
G03X428934Y1109096I0J1501D01*
G01X428962Y1109128D01*
X429041Y1109163D01*
X429084D01*
G02X429284Y1108963I0J-200D01*
G01Y1108768D01*
G02X429225Y1108626I-200J0D01*
G01X428615Y1108017D01*
G03X428176Y1106955I1062J-1061D01*
G03X429677Y1105454I1501J0D01*
G03X430739Y1105893I1J1501D01*
G01X431847Y1107001D01*
G03X432286Y1108063I-1062J1061D01*
G01Y1111867D01*
G03X431847Y1112929I-1501J1D01*
G01X431060Y1113716D01*
G02X431019Y1113940I141J142D01*
G01X431200Y1114338D01*
X431308Y1114402D01*
X431370Y1114398D01*
G03X431476Y1114394I110J1498D01*
G03X432978Y1115896I0J1502D01*
G03X432552Y1116944I-1502J0D01*
G02X432495Y1117084I143J140D01*
G01Y1117293D01*
G03X432538Y1117334I-1015J1107D01*
G01X434607Y1119404D01*
G02X434749Y1119462I141J-142D01*
G01X439475D01*
G02X439626Y1119394I1J-200D01*
G01X439853Y1119133D01*
X439877Y1119051D01*
X439871Y1119008D01*
G03X439857Y1118801I1488J-205D01*
G03X440301Y1117735I1502J0D01*
G01X440330Y1117707D01*
X440360Y1117633D01*
Y1117269D01*
X440330Y1117195D01*
X440301Y1117167D01*
G03X439857Y1116101I1058J-1066D01*
G03X439930Y1115639I1502J1D01*
G01X439943Y1115598D01*
X439934Y1115513D01*
X439737Y1115180D01*
X439667Y1115131D01*
X439625Y1115123D01*
G03X438433Y1113929I283J-1475D01*
G01X438423Y1113881D01*
X438361Y1113803D01*
X437967Y1113632D01*
X437868Y1113640D01*
X437826Y1113666D01*
G03X437023Y1113899I-803J-1269D01*
G03X436741Y1113872I2J-1502D01*
G01X436704Y1113865D01*
X436629Y1113880D01*
X436333Y1114068D01*
X436288Y1114130D01*
X436279Y1114167D01*
G03X434823Y1115299I-1456J-370D01*
G03X433321Y1113797I0J-1502D01*
G03X433851Y1112652I1502J0D01*
G02X433922Y1112499I-129J-153D01*
G01Y1112195D01*
G02X433851Y1112042I-200J0D01*
G03Y1109752I972J-1145D01*
G02X433922Y1109599I-129J-153D01*
G01Y1109295D01*
G02X433851Y1109142I-200J0D01*
G03X433321Y1107997I972J-1145D01*
G03X434823Y1106495I1502J0D01*
G03X436276Y1107615I0J1503D01*
G01X436285Y1107650D01*
X436327Y1107710D01*
X436610Y1107898D01*
X436681Y1107914D01*
X436717Y1107909D01*
G03X436923Y1107895I205J1488D01*
G03X437129Y1107909I1J1502D01*
G01X437165Y1107914D01*
X437236Y1107898D01*
X437519Y1107710D01*
X437561Y1107650D01*
X437570Y1107615D01*
G03X439023Y1106495I1453J383D01*
G03X440525Y1107997I0J1502D01*
G03X440157Y1108982I-1502J0D01*
G01X440132Y1109011D01*
X440107Y1109081D01*
X440121Y1109433D01*
X440151Y1109501D01*
X440178Y1109528D01*
G03X440625Y1110597I-1055J1069D01*
G03X440248Y1111592I-1502J0D01*
G01X440215Y1111630D01*
X440192Y1111726D01*
X440299Y1112144D01*
X440366Y1112217D01*
X440413Y1112234D01*
G03X441410Y1113648I-504J1414D01*
G03X441337Y1114110I-1502J-1D01*
G01X441324Y1114151D01*
X441333Y1114236D01*
X441530Y1114569D01*
X441600Y1114618D01*
X441642Y1114626D01*
G03X442861Y1116101I-283J1475D01*
G03X442417Y1117167I-1502J0D01*
G01X442388Y1117195D01*
X442358Y1117269D01*
Y1117633D01*
X442388Y1117707D01*
X442417Y1117735D01*
G03X442811Y1118415I-1057J1067D01*
G01X442825Y1118468D01*
X442899Y1118543D01*
X443287Y1118647D01*
G02X443480Y1118596I52J-193D01*
G01X446353Y1115723D01*
G02X446407Y1115537I-141J-142D01*
G01X446321Y1115157D01*
X446253Y1115081D01*
X446204Y1115063D01*
G03X445721Y1114780I505J-1415D01*
G01X445693Y1114756D01*
X445626Y1114731D01*
X445290D01*
X445223Y1114756D01*
X445195Y1114780D01*
G03X444208Y1115150I-987J-1131D01*
G03Y1112146I0J-1502D01*
G03X445195Y1112516I0J1501D01*
G01X445223Y1112540D01*
X445290Y1112565D01*
X445626D01*
X445693Y1112540D01*
X445721Y1112516D01*
G03X446708Y1112146I987J1131D01*
G03X448210Y1113648I0J1502D01*
G03X448080Y1114260I-1502J1D01*
G01X448059Y1114307D01*
X448067Y1114407D01*
X448277Y1114731D01*
G02X448445Y1114822I168J-109D01*
G01X460348D01*
G03X461410Y1115262I0J1502D01*
G01X461574Y1115427D01*
G02X461753Y1115482I141J-142D01*
G01X462127Y1115410D01*
X462205Y1115348D01*
X462224Y1115302D01*
G03X462797Y1114629I1380J594D01*
G01X462836Y1114605D01*
X462883Y1114528D01*
X462922Y1114172D01*
G02X462865Y1114009I-199J-22D01*
G01X461851Y1112996D01*
G03X461412Y1111934I1062J-1061D01*
G01Y1111662D01*
G02X461305Y1111485I-200J0D01*
G01X460942Y1111294D01*
X460832Y1111300D01*
X460786Y1111332D01*
G03X459938Y1111594I-848J-1241D01*
G03Y1108590I0J-1502D01*
G03X460786Y1108852I0J1503D01*
G01X460832Y1108884D01*
X460942Y1108890D01*
X461305Y1108699D01*
G02X461412Y1108522I-93J-177D01*
G01Y1106365D01*
G03X464414I1501J0D01*
G01Y1111229D01*
G02X464473Y1111371I200J0D01*
G01X466309Y1113207D01*
G02X466482Y1113263I141J-142D01*
G01X466849Y1113206D01*
X466925Y1113151D01*
X466948Y1113108D01*
G03X467310Y1112652I1335J688D01*
G02X467381Y1112499I-129J-153D01*
G01Y1112195D01*
G02X467310Y1112042I-200J0D01*
G03Y1109752I972J-1145D01*
G02X467381Y1109599I-129J-153D01*
G01Y1109295D01*
G02X467310Y1109142I-200J0D01*
G03X466780Y1107997I972J-1145D01*
G03X468282Y1106495I1502J0D01*
G03X469735Y1107615I0J1503D01*
G01X469744Y1107650D01*
X469786Y1107710D01*
X470069Y1107898D01*
X470140Y1107914D01*
X470176Y1107909D01*
G03X470382Y1107895I205J1488D01*
G03X470588Y1107909I1J1502D01*
G01X470624Y1107914D01*
X470695Y1107898D01*
X470978Y1107710D01*
X471020Y1107650D01*
X471029Y1107615D01*
G03X472482Y1106495I1453J383D01*
G03X473984Y1107997I0J1502D01*
G03X473616Y1108982I-1502J0D01*
G01X473591Y1109011D01*
X473566Y1109081D01*
X473580Y1109433D01*
X473610Y1109501D01*
X473637Y1109528D01*
G03X474084Y1110597I-1055J1069D01*
G03X473707Y1111592I-1502J0D01*
G01X473674Y1111630D01*
X473651Y1111726D01*
X473758Y1112144D01*
X473825Y1112217D01*
X473872Y1112234D01*
G03X474869Y1113648I-504J1414D01*
G03X474796Y1114110I-1502J-1D01*
G01X474783Y1114151D01*
X474792Y1114236D01*
X474989Y1114569D01*
X475059Y1114618D01*
X475101Y1114626D01*
G03X476320Y1116101I-283J1475D01*
G03X475876Y1117167I-1502J0D01*
G01X475847Y1117195D01*
X475817Y1117269D01*
Y1117633D01*
X475847Y1117707D01*
X475876Y1117735D01*
G03X476320Y1118801I-1058J1066D01*
G03X473316I-1502J0D01*
G03X473760Y1117735I1502J0D01*
G01X473789Y1117707D01*
X473819Y1117633D01*
Y1117269D01*
X473789Y1117195D01*
X473760Y1117167D01*
G03X473316Y1116101I1058J-1066D01*
G03X473389Y1115639I1502J1D01*
G01X473402Y1115598D01*
X473393Y1115513D01*
X473196Y1115180D01*
X473126Y1115131D01*
X473084Y1115123D01*
G03X471892Y1113929I283J-1475D01*
G01X471882Y1113881D01*
X471820Y1113803D01*
X471426Y1113632D01*
X471327Y1113640D01*
X471285Y1113666D01*
G03X470482Y1113899I-803J-1269D01*
G03X470200Y1113872I2J-1502D01*
G01X470163Y1113865D01*
X470088Y1113880D01*
X469792Y1114068D01*
X469747Y1114130D01*
X469738Y1114167D01*
G03X468282Y1115299I-1456J-370D01*
G03X468160Y1115294I0J-1502D01*
G01X468117Y1115291D01*
X468040Y1115317D01*
X467792Y1115546D01*
G02X467728Y1115693I136J147D01*
G01Y1120409D01*
G03X467288Y1121471I-1502J0D01*
G01X460919Y1127839D01*
G02X460860Y1127981I141J142D01*
G01Y1159576D01*
G02X460990Y1159763I200J0D01*
G01X461399Y1159918D01*
X461519Y1159888D01*
X461560Y1159841D01*
G03X462687Y1159332I1127J993D01*
G03Y1162336I0J1502D01*
G03X461319Y1161454I0J-1502D01*
G01X461296Y1161403D01*
X461207Y1161341D01*
X460746Y1161306D01*
X460649Y1161354D01*
X460619Y1161401D01*
G03X460421Y1161646I-1261J-816D01*
G01X458621Y1163446D01*
G03X458578Y1163487I-1058J-1066D01*
G01Y1163696D01*
G02X458635Y1163836I200J0D01*
G03X459061Y1164884I-1076J1048D01*
G03X458691Y1165871I-1501J0D01*
G01X458667Y1165899D01*
X458642Y1165966D01*
Y1166302D01*
X458667Y1166369D01*
X458691Y1166397D01*
G03Y1168371I-1131J987D01*
G01X458667Y1168399D01*
X458642Y1168466D01*
Y1168802D01*
X458667Y1168869D01*
X458691Y1168897D01*
G03Y1170871I-1131J987D01*
G01X458667Y1170899D01*
X458642Y1170966D01*
Y1171302D01*
X458667Y1171369D01*
X458691Y1171397D01*
G03Y1173371I-1131J987D01*
G01X458667Y1173399D01*
X458642Y1173466D01*
Y1173802D01*
X458667Y1173869D01*
X458691Y1173897D01*
G03X459061Y1174884I-1131J987D01*
G03X457559Y1176386I-1502J0D01*
G03X456572Y1176016I0J-1501D01*
G01X456544Y1175992D01*
X456477Y1175967D01*
X456141D01*
X456074Y1175992D01*
X456046Y1176016D01*
G03X455059Y1176386I-987J-1131D01*
G03X453557Y1174884I0J-1502D01*
G03X453927Y1173897I1501J0D01*
G01X453951Y1173869D01*
X453976Y1173802D01*
Y1173466D01*
X453951Y1173399D01*
X453927Y1173371D01*
G03Y1171397I1131J-987D01*
G01X453951Y1171369D01*
X453976Y1171302D01*
Y1170966D01*
X453951Y1170899D01*
X453927Y1170871D01*
G03Y1168897I1131J-987D01*
G01X453951Y1168869D01*
X453976Y1168802D01*
Y1168466D01*
X453951Y1168399D01*
X453927Y1168371D01*
G03Y1166397I1131J-987D01*
G01X453951Y1166369D01*
X453976Y1166302D01*
Y1165966D01*
X453951Y1165899D01*
X453927Y1165871D01*
G03Y1163897I1131J-987D01*
G01X453951Y1163869D01*
X453976Y1163802D01*
Y1163466D01*
X453951Y1163399D01*
X453927Y1163371D01*
G03X453557Y1162384I1131J-987D01*
G03X455059Y1160882I1502J0D01*
G03X456107Y1161308I0J1502D01*
G02X456247Y1161365I140J-143D01*
G01X456456D01*
G03X456497Y1161322I1107J1015D01*
G01X457799Y1160021D01*
G02X457858Y1159879I-141J-142D01*
G01Y1127276D01*
G03X458297Y1126214I1501J-1D01*
G01X463932Y1120580D01*
G02X463974Y1120360I-142J-141D01*
G01X463804Y1119962D01*
X463701Y1119896D01*
X463640Y1119897D01*
G03X463604Y1119898I-60J-1500D01*
G01X462420D01*
G03X461358Y1119458I0J-1502D01*
G01X459785Y1117884D01*
G02X459643Y1117826I-141J142D01*
G01X448580D01*
G02X448438Y1117884I-1J200D01*
G01X444297Y1122026D01*
G03X443235Y1122466I-1062J-1062D01*
G01X434044D01*
G03X432982Y1122026I0J-1502D01*
G01X430551Y1119594D01*
G02X430333Y1119551I-141J142D01*
G01X430276Y1119574D01*
X430210Y1119674D01*
Y1120718D01*
G02X430268Y1120860I200J1D01*
G01X436292Y1126883D01*
G03X436732Y1127945I-1062J1062D01*
G01Y1129429D01*
G03X436292Y1130491I-1502J0D01*
G01X433927Y1132855D01*
G02X433868Y1132997I141J142D01*
G01Y1147191D01*
G03X433429Y1148253I-1501J1D01*
G01X428791Y1152890D01*
G02X428732Y1153032I141J142D01*
G01Y1160579D01*
G02X428815Y1160741I200J0D01*
G01X429117Y1160959D01*
X429213Y1160974D01*
X429258Y1160958D01*
G03X429731Y1160882I472J1426D01*
G03X431233Y1162384I0J1502D01*
G03X430863Y1163371I-1501J0D01*
G01X430839Y1163399D01*
X430814Y1163466D01*
Y1163802D01*
X430839Y1163869D01*
X430863Y1163897D01*
G03Y1165871I-1131J987D01*
G01X430839Y1165899D01*
X430814Y1165966D01*
Y1166302D01*
X430839Y1166369D01*
X430863Y1166397D01*
G03Y1168371I-1131J987D01*
G01X430839Y1168399D01*
X430814Y1168466D01*
Y1168802D01*
X430839Y1168869D01*
X430863Y1168897D01*
G03Y1170871I-1131J987D01*
G01X430839Y1170899D01*
X430814Y1170966D01*
Y1171302D01*
X430839Y1171369D01*
X430863Y1171397D01*
G03Y1173371I-1131J987D01*
G01X430839Y1173399D01*
X430814Y1173466D01*
Y1173802D01*
X430839Y1173869D01*
X430863Y1173897D01*
G03X431233Y1174884I-1131J987D01*
G03X429731Y1176386I-1502J0D01*
G03X428744Y1176016I0J-1501D01*
G01X428716Y1175992D01*
X428649Y1175967D01*
X428313D01*
X428246Y1175992D01*
X428218Y1176016D01*
G03X427231Y1176386I-987J-1131D01*
G03X425729Y1174884I0J-1502D01*
G03X426099Y1173897I1501J0D01*
G01X426123Y1173869D01*
X426148Y1173802D01*
Y1173466D01*
X426123Y1173399D01*
X426099Y1173371D01*
G03Y1171397I1131J-987D01*
G01X426123Y1171369D01*
X426148Y1171302D01*
Y1170966D01*
X426123Y1170899D01*
X426099Y1170871D01*
G03Y1168897I1131J-987D01*
G01X426123Y1168869D01*
X426148Y1168802D01*
Y1168466D01*
X426123Y1168399D01*
X426099Y1168371D01*
G03Y1166397I1131J-987D01*
G01X426123Y1166369D01*
X426148Y1166302D01*
Y1165966D01*
X426123Y1165899D01*
X426099Y1165871D01*
G03Y1163897I1131J-987D01*
G01X426123Y1163869D01*
X426148Y1163802D01*
X426149Y1163465D01*
X426124Y1163399D01*
X426099Y1163371D01*
G03X425730Y1162384I1132J-986D01*
G01Y1152327D01*
G03X426169Y1151265I1501J-1D01*
G01X430807Y1146628D01*
G02X430866Y1146486I-141J-142D01*
G01Y1132292D01*
G03X431305Y1131230I1501J-1D01*
G01X431940Y1130595D01*
G02X431999Y1130442I-141J-142D01*
G01X431979Y1130100D01*
X431940Y1130026D01*
X431906Y1129999D01*
G03X431719Y1129823I932J-1178D01*
G01X431686Y1129786D01*
X431593Y1129752D01*
X431163Y1129813D01*
X431083Y1129871D01*
X431061Y1129917D01*
G03X429348Y1130994I-1713J-824D01*
G03X427446Y1129092I0J-1902D01*
G01Y1126674D01*
G02X427388Y1126533I-200J0D01*
G01X424396Y1123542D01*
G03X423840Y1122197I1346J-1344D01*
G01Y1119076D01*
G02X423781Y1118935I-200J1D01*
G01X423568Y1118722D01*
G02X423427Y1118664I-141J142D01*
G01X411757D01*
G03X411235Y1118590I3J-1902D01*
G01X411192Y1118578D01*
X411104Y1118592D01*
X410776Y1118817D01*
X410731Y1118894D01*
X410727Y1118938D01*
G03X409231Y1120303I-1496J-137D01*
G03X407729Y1118801I0J-1502D01*
G03X407743Y1118596I1502J0D01*
G01X407749Y1118552D01*
X407725Y1118470D01*
X407498Y1118210D01*
G02X407347Y1118142I-150J132D01*
G01X405521D01*
G02X405380Y1118200I0J200D01*
G01X405306Y1118275D01*
G03X403961Y1118832I-1345J-1345D01*
G01X393065D01*
G02X392865Y1119032I0J200D01*
G01Y1127337D01*
G02X392911Y1127465I200J0D01*
G01X393003Y1127577D01*
X393062Y1127612D01*
X393096Y1127619D01*
G03Y1154429I-2742J13405D01*
G01X393062Y1154436D01*
X393003Y1154471D01*
X392911Y1154583D01*
G02X392865Y1154711I154J128D01*
G01Y1299928D01*
G02X392924Y1300070I200J0D01*
G01X393587Y1300733D01*
G02X393729Y1300792I142J-141D01*
G01X430378D01*
G02X430578Y1300592I0J-200D01*
G01Y1294829D01*
G03X430961Y1293905I1306J0D01*
G01X433059Y1291807D01*
G02X433118Y1291666I-141J-142D01*
G01Y1287042D01*
X433106Y1286995D01*
X433095Y1286973D01*
G03X432922Y1286274I1329J-700D01*
G03X435926I1502J0D01*
G03X435754Y1286974I-1502J2D01*
G01X435742Y1286996D01*
X435730Y1287043D01*
Y1292290D01*
G03X435348Y1293214I-1306J1D01*
G01X433250Y1295312D01*
G02X433192Y1295453I142J141D01*
G01Y1300711D01*
G02X433352Y1300792I161J-119D01*
G01X450187D01*
G02X450304Y1300754I0J-200D01*
G01X450314Y1300747D01*
X450393Y1300689D01*
G02X450435Y1300646I-121J-160D01*
G01X450454Y1300620D01*
X450464Y1300590D01*
G03X451889Y1299564I1425J477D01*
G03X452843Y1299906I0J1503D01*
G02X453082Y1299917I127J-154D01*
G03X454385Y1299518I1303J1928D01*
G03X456030Y1300200I-1J2327D01*
G01X456435Y1300605D01*
G02X456577Y1300664I142J-141D01*
G01X456875D01*
G03X457608Y1300782I2J2326D01*
G01X457638Y1300792D01*
G37*
G36*
G01X442240Y355587D02*
X459408D01*
G02X459550Y355528I0J-200D01*
G01X460649Y354429D01*
G02X460654Y354424I-139J-144D01*
G02X460707Y354270I-146J-136D01*
G01X460680Y353965D01*
G02X460656Y353887I-199J19D01*
G01X460644Y353864D01*
X460614Y353830D01*
X460594Y353817D01*
G03X459952Y352585I861J-1232D01*
G03X461263Y351095I1502J0D01*
G01X461264D01*
G02X461438Y350897I-26J-198D01*
G01Y349317D01*
G02X461264Y349119I-200J0D01*
G01X461263D01*
G03Y346139I191J-1490D01*
G01X461264D01*
G02X461438Y345941I-26J-198D01*
G01Y345915D01*
G02X461238Y345715I-200J0D01*
G01X461224D01*
X461209Y345717D01*
G03X460950Y345736I-261J-1784D01*
G03X460058Y345499I1J-1803D01*
G02X459915Y345478I-99J174D01*
G01X459796Y345505D01*
G02X459677Y345584I44J195D01*
G03X458454Y346213I-1223J-874D01*
G03Y343209I0J-1502D01*
G03X458686Y343227I0J1502D01*
G01X458729Y343234D01*
X458813Y343210D01*
X459078Y342984D01*
G02X459148Y342832I-130J-152D01*
G01Y341634D01*
G02X459078Y341482I-200J0D01*
G01X458813Y341256D01*
X458729Y341232D01*
X458686Y341239D01*
G03X458454Y341257I-232J-1484D01*
G01X458439D01*
G03X456952Y339755I15J-1502D01*
G03X458454Y338253I1502J0D01*
G03X459677Y338882I0J1503D01*
G02X459796Y338961I163J-116D01*
G01X459915Y338988D01*
G02X460058Y338967I44J-195D01*
G03X460950Y338730I893J1566D01*
G03X461209Y338749I-2J1803D01*
G01X461224Y338751D01*
X461238D01*
G02X461438Y338551I0J-200D01*
G01Y338525D01*
G02X461264Y338327I-200J0D01*
G01X461263D01*
G03Y335347I191J-1490D01*
G01X461264D01*
G02X461438Y335149I-26J-198D01*
G01Y333569D01*
G02X461264Y333371I-200J0D01*
G01X461263D01*
G03Y330391I191J-1490D01*
G01X461264D01*
G02X461438Y330193I-26J-198D01*
G01Y330167D01*
G02X461238Y329967I-200J0D01*
G01X461224D01*
X461209Y329969D01*
G03X460950Y329988I-261J-1784D01*
G03X460058Y329751I1J-1803D01*
G02X459915Y329730I-99J174D01*
G01X459796Y329757D01*
G02X459677Y329836I44J195D01*
G03X458454Y330465I-1223J-874D01*
G03Y327461I0J-1502D01*
G03X458686Y327479I0J1502D01*
G01X458729Y327486D01*
X458813Y327462D01*
X459078Y327236D01*
G02X459148Y327084I-130J-152D01*
G01Y326273D01*
G02X459089Y326132I-200J1D01*
G01X458524Y325567D01*
G02X458464Y325526I-141J142D01*
G01X458428Y325510D01*
X458390Y325508D01*
G03X456953Y324071I64J-1501D01*
G01X456951Y324034D01*
X456935Y323997D01*
G02X456894Y323937I-183J81D01*
G01X453786Y320829D01*
X453758Y320800D01*
X453684Y320770D01*
X437939D01*
G02X437752Y320898I0J200D01*
G01X437596Y321305D01*
X437625Y321425D01*
X437671Y321467D01*
G03X438168Y322583I-1004J1116D01*
G03X435164I-1502J0D01*
G03X435661Y321467I1501J0D01*
G01X435707Y321425D01*
X435736Y321305D01*
X435580Y320899D01*
G02X435569Y320875I-187J71D01*
G01X435568Y320874D01*
G02X435393Y320770I-175J96D01*
G01X429440D01*
G02X429272Y320862I0J200D01*
G01X429063Y321189D01*
X429056Y321291D01*
X429077Y321337D01*
G03X429215Y321965I-1364J629D01*
G03X426211I-1502J0D01*
G03X426349Y321337I1502J1D01*
G01X426370Y321291D01*
X426363Y321189D01*
X426154Y320862D01*
G02X425986Y320770I-168J108D01*
G01X418423D01*
G02X418282Y320829I1J200D01*
G01X418067Y321044D01*
G03X417174Y321414I-895J-897D01*
G01X395996D01*
G02X395854Y321473I0J200D01*
G01X393500Y323827D01*
X393471Y323855D01*
X393441Y323929D01*
Y336391D01*
G02X393445Y336428I200J-3D01*
G01X393455Y336483D01*
X393494Y336582D01*
X393517Y336608D01*
G03X393610Y336726I-1132J988D01*
G02X393729Y336805I163J-116D01*
G01X393848Y336832D01*
G02X393991Y336811I44J-195D01*
G03X394883Y336574I893J1566D01*
G03X396686Y338377I0J1803D01*
G01Y341777D01*
G03X396558Y342442I-1791J0D01*
G01X396537Y342495D01*
X396556Y342604D01*
X396863Y342958D01*
X396968Y342992D01*
X397023Y342978D01*
G03X397374Y342937I349J1461D01*
G03X395872Y344439I0J1502D01*
G03X395940Y343992I1503J0D01*
G01X395957Y343938D01*
X395930Y343831D01*
X395597Y343501D01*
X395489Y343475D01*
X395435Y343493D01*
G03X394883Y343580I-553J-1716D01*
G03X393991Y343343I1J-1803D01*
G02X393848Y343322I-99J174D01*
G01X393729Y343349D01*
G02X393610Y343428I44J195D01*
G03X393517Y343546I-1225J-870D01*
G01X393494Y343572D01*
X393455Y343671D01*
X393441Y343706D01*
Y349506D01*
G02X393498Y349646I200J0D01*
G01X393499Y349647D01*
X399380Y355528D01*
G02X399382Y355530I142J-140D01*
G02X399522Y355587I140J-143D01*
G01X405904D01*
G02X406006Y355559I0J-200D01*
G02X406080Y355482I-102J-172D01*
G01X406247Y355172D01*
G02X406270Y355068I-177J-94D01*
G01X406268Y355013D01*
X406238Y354967D01*
G03X405991Y354142I1254J-825D01*
G03X408995I1502J0D01*
G03X408748Y354967I-1501J0D01*
G01X408733Y354990D01*
X408717Y355040D01*
X408716Y355068D01*
G02X408739Y355172I200J10D01*
G01X408906Y355482D01*
G02X408980Y355559I176J-95D01*
G02X409082Y355587I102J-172D01*
G01X409945D01*
G02X410009Y355576I-1J-200D01*
G01X410098Y355546D01*
X410123Y355528D01*
G03X411206Y355254I884J1215D01*
G03X411891Y355528I-198J1489D01*
G01X411916Y355546D01*
X412005Y355576D01*
G02X412069Y355587I65J-189D01*
G01X424239D01*
G02X424384Y355524I-1J-200D01*
G01X424583Y355314D01*
G02X424624Y355250I-145J-138D01*
G01X424640Y355209D01*
X424638Y355166D01*
Y355160D01*
G03X424636Y355079I1500J-78D01*
G03X427640I1502J0D01*
G03X427638Y355160I-1502J3D01*
G01Y355166D01*
X427636Y355209D01*
X427652Y355250D01*
G02X427693Y355314I186J-74D01*
G01X427893Y355525D01*
G02X428038Y355587I145J-138D01*
G01X438836D01*
G02X439036Y355387I0J-200D01*
G01Y355372D01*
G03X442040I1502J0D01*
G01Y355387D01*
G02X442240Y355587I200J0D01*
G37*
G36*
G01X418269Y757629D02*
X423552Y762913D01*
G02X423770Y762956I141J-142D01*
G01X423827Y762932D01*
X423894Y762833D01*
Y762284D01*
G02X423835Y762143I-200J1D01*
G01X415921Y754229D01*
G02X415780Y754170I-142J141D01*
G01X401292D01*
G03X400368Y753788I-1J-1306D01*
G01X397805Y751224D01*
G02X397587Y751181I-141J142D01*
G01X397530Y751205D01*
X397464Y751304D01*
Y753649D01*
G02X397522Y753790I200J0D01*
G01X400920Y757188D01*
G02X401061Y757246I141J-142D01*
G01X417345D01*
G03X418269Y757629I0J1306D01*
G37*
G36*
G01X414432Y770177D02*
Y783049D01*
G02X414555Y783234I200J1D01*
G01X414612Y783257D01*
X414729Y783234D01*
X418237Y779726D01*
G02X418296Y779585I-141J-142D01*
G01Y770340D01*
G02X418237Y770199I-200J1D01*
G01X409923Y761885D01*
G02X409782Y761826I-142J141D01*
G01X399372D01*
G03X398448Y761444I-1J-1306D01*
G01X397441Y760437D01*
G02X397223Y760394I-141J141D01*
G01X397167Y760417D01*
X397100Y760517D01*
Y764169D01*
G02X397159Y764311I200J0D01*
G01X397383Y764535D01*
G02X397524Y764594I142J-141D01*
G01X408848D01*
G03X409772Y764976I1J1306D01*
G01X414049Y769253D01*
G03X414432Y770177I-923J924D01*
G37*
G36*
G01X404143Y767504D02*
X411477Y774839D01*
G02X411695Y774882I141J-142D01*
G01X411752Y774858D01*
X411818Y774759D01*
Y770801D01*
G02X411760Y770660I-200J0D01*
G01X408365Y767265D01*
G02X408224Y767206I-142J141D01*
G01X404328D01*
G02X404143Y767330I0J200D01*
G01X404120Y767387D01*
X404143Y767504D01*
G37*
G36*
G01X397159Y769715D02*
X401465Y774021D01*
G02X401683Y774064I141J-141D01*
G01X401739Y774041D01*
X401806Y773941D01*
Y773638D01*
G03X402004Y773466I198J28D01*
G01X405927D01*
G02X406111Y773343I-1J-200D01*
G01X406135Y773286D01*
X406112Y773168D01*
X401808Y768865D01*
G02X401667Y768806I-142J141D01*
G01X397300D01*
G02X397100Y769006I0J200D01*
G01Y769573D01*
G02X397159Y769715I200J0D01*
G37*
G36*
G01X448754Y822423D02*
X453428D01*
G02X453628Y822223I0J-200D01*
G01Y816059D01*
G02X453570Y815918I-200J0D01*
G01X435907Y798255D01*
G02X435751Y798197I-141J141D01*
G01X435405Y798222D01*
X435330Y798263D01*
X435304Y798298D01*
G03X434100Y798902I-1204J-898D01*
G03X432598Y797400I0J-1502D01*
G03X433202Y796196I1502J0D01*
G01X433237Y796170D01*
X433278Y796095D01*
X433303Y795749D01*
G02X433245Y795593I-199J-15D01*
G01X430317Y792665D01*
G02X430176Y792606I-142J141D01*
G01X426800D01*
G03X425876Y792224I-1J-1306D01*
G01X422476Y788824D01*
G03X422118Y788151I924J-923D01*
G01X422110Y788109D01*
X422063Y788041D01*
X421738Y787843D01*
X421656Y787832D01*
X421615Y787844D01*
G03X421200Y787902I-413J-1444D01*
G03Y784898I0J-1502D01*
G03X421590Y784949I2J1502D01*
G01X421635Y784962D01*
X421726Y784943D01*
X422015Y784722D01*
G02X422094Y784563I-121J-159D01*
G01Y765232D01*
G02X422035Y765091I-200J1D01*
G01X416862Y759918D01*
G02X416721Y759860I-141J142D01*
G01X412076D01*
G02X411891Y759983I-1J200D01*
G01X411868Y760040D01*
X411891Y760157D01*
X420526Y768792D01*
G03X420908Y769716I-924J923D01*
G01Y780209D01*
G03X420526Y781133I-1306J1D01*
G01X416865Y784794D01*
G02X416806Y784935I141J142D01*
G01Y790476D01*
G02X416865Y790617I200J-1D01*
G01X421571Y795324D01*
G02X421766Y795375I141J-142D01*
G01X422155Y795267D01*
X422229Y795191D01*
X422242Y795137D01*
G03X423700Y793998I1458J364D01*
G03X425202Y795500I0J1502D01*
G03X425198Y795605I-1502J-5D01*
G01X425195Y795657D01*
X425237Y795749D01*
X425596Y796011D01*
X425696Y796024D01*
X425745Y796004D01*
G03X426300Y795898I554J1396D01*
G03Y798902I0J1502D01*
G03X426146Y798894I1J-1502D01*
G01X426082Y798888D01*
X425973Y798949D01*
X425783Y799347D01*
G02X425822Y799575I181J86D01*
G01X448612Y822364D01*
G02X448754Y822423I142J-141D01*
G37*
G36*
G01X464361Y818113D02*
G03X464395Y818149I-933J915D01*
G02X464606Y818203I147J-136D01*
G01X464700Y818171D01*
G02X464836Y817981I-64J-190D01*
G01Y805340D01*
G02X464777Y805198I-200J0D01*
G01X462844Y803265D01*
G02X462703Y803206I-142J141D01*
G01X449937D01*
G02X449752Y803330I0J200D01*
G01X449729Y803387D01*
X449752Y803504D01*
X464361Y818113D01*
G37*
G36*
G01X639691Y1248439D02*
X639690D01*
G03X639567Y1248445I-120J-1196D01*
G03Y1246041I0J-1202D01*
G03X639690Y1246047I3J1202D01*
G01X639691D01*
G02X639845Y1245996I20J-199D01*
G01X640065Y1245798D01*
G02X640131Y1245649I-134J-149D01*
G01Y1245373D01*
G03X640153Y1245133I1303J-2D01*
G02X640154Y1245127I-196J-36D01*
G01X640157Y1245112D01*
X640129Y1245023D01*
X639876Y1244758D01*
G02X639707Y1244697I-145J137D01*
G03X639567Y1244705I-138J-1194D01*
G03Y1242301I0J-1202D01*
G03X639709Y1242310I-5J1202D01*
G01X639711D01*
X639757Y1242315D01*
X639845Y1242283D01*
X640132Y1241983D01*
X640160Y1241894D01*
X640155Y1241866D01*
G03X640134Y1241633I1281J-233D01*
G03X640156Y1241398I1302J3D01*
G01Y1241394D01*
X640160Y1241372D01*
X640132Y1241283D01*
X639845Y1240983D01*
X639757Y1240951D01*
X639710Y1240957D01*
G03X639567Y1240965I-139J-1194D01*
G03X640769Y1239763I0J-1202D01*
G03X640760Y1239905I-1202J-5D01*
G01Y1239908D01*
G02X640820Y1240074I199J22D01*
G01X641086Y1240329D01*
X641175Y1240357D01*
X641194Y1240354D01*
G03X641436Y1240331I244J1279D01*
G03X641636Y1240347I-3J1302D01*
G01X641639D01*
G02X641809Y1240291I29J-198D01*
G01X642086Y1240014D01*
X642116Y1239929D01*
X642111Y1239885D01*
G03X642105Y1239763I1196J-120D01*
G03X643307Y1238561I1202J0D01*
G03X643429Y1238567I2J1202D01*
G01X643473Y1238572D01*
X643558Y1238542D01*
X643617Y1238483D01*
G03X643667Y1238446I143J140D01*
G01X643679Y1238440D01*
G02X643752Y1238362I-104J-171D01*
G01X643799Y1238274D01*
X643860Y1238158D01*
G02X643880Y1238104I-176J-96D01*
G01X643885Y1238077D01*
X643881Y1238044D01*
G03X643872Y1237893I1294J-153D01*
G01Y1237616D01*
G02X643806Y1237467I-200J0D01*
G01X643554Y1237240D01*
X643472Y1237214D01*
X643431Y1237219D01*
G03X643307Y1237225I-120J-1196D01*
G03Y1234821I0J-1202D01*
G03X643431Y1234827I4J1202D01*
G01X643472Y1234832D01*
X643554Y1234806D01*
X643806Y1234579D01*
G02X643872Y1234430I-134J-149D01*
G01Y1234153D01*
G03X643894Y1233917I1303J2D01*
G01Y1233913D01*
X643898Y1233892D01*
X643870Y1233803D01*
X643583Y1233503D01*
X643495Y1233471D01*
X643448Y1233477D01*
G03X643307Y1233485I-138J-1194D01*
G03X644509Y1232283I0J-1202D01*
G03X644501Y1232425I-1202J3D01*
G01Y1232426D01*
G02X644561Y1232594I199J24D01*
G01X644826Y1232847D01*
X644916Y1232875D01*
X644963Y1232867D01*
G03X645175Y1232850I210J1286D01*
G03X645401Y1232870I-1J1302D01*
G01X645404D01*
X645438Y1232876D01*
X645527Y1232848D01*
X645793Y1232593D01*
G02X645854Y1232427I-138J-145D01*
G01Y1232426D01*
G03X645845Y1232283I1193J-147D01*
G03X647047Y1233485I1202J0D01*
G03X646903Y1233476I3J-1202D01*
G01X646856Y1233470D01*
X646768Y1233502D01*
X646481Y1233802D01*
X646453Y1233892D01*
X646461Y1233939D01*
G03X646478Y1234117I-1285J213D01*
G01Y1234430D01*
G02X646544Y1234579I200J0D01*
G01X646798Y1234806D01*
X646878Y1234832D01*
X646920Y1234828D01*
G03X647047Y1234821I130J1195D01*
G03X648249Y1236023I0J1202D01*
G03X648179Y1236427I-1201J0D01*
G02X648434Y1236683I188J67D01*
G03X648607Y1236628I480J1211D01*
G03X649154Y1236613I308J1265D01*
G01X649158D01*
X649178Y1236617D01*
X649267Y1236589D01*
X649533Y1236335D01*
G02X649594Y1236166I-137J-145D01*
G03X649585Y1236023I1193J-147D01*
G03X650787Y1234821I1202J0D01*
G03X650912Y1234827I5J1202D01*
G01X650953Y1234832D01*
X651035Y1234805D01*
X651287Y1234578D01*
G02X651353Y1234429I-134J-149D01*
G01Y1234149D01*
X651354Y1234140D01*
Y1234126D01*
G03X651363Y1233992I1302J20D01*
G01X651364Y1233985D01*
X651365Y1233981D01*
G03X651371Y1233939I1292J163D01*
G01X651379Y1233893D01*
X651351Y1233803D01*
X651098Y1233537D01*
G02X650930Y1233477I-144J139D01*
G01X650929D01*
G03X650787Y1233485I-139J-1194D01*
G03X651989Y1232283I0J-1202D01*
G03X651981Y1232426I-1202J4D01*
G01X651975Y1232473D01*
X652007Y1232561D01*
X652306Y1232848D01*
X652395Y1232876D01*
X652414Y1232873D01*
G03X652656Y1232850I244J1279D01*
G03X652884Y1232871I-5J1302D01*
G01X652888D01*
X652918Y1232876D01*
X653007Y1232848D01*
X653273Y1232593D01*
G02X653334Y1232427I-138J-145D01*
G01Y1232426D01*
G03X653325Y1232283I1193J-147D01*
G03X654527Y1233485I1202J0D01*
G03X654384Y1233477I-4J-1202D01*
G01X654337Y1233471D01*
X654249Y1233503D01*
X653962Y1233803D01*
X653934Y1233892D01*
X653938Y1233916D01*
G03X653960Y1234153I-1279J238D01*
G01Y1234430D01*
G02X654026Y1234579I200J0D01*
G01X654247Y1234778D01*
G02X654401Y1234828I134J-149D01*
G01X654402D01*
G03X654527Y1234821I130J1195D01*
G03X655729Y1236023I0J1202D01*
G03X655720Y1236166I-1202J-4D01*
G02X655781Y1236335I198J24D01*
G01X656047Y1236589D01*
X656136Y1236617D01*
X656158Y1236613D01*
G03X656574Y1236603I239J1280D01*
G03X656630Y1236612I-179J1290D01*
G01X656632D01*
X656659Y1236617D01*
X656748Y1236589D01*
X657014Y1236335D01*
G02X657075Y1236166I-137J-145D01*
G03X657066Y1236023I1193J-147D01*
G03X658268Y1234821I1202J0D01*
G03X658392Y1234827I4J1202D01*
G01X658433Y1234832D01*
X658515Y1234805D01*
X658767Y1234578D01*
G02X658833Y1234429I-134J-149D01*
G01Y1234153D01*
G03X658855Y1233917I1303J2D01*
G01Y1233913D01*
X658859Y1233892D01*
X658831Y1233803D01*
X658544Y1233503D01*
X658456Y1233471D01*
X658409Y1233477D01*
G03X658268Y1233485I-138J-1194D01*
G03X659470Y1232283I0J-1202D01*
G03X659462Y1232425I-1202J3D01*
G01Y1232426D01*
G02X659522Y1232594I199J24D01*
G01X659787Y1232847D01*
X659877Y1232875D01*
X659924Y1232867D01*
G03X660136Y1232850I210J1286D01*
G01X660169D01*
X660187Y1232851D01*
X660188D01*
G03X660368Y1232871I-53J1301D01*
G01X660372D01*
X660399Y1232876D01*
X660488Y1232848D01*
X660754Y1232593D01*
G02X660815Y1232427I-138J-145D01*
G01Y1232426D01*
G03X660806Y1232283I1193J-147D01*
G03X662008Y1233485I1202J0D01*
G03X661865Y1233476I4J-1202D01*
G02X661696Y1233537I-24J198D01*
G01X661442Y1233803D01*
X661415Y1233892D01*
X661419Y1233919D01*
G03X661440Y1234151I-1282J233D01*
G01Y1234430D01*
G02X661506Y1234579I200J0D01*
G01X661727Y1234778D01*
G02X661881Y1234828I134J-149D01*
G01X661882D01*
G03X662008Y1234821I130J1195D01*
G03X663210Y1236023I0J1202D01*
G03X663201Y1236165I-1202J-5D01*
G01Y1236168D01*
G02X663261Y1236334I199J22D01*
G01X663527Y1236589D01*
X663616Y1236617D01*
X663634Y1236614D01*
G03X664054Y1236603I244J1279D01*
G03X664110Y1236612I-179J1290D01*
G01X664112D01*
X664139Y1236617D01*
X664228Y1236589D01*
X664494Y1236335D01*
G02X664555Y1236166I-137J-145D01*
G03X664546Y1236023I1193J-147D01*
G03X665748Y1234821I1202J0D01*
G03X665872Y1234827I4J1202D01*
G01X665913Y1234832D01*
X665995Y1234805D01*
X666247Y1234578D01*
G02X666313Y1234429I-134J-149D01*
G01Y1234153D01*
G03X666335Y1233917I1303J2D01*
G01Y1233913D01*
X666339Y1233892D01*
X666311Y1233803D01*
X666024Y1233503D01*
X665936Y1233471D01*
X665889Y1233477D01*
G03X665748Y1233485I-138J-1194D01*
G03X666950Y1232283I0J-1202D01*
G03X666942Y1232425I-1202J3D01*
G01Y1232426D01*
G02X667002Y1232594I199J24D01*
G01X667267Y1232847D01*
X667357Y1232875D01*
X667404Y1232867D01*
G03X667616Y1232850I210J1286D01*
G01X667649D01*
X667667Y1232851D01*
X667668D01*
G03X667848Y1232871I-53J1301D01*
G01X667852D01*
X667879Y1232876D01*
X667968Y1232848D01*
X668234Y1232593D01*
G02X668295Y1232427I-138J-145D01*
G01Y1232426D01*
G03X668286Y1232283I1193J-147D01*
G03X669488Y1233485I1202J0D01*
G03X669345Y1233476I4J-1202D01*
G02X669176Y1233537I-24J198D01*
G01X668922Y1233803D01*
X668895Y1233892D01*
X668899Y1233919D01*
G03X668920Y1234151I-1282J233D01*
G01Y1234430D01*
G02X668986Y1234579I200J0D01*
G01X669207Y1234778D01*
G02X669361Y1234828I134J-149D01*
G01X669362D01*
G03X669488Y1234821I130J1195D01*
G03X670690Y1236023I0J1202D01*
G03X670681Y1236165I-1202J-5D01*
G01Y1236168D01*
G02X670741Y1236334I199J22D01*
G01X671007Y1236589D01*
X671096Y1236617D01*
X671114Y1236614D01*
G03X671534Y1236603I244J1279D01*
G03X671590Y1236612I-179J1290D01*
G01X671592D01*
X671619Y1236617D01*
X671708Y1236589D01*
X671974Y1236335D01*
G02X672035Y1236166I-137J-145D01*
G03X672026Y1236023I1193J-147D01*
G03X673228Y1234821I1202J0D01*
G03X673353Y1234827I5J1202D01*
G01X673394Y1234832D01*
X673476Y1234806D01*
X673728Y1234579D01*
G02X673794Y1234430I-134J-149D01*
G01Y1234153D01*
G03X673801Y1234022I1303J4D01*
G03X673812Y1233939I1296J130D01*
G01X673820Y1233892D01*
X673792Y1233803D01*
X673505Y1233503D01*
X673417Y1233471D01*
X673370Y1233477D01*
G03X673228Y1233485I-139J-1194D01*
G03X674430Y1232283I0J-1202D01*
G03X674422Y1232426I-1202J4D01*
G01X674416Y1232473D01*
X674448Y1232561D01*
X674747Y1232848D01*
X674836Y1232876D01*
X674855Y1232873D01*
G03X675097Y1232850I244J1279D01*
G01X675100D01*
G03X675325Y1232870I-2J1303D01*
G01X675327D01*
X675359Y1232875D01*
X675448Y1232848D01*
X675714Y1232593D01*
G02X675775Y1232427I-138J-145D01*
G01Y1232426D01*
G03X675766Y1232283I1193J-147D01*
G03X676968Y1233485I1202J0D01*
G03X676825Y1233476I4J-1202D01*
G01X676824D01*
G02X676656Y1233536I-24J199D01*
G01X676402Y1233802D01*
X676374Y1233891D01*
X676378Y1233917D01*
G03X676400Y1234153I-1281J238D01*
G01Y1234430D01*
G02X676466Y1234579I200J0D01*
G01X676687Y1234778D01*
G02X676841Y1234828I134J-149D01*
G01X676842D01*
G03X676968Y1234821I130J1195D01*
G03X678170Y1236023I0J1202D01*
G03X678161Y1236165I-1202J-5D01*
G01Y1236168D01*
G02X678221Y1236334I199J22D01*
G01X678487Y1236589D01*
X678576Y1236617D01*
X678595Y1236614D01*
G03X678837Y1236591I244J1279D01*
G03X679063Y1236611I-1J1302D01*
G01X679066D01*
X679100Y1236617D01*
X679189Y1236589D01*
X679490Y1236303D01*
X679522Y1236213D01*
X679516Y1236167D01*
G03X679507Y1236023I1193J-147D01*
G03X680709Y1234821I1202J0D01*
G03X680833Y1234828I-6J1202D01*
G01X680835D01*
G02X680989Y1234778I20J-199D01*
G01X681210Y1234579D01*
G02X681276Y1234430I-134J-149D01*
G01Y1234185D01*
X681275Y1234183D01*
Y1234153D01*
G03X681283Y1234011I1303J2D01*
G01X681285Y1233993D01*
Y1233992D01*
G03X681297Y1233918I1291J171D01*
G01Y1233913D01*
X681301Y1233892D01*
X681273Y1233803D01*
X680986Y1233503D01*
X680898Y1233471D01*
X680851Y1233477D01*
G03X680709Y1233485I-139J-1194D01*
G03X681911Y1232283I0J-1202D01*
G03X681903Y1232426I-1202J4D01*
G01X681897Y1232473D01*
X681929Y1232561D01*
X682228Y1232848D01*
X682317Y1232876D01*
X682335Y1232873D01*
G03X682578Y1232850I244J1280D01*
G03X682806Y1232871I-5J1302D01*
G01X682810D01*
X682840Y1232876D01*
X682929Y1232848D01*
X683195Y1232593D01*
G02X683256Y1232427I-138J-145D01*
G01Y1232426D01*
G03X683247Y1232283I1193J-147D01*
G03X684449Y1233485I1202J0D01*
G03X684306Y1233477I-4J-1202D01*
G01X684259Y1233471D01*
X684171Y1233503D01*
X683884Y1233803D01*
X683856Y1233892D01*
X683860Y1233916D01*
G03X683882Y1234153I-1279J238D01*
G01Y1234430D01*
G02X683948Y1234579I200J0D01*
G01X684169Y1234778D01*
G02X684323Y1234828I134J-149D01*
G01X684324D01*
G03X684449Y1234821I130J1195D01*
G03X685651Y1236023I0J1202D01*
G03X685581Y1236427I-1201J0D01*
G02X685836Y1236683I188J67D01*
G03X686009Y1236628I480J1211D01*
G03X686556Y1236613I308J1265D01*
G01X686560D01*
X686580Y1236617D01*
X686669Y1236589D01*
X686935Y1236335D01*
G02X686996Y1236166I-137J-145D01*
G03X686987Y1236023I1193J-147D01*
G03X688189Y1237225I1202J0D01*
G03X688045Y1237216I3J-1202D01*
G01X687998Y1237210D01*
X687910Y1237242D01*
X687623Y1237542D01*
X687595Y1237632D01*
X687603Y1237679D01*
G03X687619Y1237830I-1285J213D01*
G01X687621Y1237869D01*
X687635Y1237902D01*
G02X687679Y1237964I182J-83D01*
G01X687769Y1238052D01*
X687770Y1238053D01*
X687803Y1238085D01*
X687879Y1238158D01*
G02X688018Y1238214I139J-144D01*
G01X692098D01*
G02X692117Y1238213I-1J-200D01*
G02X692237Y1238158I-19J-199D01*
G01X692310Y1238088D01*
X692441Y1237962D01*
G02X692496Y1237835I-145J-138D01*
G01Y1237616D01*
G02X692430Y1237467I-200J0D01*
G01X692209Y1237268D01*
G02X692055Y1237218I-134J149D01*
G01X692054D01*
G03X691929Y1237225I-130J-1195D01*
G03Y1234821I0J-1202D01*
G03X692053Y1234828I-6J1202D01*
G01X692055D01*
G02X692209Y1234778I20J-199D01*
G01X692430Y1234579D01*
G02X692496Y1234430I-134J-149D01*
G01Y1234153D01*
G03X692518Y1233917I1303J2D01*
G01Y1233913D01*
X692522Y1233892D01*
X692494Y1233803D01*
X692207Y1233503D01*
X692119Y1233471D01*
X692072Y1233477D01*
G03X691929Y1233485I-139J-1194D01*
G03X693131Y1232283I0J-1202D01*
G03X693123Y1232426I-1202J4D01*
G01X693117Y1232473D01*
X693149Y1232561D01*
X693449Y1232848D01*
X693538Y1232875D01*
X693564Y1232871D01*
G03X693750Y1232851I232J1281D01*
G03X693790Y1232850I53J1302D01*
G01X693801D01*
G03X694121Y1232890I0J1303D01*
G03X694283Y1232943I-323J1262D01*
G02X694542Y1232705I65J-189D01*
G02X694537Y1232687I-195J44D01*
G03X694467Y1232283I1131J-404D01*
G03X695669Y1231081I1202J0D01*
G03X695811Y1231089I3J1202D01*
G01X695812D01*
G02X695980Y1231029I24J-199D01*
G01X696233Y1230763D01*
X696261Y1230673D01*
X696253Y1230627D01*
G03Y1230199I1285J-214D01*
G01X696261Y1230153D01*
X696233Y1230063D01*
X695980Y1229797D01*
G02X695812Y1229737I-144J139D01*
G01X695811D01*
G03X695669Y1229745I-139J-1194D01*
G03Y1227341I0J-1202D01*
G03X695812Y1227349I4J1202D01*
G01X695859Y1227355D01*
X695947Y1227323D01*
X696234Y1227023D01*
X696262Y1226934D01*
X696258Y1226910D01*
G03X696236Y1226673I1280J-238D01*
G01Y1226396D01*
G02X696170Y1226247I-200J0D01*
G01X695949Y1226048D01*
G02X695795Y1225998I-134J149D01*
G01X695794D01*
G03X695669Y1226005I-130J-1195D01*
G03Y1223601I0J-1202D01*
G03X695793Y1223608I-6J1202D01*
G01X695795D01*
G02X695949Y1223558I20J-199D01*
G01X696170Y1223359D01*
G02X696236Y1223210I-134J-149D01*
G01Y1222932D01*
G03X696251Y1222733I1302J-2D01*
G01Y1222731D01*
G03X696253Y1222718I1288J192D01*
G01X696261Y1222672D01*
X696233Y1222582D01*
X695980Y1222316D01*
G02X695812Y1222256I-144J139D01*
G01X695811D01*
G03X695669Y1222264I-139J-1194D01*
G03Y1219860I0J-1202D01*
G03X695812Y1219868I4J1202D01*
G01X695859Y1219874D01*
X695947Y1219842D01*
X696234Y1219542D01*
X696262Y1219453D01*
X696259Y1219435D01*
G03X696237Y1219138I1279J-244D01*
G03X696253Y1218978I1301J49D01*
G01X696261Y1218931D01*
X696233Y1218841D01*
X695980Y1218576D01*
G02X695812Y1218516I-144J139D01*
G01X695811D01*
G03X695669Y1218524I-139J-1194D01*
G03X694467Y1217322I0J-1202D01*
G03X694488Y1217100I1202J2D01*
G01X694497Y1217051D01*
X694468Y1216958D01*
X694163Y1216653D01*
X694070Y1216624D01*
X694021Y1216633D01*
G03X693799Y1216654I-224J-1181D01*
G03X695001Y1215452I0J-1202D01*
G03X694980Y1215674I-1202J-2D01*
G01X694971Y1215723D01*
X695000Y1215816D01*
X695305Y1216121D01*
X695398Y1216150D01*
X695447Y1216141D01*
G03X695669Y1216120I224J1181D01*
G03X695811Y1216128I3J1202D01*
G01X695812D01*
G02X695980Y1216068I24J-199D01*
G01X696233Y1215802D01*
X696261Y1215712D01*
X696253Y1215666D01*
G03X697422Y1214155I1285J-214D01*
G03X697510Y1214150I118J1297D01*
G01X697519D01*
G02X697640Y1214100I-12J-200D01*
G01X697856Y1213881D01*
G02X697905Y1213763I-150J-132D01*
G01X697906Y1213754D01*
Y1213414D01*
G02X697905Y1213391I-200J-3D01*
G02X697854Y1213279I-199J23D01*
G01X697652Y1213074D01*
G02X697588Y1213031I-141J141D01*
G01X697551Y1213015D01*
X697512Y1213014D01*
G03X696444Y1212419I26J-1302D01*
G03X697510Y1210410I1094J-707D01*
G01X697519D01*
G02X697640Y1210360I-12J-200D01*
G01X697856Y1210141D01*
G02X697905Y1210023I-150J-132D01*
G01X697906Y1210014D01*
Y1209674D01*
G02X697905Y1209651I-200J-3D01*
G02X697854Y1209539I-199J23D01*
G01X697652Y1209334D01*
G02X697588Y1209291I-141J141D01*
G01X697551Y1209275D01*
X697512Y1209274D01*
G03X696236Y1207972I26J-1302D01*
G03X697538Y1206670I1302J0D01*
G03X697682Y1206678I0J1302D01*
G01X697691Y1206679D01*
X697706D01*
G02X697906Y1206479I0J-200D01*
G01Y1206432D01*
G03X697909Y1206351I1501J15D01*
G01Y1206349D01*
G03X697959Y1206038I1499J81D01*
G01X697985Y1205947D01*
X697971Y1205922D01*
X697872Y1205796D01*
X697858Y1205778D01*
Y1205776D01*
X697725Y1205609D01*
G02X697654Y1205553I-156J125D01*
G01X697612Y1205533D01*
X697565Y1205534D01*
X697538D01*
G03Y1202930I0J-1302D01*
G03X697738Y1202945I3J1302D01*
G03X698839Y1204170I-200J1287D01*
G01X698841Y1204220D01*
X698864Y1204260D01*
G02X698927Y1204327I173J-100D01*
G01X699199Y1204507D01*
G02X699286Y1204538I109J-168D01*
G01X699334Y1204544D01*
X699379Y1204527D01*
G03X699517Y1204482I534J1403D01*
G03X699679Y1204447I398J1448D01*
G01X699682D01*
X699696Y1204444D01*
X699746Y1204428D01*
X699766Y1204419D01*
X699810Y1204397D01*
G02X699866Y1204354I-92J-178D01*
G01X699876Y1204343D01*
X699908Y1204306D01*
G02X699933Y1204269I-152J-130D01*
G01X699977Y1204168D01*
X699980Y1204134D01*
Y1204133D01*
G03X701278Y1202930I1298J99D01*
G03X702257Y1203373I0J1303D01*
G01X702261Y1203378D01*
X702274Y1203391D01*
G02X702330Y1203430I141J-142D01*
G01X702404Y1203466D01*
G02X702447Y1203481I87J-180D01*
G02X702489Y1203485I40J-196D01*
G01X703785D01*
G02X703819Y1203482I-1J-200D01*
G01X703865Y1203472D01*
X703867D01*
G02X703909Y1203458I-42J-196D01*
G01X703966Y1203431D01*
X703967Y1203430D01*
X703988D01*
X704048Y1203363D01*
G03X706000Y1203375I971J870D01*
G01X706004Y1203380D01*
X706022Y1203398D01*
G02X706066Y1203427I131J-151D01*
G01X706155Y1203469D01*
G02X706232Y1203485I78J-184D01*
G01X707525D01*
G02X707559Y1203482I-1J-200D01*
G01X707605Y1203472D01*
X707607D01*
G02X707649Y1203458I-42J-196D01*
G01X707706Y1203431D01*
X707707Y1203430D01*
X707728D01*
X707788Y1203363D01*
G03X709740Y1203375I971J870D01*
G01X709744Y1203380D01*
X709762Y1203398D01*
G02X709806Y1203427I131J-151D01*
G01X709895Y1203469D01*
G02X709972Y1203485I78J-184D01*
G01X711265D01*
G02X711299Y1203482I-1J-200D01*
G01X711345Y1203472D01*
X711347D01*
G02X711389Y1203458I-42J-196D01*
G01X711446Y1203431D01*
X711447Y1203430D01*
X711468D01*
X711528Y1203363D01*
G03X713480Y1203375I971J870D01*
G01X713484Y1203380D01*
X713502Y1203398D01*
G02X713546Y1203427I131J-151D01*
G01X713635Y1203469D01*
G02X713712Y1203485I78J-184D01*
G01X715005D01*
G02X715039Y1203482I-1J-200D01*
G01X715085Y1203472D01*
X715087D01*
G02X715129Y1203458I-42J-196D01*
G01X715186Y1203431D01*
X715187Y1203430D01*
X715208D01*
X715268Y1203363D01*
G03X717220Y1203375I971J870D01*
G01X717224Y1203380D01*
X717242Y1203398D01*
G02X717286Y1203427I131J-151D01*
G01X717375Y1203469D01*
G02X717452Y1203485I78J-184D01*
G01X718745D01*
G02X718779Y1203482I-1J-200D01*
G01X718825Y1203472D01*
X718827D01*
G02X718869Y1203458I-42J-196D01*
G01X718926Y1203431D01*
X718927Y1203430D01*
X718948D01*
X719008Y1203363D01*
G03X720960Y1203375I971J870D01*
G01X720964Y1203380D01*
X720982Y1203398D01*
G02X721026Y1203427I131J-151D01*
G01X721115Y1203469D01*
G02X721192Y1203485I78J-184D01*
G01X722485D01*
G02X722519Y1203482I-1J-200D01*
G01X722565Y1203472D01*
X722567D01*
G02X722609Y1203458I-42J-196D01*
G01X722666Y1203431D01*
X722667Y1203430D01*
X722688D01*
X722748Y1203363D01*
G03X724700Y1203375I971J870D01*
G01X724704Y1203380D01*
X724722Y1203398D01*
G02X724766Y1203427I131J-151D01*
G01X724855Y1203469D01*
G02X724932Y1203485I78J-184D01*
G01X726267D01*
X726313Y1203476D01*
X726436Y1203418D01*
X726461Y1203391D01*
G03X726480Y1203372I929J910D01*
G01X726484Y1203368D01*
X726491Y1203360D01*
G03X726971Y1203025I966J873D01*
G02X726975Y1203023I-87J-179D01*
G01X727011Y1203008D01*
X727076Y1202909D01*
Y1202824D01*
G03X727171Y1202170I2305J1D01*
G01Y1202168D01*
G02X727160Y1202028I-192J-55D01*
G01X727015Y1201717D01*
X726976Y1201700D01*
G03X727435Y1199189I483J-1209D01*
G01X727438D01*
G02X727575Y1199129I-6J-200D01*
G01X727771Y1198929D01*
G02X727828Y1198789I-143J-140D01*
G01Y1198426D01*
X727827Y1198417D01*
Y1198416D01*
X727826Y1198406D01*
G02X727757Y1198269I-199J15D01*
G01X727712Y1198231D01*
G03X727698Y1198218I129J-153D01*
G01X727643Y1198161D01*
X727579Y1198095D01*
X727578Y1198094D01*
G02X727514Y1198050I-143J140D01*
G01X727478Y1198035D01*
X727440Y1198033D01*
X727438D01*
G03Y1195431I41J-1301D01*
G01X727440D01*
X727478Y1195429D01*
X727514Y1195414D01*
G02X727578Y1195370I-79J-184D01*
G01X727579Y1195369D01*
X727643Y1195303D01*
X727779Y1195161D01*
G02X727828Y1195041I-151J-132D01*
G01Y1194776D01*
G03X727829Y1194737I1502J19D01*
G01Y1194735D01*
X727830Y1194681D01*
X727808Y1194633D01*
G02X727776Y1194585I-181J86D01*
G01X727739Y1194547D01*
Y1194545D01*
X727573Y1194370D01*
G02X727481Y1194319I-140J143D01*
G01X727475Y1194318D01*
G02X727470Y1194317I-42J196D01*
G01X727452Y1194313D01*
X727433D01*
G03X726157Y1193011I26J-1302D01*
G03X727459Y1191709I1302J0D01*
G03X728660Y1192506I0J1303D01*
G01X728669Y1192527D01*
X728702Y1192572D01*
X728711Y1192584D01*
G02X728816Y1192649I153J-129D01*
G01X729044Y1192695D01*
X729149Y1192716D01*
G02X729316Y1192665I31J-197D01*
G01X729422Y1192561D01*
Y1192560D01*
X729548Y1192434D01*
G02X729601Y1192332I-143J-139D01*
G02X729605Y1192294I-196J-40D01*
G01Y1110455D01*
G02X729552Y1110320I-200J1D01*
G01X729368Y1110120D01*
G02X729236Y1110056I-147J135D01*
G03Y1107660I95J-1198D01*
G02X729368Y1107596I-15J-199D01*
G01X729552Y1107396D01*
G02X729605Y1107261I-147J-136D01*
G01Y1106714D01*
G02X729552Y1106579I-200J1D01*
G01X729368Y1106379D01*
G02X729236Y1106315I-147J135D01*
G03Y1103919I95J-1198D01*
G02X729368Y1103855I-15J-199D01*
G01X729552Y1103655D01*
G02X729605Y1103520I-147J-136D01*
G01Y1102974D01*
G02X729552Y1102839I-200J1D01*
G01X729368Y1102639D01*
G02X729236Y1102575I-147J135D01*
G03Y1100179I95J-1198D01*
G02X729368Y1100115I-15J-199D01*
G01X729552Y1099915D01*
G02X729605Y1099780I-147J-136D01*
G01Y1099234D01*
G02X729552Y1099099I-200J1D01*
G01X729341Y1098870D01*
X729274Y1098838D01*
X729236Y1098835D01*
G03Y1096439I94J-1198D01*
G01X729274Y1096436D01*
X729341Y1096404D01*
X729552Y1096175D01*
G02X729605Y1096040I-147J-136D01*
G01Y1095494D01*
G02X729552Y1095359I-200J1D01*
G01X729341Y1095130D01*
X729274Y1095098D01*
X729236Y1095095D01*
G03X728128Y1093897I94J-1198D01*
G01Y1093895D01*
G03X728198Y1093492I1202J1D01*
G02X727948Y1093234I-188J-68D01*
G03X727872Y1093262I-488J-1208D01*
G03X727460Y1093329I-412J-1236D01*
G01X727459D01*
G03X727220Y1093307I-1J-1303D01*
G02X727214Y1093306I-36J196D01*
G01X727198Y1093303D01*
X727109Y1093331D01*
X726843Y1093586D01*
G02X726783Y1093752I139J144D01*
G01Y1093754D01*
G03X726792Y1093897I-1193J147D01*
G03X725590Y1095099I-1202J0D01*
G03X725465Y1095092I5J-1202D01*
G01X725463D01*
G02X725309Y1095142I-20J199D01*
G01X725088Y1095341D01*
G02X725022Y1095490I134J149D01*
G01Y1095669D01*
G03Y1095698I-1302J14D01*
G01Y1095767D01*
G03X725000Y1096000I-1303J-5D01*
G01Y1096006D01*
X724996Y1096029D01*
X725024Y1096118D01*
X725278Y1096384D01*
G02X725446Y1096444I144J-139D01*
G01X725447D01*
G03X725590Y1096435I147J1193D01*
G03X724388Y1097637I0J1202D01*
G03X724397Y1097495I1202J5D01*
G01Y1097493D01*
X724402Y1097447D01*
X724370Y1097359D01*
X724070Y1097072D01*
X723981Y1097045D01*
X723948Y1097050D01*
G03X723722Y1097070I-227J-1283D01*
G01X723719D01*
G03X723483Y1097048I2J-1303D01*
G01X723479D01*
X723458Y1097044D01*
X723369Y1097072D01*
X723069Y1097359D01*
X723037Y1097447D01*
X723043Y1097494D01*
G03X723051Y1097637I-1194J139D01*
G03X721849Y1096435I-1202J0D01*
G03X721992Y1096443I4J1202D01*
G01X722039Y1096449D01*
X722127Y1096417D01*
X722414Y1096117D01*
X722442Y1096028D01*
X722438Y1096005D01*
G03X722416Y1095767I1281J-238D01*
G01Y1095490D01*
G02X722350Y1095341I-200J0D01*
G01X722129Y1095142D01*
G02X721975Y1095092I-134J149D01*
G01X721974D01*
G03X721849Y1095099I-130J-1195D01*
G03X720647Y1093897I0J-1202D01*
G03X720656Y1093754I1202J4D01*
G02X720595Y1093585I-198J-24D01*
G01X720329Y1093331D01*
X720240Y1093304D01*
X720220Y1093307D01*
G03X719992Y1093329I-239J-1280D01*
G03X719766Y1093312I-16J-1302D01*
G01X719719Y1093304D01*
X719629Y1093332D01*
X719363Y1093587D01*
G02X719303Y1093753I139J144D01*
G01Y1093754D01*
G03X719312Y1093897I-1193J147D01*
G03X718110Y1095099I-1202J0D01*
G03X717985Y1095092I5J-1202D01*
G01X717983D01*
G02X717829Y1095142I-20J199D01*
G01X717608Y1095341D01*
G02X717542Y1095490I134J149D01*
G01Y1095767D01*
G03X717520Y1096002I-1301J-3D01*
G01Y1096006D01*
X717516Y1096028D01*
X717544Y1096117D01*
X717798Y1096383D01*
G02X717967Y1096444I145J-137D01*
G03X718110Y1096435I147J1193D01*
G03X716908Y1097637I0J1202D01*
G03X716917Y1097495I1202J5D01*
G01Y1097493D01*
X716922Y1097447D01*
X716890Y1097359D01*
X716590Y1097072D01*
X716501Y1097044D01*
X716471Y1097049D01*
G03X716239Y1097070I-233J-1281D01*
G01X716238D01*
G03X715999Y1097048I-1J-1302D01*
G02X715993Y1097047I-36J196D01*
G01X715977Y1097044D01*
X715888Y1097072D01*
X715589Y1097359D01*
X715557Y1097447D01*
X715563Y1097494D01*
G03X715571Y1097637I-1194J139D01*
G03X714369Y1096435I-1202J0D01*
G03X714512Y1096443I4J1202D01*
G01X714559Y1096449D01*
X714647Y1096417D01*
X714934Y1096118D01*
X714962Y1096029D01*
X714959Y1096010D01*
G03X714936Y1095769I1279J-244D01*
G01Y1095490D01*
G02X714870Y1095341I-200J0D01*
G01X714649Y1095142D01*
G02X714495Y1095092I-134J149D01*
G01X714494D01*
G03X714369Y1095099I-130J-1195D01*
G03X713167Y1093897I0J-1202D01*
G03X713176Y1093754I1202J4D01*
G02X713115Y1093585I-198J-24D01*
G01X712849Y1093331D01*
X712760Y1093304D01*
X712740Y1093307D01*
G03X712512Y1093329I-239J-1280D01*
G03X712286Y1093312I-16J-1302D01*
G01X712239Y1093304D01*
X712149Y1093332D01*
X711883Y1093587D01*
G02X711823Y1093753I139J144D01*
G01Y1093754D01*
G03X711832Y1093897I-1193J147D01*
G03X710630Y1095099I-1202J0D01*
G03X710505Y1095092I5J-1202D01*
G01X710503D01*
G02X710349Y1095142I-20J199D01*
G01X710128Y1095341D01*
G02X710062Y1095490I134J149D01*
G01Y1095767D01*
G03X710040Y1096002I-1301J-3D01*
G01Y1096006D01*
X710036Y1096028D01*
X710064Y1096117D01*
X710318Y1096383D01*
G02X710487Y1096444I145J-137D01*
G03X710630Y1096435I147J1193D01*
G03X709428Y1097637I0J1202D01*
G03X709437Y1097495I1202J5D01*
G01Y1097493D01*
X709442Y1097447D01*
X709410Y1097359D01*
X709110Y1097072D01*
X709021Y1097044D01*
X708991Y1097049D01*
G03X708759Y1097070I-233J-1281D01*
G01X708758D01*
G03X708519Y1097048I-1J-1302D01*
G02X708513Y1097047I-36J196D01*
G01X708497Y1097044D01*
X708408Y1097072D01*
X708109Y1097359D01*
X708077Y1097447D01*
X708083Y1097494D01*
G03X708091Y1097637I-1194J139D01*
G03X706889Y1096435I-1202J0D01*
G03X707032Y1096443I4J1202D01*
G01X707079Y1096449D01*
X707167Y1096417D01*
X707454Y1096118D01*
X707482Y1096029D01*
X707479Y1096010D01*
G03X707456Y1095769I1279J-244D01*
G01Y1095490D01*
G02X707390Y1095341I-200J0D01*
G01X707169Y1095142D01*
G02X707015Y1095092I-134J149D01*
G01X707014D01*
G03X706889Y1095099I-130J-1195D01*
G03X705687Y1093897I0J-1202D01*
G03X705696Y1093754I1202J4D01*
G02X705635Y1093585I-198J-24D01*
G01X705369Y1093331D01*
X705280Y1093304D01*
X705260Y1093307D01*
G03X704780I-240J-1280D01*
G01X704776D01*
X704758Y1093304D01*
X704669Y1093331D01*
X704403Y1093585D01*
G02X704342Y1093754I137J145D01*
G03X704351Y1093897I-1193J147D01*
G03X703149Y1095099I-1202J0D01*
G03X703025Y1095092I6J-1202D01*
G01X703023D01*
G02X702869Y1095142I-20J199D01*
G01X702648Y1095341D01*
G02X702582Y1095490I134J149D01*
G01Y1095667D01*
G03Y1095676I-1303J5D01*
G01Y1095767D01*
G03X702560Y1096003I-1303J-2D01*
G01Y1096007D01*
X702556Y1096028D01*
X702584Y1096117D01*
X702871Y1096417D01*
X702959Y1096449D01*
X703006Y1096443D01*
G03X703149Y1096435I139J1194D01*
G03X701947Y1097637I0J1202D01*
G03X701955Y1097494I1202J-4D01*
G01X701961Y1097447D01*
X701929Y1097359D01*
X701629Y1097072D01*
X701540Y1097044D01*
X701517Y1097048D01*
G03X701279Y1097070I-238J-1281D01*
G03X701044Y1097049I-2J-1302D01*
G01X701042D01*
X701017Y1097045D01*
X700928Y1097072D01*
X700662Y1097327D01*
G02X700601Y1097493I138J145D01*
G01Y1097494D01*
G03X700610Y1097637I-1193J147D01*
G03X699408Y1096435I-1202J0D01*
G03X699551Y1096444I-4J1202D01*
G01X699552D01*
G02X699720Y1096384I24J-199D01*
G01X699974Y1096118D01*
X700002Y1096029D01*
X699998Y1096003D01*
G03X699976Y1095767I1281J-238D01*
G01Y1095490D01*
G02X699910Y1095341I-200J0D01*
G01X699689Y1095142D01*
G02X699535Y1095092I-134J149D01*
G01X699534D01*
G03X699408Y1095099I-130J-1195D01*
G03X698206Y1093897I0J-1202D01*
G03X698215Y1093754I1202J4D01*
G02X698154Y1093585I-198J-24D01*
G01X697888Y1093331D01*
X697799Y1093304D01*
X697779Y1093307D01*
G03X697551Y1093329I-239J-1280D01*
G03X697325Y1093312I-16J-1302D01*
G01X697278Y1093304D01*
X697188Y1093332D01*
X696922Y1093587D01*
G02X696862Y1093753I139J144D01*
G01Y1093754D01*
G03X696871Y1093897I-1193J147D01*
G03X695669Y1095099I-1202J0D01*
G03X695544Y1095092I5J-1202D01*
G01X695542D01*
G02X695388Y1095142I-20J199D01*
G01X695167Y1095341D01*
G02X695101Y1095490I134J149D01*
G01Y1095767D01*
G03X695079Y1096002I-1301J-3D01*
G01Y1096006D01*
X695075Y1096028D01*
X695103Y1096117D01*
X695357Y1096383D01*
G02X695526Y1096444I145J-137D01*
G03X695669Y1096435I147J1193D01*
G03X694467Y1097637I0J1202D01*
G03X694476Y1097495I1202J5D01*
G01Y1097493D01*
X694481Y1097447D01*
X694449Y1097359D01*
X694149Y1097072D01*
X694060Y1097044D01*
X694032Y1097049D01*
G03X693810Y1097070I-233J-1281D01*
G01X693797D01*
G03X693557Y1097048I-2J-1303D01*
G02X693551Y1097047I-36J196D01*
G01X693536Y1097044D01*
X693447Y1097072D01*
X693148Y1097359D01*
X693116Y1097447D01*
X693122Y1097494D01*
G03X693130Y1097637I-1194J139D01*
G03X691928Y1096435I-1202J0D01*
G03X692070Y1096443I3J1202D01*
G01X692117Y1096449D01*
X692205Y1096417D01*
X692492Y1096117D01*
X692520Y1096028D01*
X692516Y1096005D01*
G03X692494Y1095767I1281J-238D01*
G01Y1095490D01*
G02X692428Y1095341I-200J0D01*
G01X692176Y1095114D01*
X692094Y1095088D01*
X692053Y1095093D01*
G03X691928Y1095099I-120J-1196D01*
G03X690726Y1093897I0J-1202D01*
G03X691789Y1092703I1202J0D01*
G01X691845Y1092697D01*
X691935Y1092625D01*
X692073Y1092230D01*
G02X692025Y1092023I-189J-65D01*
G01X690063Y1090061D01*
G02X689856Y1090013I-142J141D01*
G01X689461Y1090151D01*
X689389Y1090241D01*
X689383Y1090297D01*
G03X688189Y1091359I-1194J-140D01*
G03X686987Y1090157I0J-1202D01*
G03X686996Y1090013I1202J3D01*
G01X687002Y1089967D01*
X686970Y1089877D01*
X686669Y1089591D01*
X686580Y1089564D01*
X686548Y1089569D01*
G03X686318Y1089589I-227J-1284D01*
G03X686079Y1089567I-1J-1302D01*
G02X686073Y1089566I-36J196D01*
G01X686057Y1089563D01*
X685968Y1089591D01*
X685702Y1089846D01*
G02X685642Y1090012I139J144D01*
G01Y1090014D01*
G03X685651Y1090157I-1193J147D01*
G03X684449Y1088955I-1202J0D01*
G03X684592Y1088963I4J1202D01*
G01X684639Y1088969D01*
X684727Y1088937D01*
X685014Y1088637D01*
X685042Y1088548D01*
X685038Y1088524D01*
G03X685016Y1088287I1280J-238D01*
G01Y1088286D01*
G03X685038Y1088047I1302J-1D01*
G01Y1088044D01*
X685041Y1088026D01*
X685014Y1087937D01*
X684727Y1087637D01*
X684639Y1087605D01*
X684592Y1087611D01*
G03X684449Y1087619I-139J-1194D01*
G03Y1085215I0J-1202D01*
G03X684590Y1085223I3J1202D01*
G02X684759Y1085162I24J-198D01*
G01X685012Y1084897D01*
X685040Y1084808D01*
X685035Y1084779D01*
G03X685014Y1084547I1282J-233D01*
G01Y1084270D01*
G02X684948Y1084121I-200J0D01*
G01X684696Y1083894D01*
X684614Y1083868D01*
X684573Y1083873D01*
G03X684449Y1083879I-120J-1196D01*
G03Y1081475I0J-1202D01*
G03X684573Y1081481I4J1202D01*
G01X684614Y1081486D01*
X684696Y1081460D01*
X684948Y1081233D01*
G02X685014Y1081084I-134J-149D01*
G01Y1080806D01*
G03X685036Y1080570I1302J2D01*
G01Y1080566D01*
X685040Y1080545D01*
X685012Y1080456D01*
X684725Y1080156D01*
X684637Y1080124D01*
X684590Y1080130D01*
G03X684449Y1080138I-138J-1194D01*
G03Y1077734I0J-1202D01*
G03X684592Y1077742I4J1202D01*
G01X684639Y1077748D01*
X684727Y1077716D01*
X685014Y1077416D01*
X685041Y1077327D01*
X685038Y1077306D01*
G03X685016Y1077067I1280J-238D01*
G01Y1077065D01*
G03X685038Y1076828I1302J1D01*
G01Y1076824D01*
X685041Y1076805D01*
X685014Y1076716D01*
X684727Y1076416D01*
X684639Y1076384D01*
X684592Y1076390D01*
G03X684449Y1076398I-139J-1194D01*
G03Y1073994I0J-1202D01*
G03X684592Y1074002I4J1202D01*
G01X684639Y1074008D01*
X684727Y1073976D01*
X685014Y1073676D01*
X685041Y1073587D01*
X685038Y1073566D01*
G03X685016Y1073327I1280J-238D01*
G01Y1073325D01*
G03X685037Y1073096I1302J4D01*
G01Y1073092D01*
X685042Y1073064D01*
X685014Y1072975D01*
X684728Y1072674D01*
X684638Y1072642D01*
X684592Y1072648D01*
G03X684448Y1072657I-147J-1193D01*
G03Y1070253I0J-1202D01*
G03X685047Y1070413I0J1202D01*
G02X685050Y1070415I112J-165D01*
G02X685147Y1070440I97J-175D01*
G01X685148D01*
G02X685348Y1070240I0J-200D01*
G01Y1070211D01*
G02X685290Y1070070I-200J0D01*
G01X684292Y1069072D01*
G02X684242Y1069036I-140J142D01*
G02X684151Y1069014I-91J178D01*
G01X592650D01*
G02X592614Y1069017I-1J200D01*
G01X592561Y1069027D01*
X592553Y1069030D01*
G02X592499Y1069064I78J184D01*
G01Y1069065D01*
G02X592437Y1069165I131J151D01*
G01X592434Y1069180D01*
X592433Y1069187D01*
G03X576087Y1085201I-18615J-2652D01*
G03X555202Y1069186I-2270J-18665D01*
G01Y1069184D01*
G02X555135Y1069062I-198J29D01*
G01X555109Y1069039D01*
X555042Y1069014D01*
X545714D01*
G02X545623Y1069036I0J200D01*
G02X545573Y1069072I90J178D01*
G01X541060Y1073585D01*
G02X541002Y1073743I141J142D01*
G02X541006Y1073768I199J-19D01*
G01X541072Y1074077D01*
X541076Y1074097D01*
X541080Y1074110D01*
G02X541125Y1074191I193J-54D01*
G01X541140Y1074207D01*
X541177Y1074232D01*
X541200Y1074241D01*
G03X549720Y1086654I-4782J12413D01*
G03X536418Y1099956I-13302J0D01*
G03X532674Y1099418I1J-13302D01*
G01X532672D01*
G02X532498Y1099450I-55J192D01*
G01X532370Y1099546D01*
X532236Y1099646D01*
G02X532161Y1099802I125J156D01*
G01Y1110768D01*
G03X532137Y1110864I-200J1D01*
G01X532114Y1110906D01*
X532102Y1110949D01*
Y1110989D01*
X532132Y1111062D01*
X532373Y1111302D01*
G03X532812Y1112362I-1062J1061D01*
G01Y1120328D01*
G03X532373Y1121388I-1501J-1D01*
G01X532161Y1121599D01*
G02X532102Y1121741I141J142D01*
G01Y1210997D01*
G03X532043Y1211139I-200J0D01*
G01X528250Y1214932D01*
G03X528108Y1214991I-142J-141D01*
G01X474948D01*
G02X474857Y1215013I0J200D01*
G02X474807Y1215049I90J178D01*
G01X471047Y1218809D01*
G02X471011Y1218859I142J140D01*
G02X470989Y1218950I178J91D01*
G01Y1296502D01*
G02X470993Y1296540I200J-2D01*
G02X471046Y1296642I196J-37D01*
G01X473796Y1299392D01*
G02X473898Y1299445I139J-143D01*
G02X473936Y1299449I40J-196D01*
G01X488243D01*
G03X488300Y1299447I81J1499D01*
G01X488302D01*
G03X488359Y1299449I-24J1501D01*
G01X580434D01*
G02X580544Y1299416I0J-200D01*
G01X639426Y1260359D01*
G02X639513Y1260157I-110J-167D01*
G01X639447Y1259795D01*
G02X639296Y1259636I-197J36D01*
G03X638365Y1258465I271J-1171D01*
G03X639567Y1257263I1202J0D01*
G03X639709Y1257272I-5J1202D01*
G01X639711D01*
X639757Y1257277D01*
X639845Y1257245D01*
X640132Y1256945D01*
X640160Y1256856D01*
X640155Y1256826D01*
G03X640134Y1256594I1281J-233D01*
G03X640155Y1256362I1302J1D01*
G01Y1256359D01*
X640160Y1256333D01*
X640132Y1256244D01*
X639877Y1255978D01*
G02X639711Y1255917I-145J138D01*
G01X639710D01*
G03X639567Y1255926I-147J-1193D01*
G03Y1253522I0J-1202D01*
G03X639709Y1253531I-5J1202D01*
G01X639711D01*
X639757Y1253536D01*
X639845Y1253504D01*
X640132Y1253204D01*
X640160Y1253115D01*
X640155Y1253087D01*
G03X640134Y1252854I1281J-233D01*
G03X640155Y1252622I1302J1D01*
G01Y1252619D01*
X640160Y1252593D01*
X640132Y1252504D01*
X639877Y1252238D01*
G02X639711Y1252177I-145J138D01*
G01X639710D01*
G03X639567Y1252186I-147J-1193D01*
G03Y1249782I0J-1202D01*
G03X639708Y1249790I3J1202D01*
G01X639754Y1249796D01*
X639844Y1249764D01*
X640129Y1249464D01*
X640156Y1249375D01*
X640151Y1249342D01*
G03X640131Y1249116I1283J-227D01*
G01Y1248837D01*
G02X640065Y1248688I-200J0D01*
G01X639845Y1248490D01*
G02X639691Y1248439I-134J148D01*
G37*
G36*
G01X536462Y645677D02*
X544301Y653516D01*
G02X544584I142J-141D01*
G01X545535Y652565D01*
G02X545594Y652424I-141J-142D01*
G01Y607297D01*
G02X545518Y607141I-200J1D01*
G01X545237Y606917D01*
X545150Y606897D01*
X545104Y606907D01*
G03X544770Y606945I-336J-1464D01*
G03Y603941I0J-1502D01*
G03X545104Y603979I-2J1502D01*
G01X545150Y603989D01*
X545237Y603969D01*
X545518Y603745D01*
G02X545594Y603589I-124J-157D01*
G01Y583506D01*
G02X545517Y583348I-200J0D01*
G01X545232Y583125D01*
X545143Y583106D01*
X545098Y583117D01*
G03X544738Y583161I-361J-1458D01*
G03Y580157I0J-1502D01*
G03X545098Y580201I-1J1502D01*
G01X545143Y580212D01*
X545232Y580193D01*
X545517Y579970D01*
G02X545594Y579812I-123J-158D01*
G01Y482315D01*
G02X545535Y482174I-200J1D01*
G01X529620Y466259D01*
G02X529479Y466200I-142J141D01*
G01X517512D01*
G02X517327Y466324I0J200D01*
G01X517304Y466381D01*
X517327Y466498D01*
X518234Y467405D01*
G03X518616Y468329I-924J923D01*
G01Y469277D01*
X518628Y469324D01*
X518639Y469346D01*
G03X518812Y470045I-1329J700D01*
G03X515808I-1502J0D01*
G03X515981Y469346I1502J1D01*
G01X515992Y469324D01*
X516004Y469277D01*
Y468953D01*
G02X515945Y468812I-200J1D01*
G01X515423Y468290D01*
G02X515282Y468232I-141J142D01*
G01X506142D01*
G02X505959Y468350I-1J200D01*
G01X505786Y468739D01*
X505804Y468855D01*
X505845Y468899D01*
G03X506231Y469905I-1116J1005D01*
G03X504729Y471407I-1502J0D01*
G03X504478Y471386I-1J-1502D01*
G01X504434Y471378D01*
X504350Y471401D01*
X504082Y471628D01*
G02X504012Y471780I130J152D01*
G01Y473844D01*
G03X503629Y474768I-1306J0D01*
G01X502225Y476172D01*
G02X502166Y476313I141J142D01*
G01Y480680D01*
X502229Y480778D01*
X502282Y480803D01*
G03X503151Y482165I-633J1362D01*
G03X502095Y483599I-1502J0D01*
G01X502072Y483607D01*
X502030Y483632D01*
X498563Y487099D01*
G02X498504Y487240I141J142D01*
G01Y499386D01*
G03X498122Y500310I-1306J1D01*
G01X497859Y500573D01*
G02X497800Y500715I141J142D01*
G01Y502017D01*
G03X497741Y502159I-200J0D01*
G01X497173Y502727D01*
G02X497120Y502916I141J142D01*
G01X497214Y503300D01*
X497286Y503376D01*
X497336Y503392D01*
G03X497874Y503693I-449J1433D01*
G01X497902Y503717D01*
X497969Y503742D01*
X498305D01*
X498372Y503717D01*
X498400Y503693D01*
G03X500374I987J1131D01*
G01X500402Y503717D01*
X500469Y503742D01*
X500805D01*
X500872Y503717D01*
X500900Y503693D01*
G03X501887Y503323I987J1131D01*
G03Y506327I0J1502D01*
G03X500900Y505957I0J-1501D01*
G01X500872Y505933D01*
X500805Y505908D01*
X500469D01*
X500402Y505933D01*
X500374Y505957D01*
G03X498400I-987J-1131D01*
G01X498372Y505933D01*
X498305Y505908D01*
X497969D01*
X497902Y505933D01*
X497874Y505957D01*
G03X496887Y506327I-987J-1131D01*
G03X495454Y505274I0J-1502D01*
G01X495438Y505224D01*
X495362Y505152D01*
X494978Y505058D01*
G02X494789Y505111I-47J194D01*
G01X484270Y515630D01*
G02X484212Y515771I142J141D01*
G01Y526958D01*
X484223Y527005D01*
X484234Y527027D01*
G03X484407Y527726I-1329J700D01*
G03X484136Y528586I-1502J-1D01*
G02X484100Y528701I164J115D01*
G01Y530751D01*
G02X484136Y530866I200J0D01*
G03X484407Y531726I-1231J861D01*
G03X484136Y532586I-1502J-1D01*
G02X484100Y532701I164J115D01*
G01Y533381D01*
G02X484128Y533483I200J0D01*
G03Y535015I-1292J766D01*
G02X484100Y535117I172J102D01*
G01Y536583D01*
X484116Y536620D01*
G03Y537810I-1378J595D01*
G01X484100Y537847D01*
Y539751D01*
G02X484136Y539866I200J0D01*
G03X484407Y540726I-1231J861D01*
G03X484136Y541586I-1502J-1D01*
G02X484100Y541701I164J115D01*
G01Y543751D01*
G02X484136Y543866I200J0D01*
G03X484407Y544726I-1231J861D01*
G03X484136Y545586I-1502J-1D01*
G02X484100Y545701I164J115D01*
G01Y547751D01*
G02X484136Y547866I200J0D01*
G03X484407Y548726I-1231J861D01*
G03X484136Y549586I-1502J-1D01*
G02X484100Y549701I164J115D01*
G01Y551751D01*
G02X484136Y551866I200J0D01*
G03X484407Y552726I-1231J861D01*
G03X484136Y553586I-1502J-1D01*
G02X484100Y553701I164J115D01*
G01Y619429D01*
G02X484169Y619580I200J0D01*
G01X484431Y619807D01*
X484513Y619831D01*
X484557Y619824D01*
G03X484772Y619809I212J1487D01*
G03X486274Y621311I0J1502D01*
G03X485003Y622795I-1502J0D01*
G01X484947Y622804D01*
X484861Y622877D01*
X484733Y623270D01*
G02X484782Y623473I190J61D01*
G01X485153Y623844D01*
X485195Y623869D01*
X485218Y623877D01*
G03X486274Y625311I-446J1434D01*
G03X484772Y626813I-1502J0D01*
G03X484557Y626798I-3J-1502D01*
G01X484513Y626791D01*
X484431Y626815D01*
X484169Y627042D01*
G02X484100Y627193I131J151D01*
G01Y627429D01*
G02X484169Y627580I200J0D01*
G01X484431Y627807D01*
X484513Y627831D01*
X484557Y627824D01*
G03X484772Y627809I212J1487D01*
G03Y630813I0J1502D01*
G03X484557Y630798I-3J-1502D01*
G01X484513Y630791D01*
X484431Y630815D01*
X484169Y631042D01*
G02X484100Y631193I131J151D01*
G01Y635252D01*
G02X484159Y635394I200J0D01*
G01X494001Y645236D01*
G02X494142Y645294I141J-142D01*
G01X535538D01*
G03X536462Y645677I0J1306D01*
G37*
G36*
G01X540379Y721287D02*
G03Y718283I0J-1502D01*
G03X541555Y718850I0J1503D01*
G01X541595Y718900D01*
X541717Y718935D01*
X542134Y718790D01*
G02X542268Y718601I-66J-189D01*
G01Y703912D01*
G02X542209Y703770I-200J0D01*
G01X539943Y701505D01*
G03X539560Y700581I923J-924D01*
G01Y697546D01*
G03X539943Y696622I1306J0D01*
G01X541547Y695019D01*
G02X541606Y694877I-141J-142D01*
G01Y685402D01*
G02X541547Y685260I-200J0D01*
G01X540687Y684401D01*
G03X540304Y683477I923J-924D01*
G01Y660890D01*
G02X540245Y660748I-200J0D01*
G01X539147Y659649D01*
G02X539005Y659590I-142J141D01*
G01X538609D01*
G02X538409Y659790I0J200D01*
G02X538514Y659967I200J1D01*
G01X538515D01*
G03X539466Y661556I-852J1589D01*
G03X537664Y663358I-1802J0D01*
G01X534264D01*
G03X532462Y661556I0J-1802D01*
G01Y661555D01*
G03X532996Y660275I1802J0D01*
G01X533039Y660232D01*
X533063Y660113D01*
X532900Y659714D01*
G02X532715Y659590I-185J76D01*
G01X508055D01*
G02X507913Y659649I0J200D01*
G01X500663Y666900D01*
G03X499741Y667282I-923J-924D01*
G01X496862D01*
G02X496769Y667305I0J200D01*
G03X496070Y667478I-700J-1329D01*
G03Y664474I0J-1502D01*
G03X496769Y664647I-1J1502D01*
G02X496862Y664670I93J-177D01*
G01X499115D01*
G02X499257Y664611I0J-200D01*
G01X506507Y657360D01*
G03X507429Y656978I923J924D01*
G01X539631D01*
G03X540553Y657360I-1J1306D01*
G01X541458Y658266D01*
G02X541677Y658309I141J-141D01*
G02X541800Y658125I-77J-185D01*
G01Y654794D01*
G02X541741Y654652I-200J0D01*
G01X535056Y647967D01*
G02X534914Y647908I-142J141D01*
G01X493518D01*
G03X492594Y647525I0J-1306D01*
G01X484442Y639372D01*
G02X484223Y639329I-141J141D01*
G02X484100Y639513I77J185D01*
G01Y660471D01*
G02X484201Y660645I200J0D01*
G03X485366Y662649I-1141J2004D01*
G03X484690Y664280I-2307J-1D01*
G01X484665Y664304D01*
G02X484606Y664447I141J142D01*
G01Y698891D01*
G02X484751Y699084I200J1D01*
G03X485605Y699717I-409J1445D01*
G02X485879Y699778I168J-108D01*
G03X486835Y699503I957J1528D01*
G01X486837D01*
G03X488640Y701306I0J1803D01*
G01Y704706D01*
G03X486837Y706509I-1803J0D01*
G01X486835D01*
G03X485879Y706234I1J-1803D01*
G02X485605Y706295I-106J169D01*
G03X484751Y706928I-1263J-812D01*
G02X484606Y707121I55J192D01*
G01Y713062D01*
G02X484665Y713204I200J0D01*
G01X498531Y727069D01*
G03X499206Y728699I-1631J1630D01*
G01Y736223D01*
G02X499265Y736365I200J0D01*
G01X499995Y737095D01*
G02X500277I141J-142D01*
G01X525333Y712038D01*
G02X525392Y711896I-141J-142D01*
G01Y707922D01*
G02X525285Y707745I-200J0D01*
G01X524922Y707555D01*
X524811Y707562D01*
X524765Y707594D01*
G03X523930Y707855I-835J-1206D01*
G01X523929D01*
G03X522841Y707372I0J-1467D01*
G02X522693Y707306I-148J134D01*
G01X522395D01*
G02X522247Y707372I0J200D01*
G03X520071I-1088J-983D01*
G02X519923Y707306I-148J134D01*
G01X519625D01*
G02X519477Y707372I0J200D01*
G03X518389Y707855I-1088J-984D01*
G03X517313Y707384I1J-1467D01*
G02X517166Y707320I-147J136D01*
G01X516872D01*
G02X516725Y707384I0J200D01*
G03X515649Y707855I-1077J-996D01*
G03Y704921I0J-1467D01*
G03X516725Y705392I-1J1467D01*
G02X516872Y705456I147J-136D01*
G01X517166D01*
G02X517313Y705392I0J-200D01*
G03X518389Y704921I1077J996D01*
G03X519477Y705404I0J1467D01*
G02X519625Y705470I148J-134D01*
G01X519923D01*
G02X520071Y705404I0J-200D01*
G03X522247I1088J983D01*
G02X522395Y705470I148J-134D01*
G01X522693D01*
G02X522841Y705404I0J-200D01*
G03X525017I1088J983D01*
G02X525165Y705470I148J-134D01*
G01X525463D01*
G02X525611Y705404I0J-200D01*
G03X526699Y704921I1088J984D01*
G03X527730Y705345I-1J1467D01*
G02X527732Y705347I142J-140D01*
G02X527883Y705403I139J-144D01*
G01X528181Y705386D01*
G02X528325Y705312I-12J-200D01*
G03X529032Y704829I1145J917D01*
G01X529083Y704814D01*
X529154Y704738D01*
X529249Y704354D01*
G02X529196Y704165I-194J-47D01*
G01X528938Y703906D01*
X528906Y703891D01*
G03X528099Y702622I594J-1269D01*
G03X528560Y701583I1401J0D01*
G02X528626Y701434I-134J-149D01*
G01X528625Y701094D01*
X528590Y701016D01*
X528558Y700988D01*
G03X528091Y699943I936J-1045D01*
G01Y699942D01*
G03X528483Y698970I1402J0D01*
G01X528511Y698941D01*
X528539Y698871D01*
Y698515D01*
X528511Y698445D01*
X528483Y698416D01*
G03X528091Y697443I1010J-972D01*
G03X528483Y696470I1402J-1D01*
G01X528511Y696441D01*
X528539Y696371D01*
Y696015D01*
X528511Y695945D01*
X528483Y695916D01*
G03X528091Y694943I1010J-972D01*
G03X528483Y693970I1402J-1D01*
G01X528511Y693941D01*
X528539Y693871D01*
Y693515D01*
X528511Y693445D01*
X528483Y693416D01*
G03X528455Y693386I1011J-972D01*
G02X528307Y693320I-148J134D01*
G01X528179D01*
G02X528031Y693386I0J200D01*
G03X526993Y693845I-1038J-944D01*
G01X526992D01*
G03X526020Y693453I0J-1402D01*
G01X525991Y693425D01*
X525921Y693397D01*
X525565D01*
X525495Y693425D01*
X525466Y693453D01*
G03X524494Y693845I-972J-1010D01*
G01X524493D01*
G03Y691041I0J-1402D01*
G01X524494D01*
G03X525466Y691433I0J1402D01*
G01X525495Y691461D01*
X525565Y691489D01*
X525921D01*
X525991Y691461D01*
X526020Y691433D01*
G03X526993Y691041I972J1010D01*
G03X527966Y691433I1J1402D01*
G01X527995Y691461D01*
X528065Y691489D01*
X528421D01*
X528491Y691461D01*
X528520Y691433D01*
G03X529492Y691041I972J1010D01*
G01X529493D01*
G03X530895Y692443I0J1402D01*
G01Y692444D01*
G03X530503Y693416I-1402J0D01*
G01X530475Y693445D01*
X530447Y693515D01*
Y693871D01*
X530475Y693941D01*
X530503Y693970D01*
G03X530895Y694943I-1010J972D01*
G03X530503Y695916I-1402J1D01*
G01X530475Y695945D01*
X530447Y696015D01*
Y696371D01*
X530475Y696441D01*
X530503Y696470D01*
G03X530895Y697443I-1010J972D01*
G03X530503Y698416I-1402J1D01*
G01X530475Y698445D01*
X530447Y698515D01*
Y698871D01*
X530475Y698941D01*
X530503Y698970D01*
G03X530895Y699942I-1010J972D01*
G01Y699943D01*
G03X530434Y700982I-1401J0D01*
G02X530368Y701131I134J149D01*
G01X530369Y701471D01*
X530404Y701549D01*
X530436Y701577D01*
G03X530770Y702027I-936J1044D01*
G01X530785Y702059D01*
X532309Y703582D01*
G03X532692Y704506I-923J924D01*
G01Y709880D01*
G03X532309Y710804I-1306J0D01*
G01X503147Y739965D01*
G02Y740247I142J141D01*
G01X511341Y748441D01*
G02X511483Y748500I142J-141D01*
G01X534057D01*
G02X534199Y748441I0J-200D01*
G01X542209Y740432D01*
G02X542268Y740290I-141J-142D01*
G01Y720969D01*
G02X542134Y720780I-200J0D01*
G01X541717Y720635D01*
X541595Y720670D01*
X541555Y720720D01*
G03X540379Y721287I-1176J-936D01*
G37*
G36*
G01X573605Y784265D02*
G02X573515Y784342I79J184D01*
G01X573500Y784367D01*
X573484Y784424D01*
X573485Y784455D01*
G03X573486Y784507I-1501J55D01*
G03X571984Y783005I-1502J0D01*
G03X572036Y783006I-3J1502D01*
G01X572037D01*
G02X572150Y782975I6J-200D01*
G01X572175Y782960D01*
X572194Y782937D01*
G02X572225Y782888I-152J-130D01*
G01X572354Y782591D01*
X572377Y782538D01*
G02X572332Y782323I-186J-73D01*
G01X571499Y781490D01*
G02X571432Y781446I-141J142D01*
G01X571398Y781432D01*
X562127D01*
G02X562105Y781433I-2J200D01*
G02X562053Y781446I22J199D01*
G02X561980Y781496I74J186D01*
G01X561768Y781757D01*
G02X561737Y781824I163J116D01*
G01X561727Y781865D01*
X561736Y781910D01*
G03X561765Y782205I-1473J294D01*
G01Y782226D01*
G03X561619Y782853I-1502J-19D01*
G01X561618Y782856D01*
G02X561600Y782958I181J85D01*
G02X561630Y783047I199J-18D01*
G01X561844Y783341D01*
G02X561928Y783408I162J-117D01*
G02X562032Y783422I78J-184D01*
G01X562033D01*
X562046Y783420D01*
G03X562234Y783409I182J1491D01*
G01X562237D01*
G03X563733Y784911I-6J1502D01*
G03X562231Y786413I-1502J0D01*
G03X560729Y784931I0J-1502D01*
G01Y784910D01*
G03X560875Y784264I1502J0D01*
G01X560880Y784254D01*
G02X560894Y784160I-185J-76D01*
G02X560856Y784060I-199J18D01*
G01X560650Y783777D01*
G02X560566Y783710I-162J117D01*
G02X560462Y783696I-78J184D01*
G01X560461D01*
X560448Y783698D01*
G03X560381Y783705I-190J-1490D01*
G01X560379D01*
G03X560295Y783709I-113J-1498D01*
G01X560270D01*
G03X560263I-3J-1502D01*
G03X560064Y783696I-2J-1502D01*
G01X560061D01*
G02X559958Y783710I-25J198D01*
G01X559935Y783720D01*
X559892Y783754D01*
X559881Y783770D01*
X559669Y784060D01*
G02X559631Y784160I161J118D01*
G02X559650Y784265I199J18D01*
G03X559796Y784905I-1356J646D01*
G01Y784931D01*
G03X558294Y786413I-1502J-20D01*
G03Y783409I0J-1502D01*
G01X558295D01*
G03X558493Y783422I1J1502D01*
G01X558496D01*
G02X558599Y783408I25J-198D01*
G01X558622Y783398D01*
X558665Y783364D01*
X558676Y783348D01*
X558888Y783058D01*
G02X558926Y782958I-161J-118D01*
G02X558907Y782853I-199J-18D01*
G03X558761Y782207I1356J-646D01*
G01Y782145D01*
G03X558762Y782126I200J1D01*
G01X558766Y782080D01*
Y782078D01*
G03X558781Y781958I1497J126D01*
G03X558790Y781909I1482J247D01*
G01X558794Y781887D01*
X558799Y781865D01*
X558789Y781824D01*
G02X558758Y781757I-194J49D01*
G01X558546Y781496D01*
G02X558473Y781446I-147J136D01*
G02X558421Y781433I-74J186D01*
G02X558399Y781432I-20J199D01*
G01X551122D01*
G02X550922Y781629I0J200D01*
G03X549168Y783354I-1754J-29D01*
G01X549167D01*
G03X548287Y783117I1J-1755D01*
G02X548187Y783090I-100J173D01*
G01X545963D01*
X545951Y783092D01*
G03X545689Y783101I-182J-1492D01*
G01X545648Y783097D01*
G03X545494Y783077I116J-1497D01*
G03X544703Y782660I273J-1477D01*
G01X544691Y782648D01*
G02X544615Y782607I-131J151D01*
G01X544592Y782600D01*
X544540D01*
X544346Y782648D01*
X544179Y782689D01*
G02X544088Y782739I48J194D01*
G01X544071Y782756D01*
X544044Y782799D01*
X544036Y782825D01*
G03X543702Y783408I-1437J-436D01*
G01X543677Y783436D01*
X543664Y783469D01*
G02X543649Y783532I185J77D01*
G01X543646Y783671D01*
Y783673D01*
X543644Y783814D01*
G02X543655Y783876I200J-3D01*
G01X543667Y783910D01*
X543691Y783939D01*
G03X544048Y784911I-1145J972D01*
G03X541044I-1502J0D01*
G01Y784910D01*
G03X541442Y783892I1502J1D01*
G01X541456Y783878D01*
X541468Y783864D01*
X541481Y783831D01*
X541483Y783827D01*
G02X541495Y783770I-188J-69D01*
G01X541498Y783629D01*
Y783627D01*
X541501Y783495D01*
G02X541490Y783423I-200J-6D01*
G01X541478Y783390D01*
X541454Y783361D01*
G03X541425Y783326I1142J-976D01*
G03X541401Y783295I1175J-935D01*
G01X541386Y783275D01*
X541366Y783248D01*
X541351Y783235D01*
G02X541312Y783208I-133J150D01*
G01X541226Y783163D01*
G02X541140Y783143I-87J180D01*
G01X540908D01*
G02X540823Y783162I0J200D01*
G01X540725Y783214D01*
G02X540707Y783227I108J168D01*
G01X540681Y783249D01*
X540667Y783268D01*
G03X539449Y783891I-1218J-879D01*
G03X537947Y782389I0J-1502D01*
G03X538013Y781949I1502J0D01*
G01Y781948D01*
X538017Y781936D01*
G02X538019Y781856I-195J-45D01*
G01X538011Y781810D01*
X537784Y781505D01*
G02X537631Y781432I-154J127D01*
G01X534267D01*
G02X534111Y781508I1J200D01*
G01X534081Y781548D01*
Y781550D01*
X533915Y781772D01*
G02X533879Y781857I161J118D01*
G01X533874Y781887D01*
X533881Y781935D01*
X533885Y781948D01*
Y781950D01*
G03X533951Y782389I-1436J440D01*
G03X530947I-1502J0D01*
G03X531013Y781949I1502J0D01*
G01Y781948D01*
X531017Y781936D01*
G02X531019Y781856I-195J-45D01*
G01X531011Y781810D01*
X530918Y781684D01*
X530789Y781511D01*
G02X530783Y781504I-154J126D01*
G01X530693Y781498D01*
G02X530537Y781556I-15J199D01*
G01X523943Y788150D01*
G02X523884Y788292I141J142D01*
G01Y791484D01*
G03X523607Y792570I-2267J0D01*
G01X523595Y792592D01*
X523582Y792640D01*
G02X523577Y792686I195J44D01*
G01Y792702D01*
G02X523584Y792742I200J-14D01*
G01X523599Y792792D01*
X523612Y792814D01*
G03X523818Y793571I-1296J759D01*
G01Y793599D01*
G03X522316Y795076I-1502J-25D01*
G01X522315D01*
G03X521650Y794921I0J-1502D01*
G01X521649Y794920D01*
X521618Y794905D01*
X521594Y794892D01*
G02X521485Y794877I-81J183D01*
G02X521394Y794916I31J197D01*
G01X521392D01*
G02X521373Y794933I124J157D01*
G01X521300Y795006D01*
G02X521260Y795064I142J141D01*
G01Y795229D01*
X521276Y795266D01*
G03X521393Y795842I-1385J581D01*
G01Y795867D01*
G03X519910Y797350I-1502J-19D01*
G01X519890D01*
G03X519272Y797217I0J-1502D01*
G01X519271D01*
X519190Y797199D01*
G02X519054Y797253I1J200D01*
G01X518691Y797616D01*
G02X518632Y797757I141J142D01*
G01Y802413D01*
Y802414D01*
G02X518657Y802510I200J-1D01*
G01X518755Y802550D01*
G03X519630Y803508I-597J1424D01*
G01X519642Y803547D01*
X519721Y803640D01*
G02X519790Y803691I151J-132D01*
G01X519980Y803778D01*
X520011Y803792D01*
X520095D01*
X520135Y803775D01*
G03X520741Y803647I607J1374D01*
G03Y806651I0J1502D01*
G03X519306Y805594I0J-1503D01*
G01X519293Y805552D01*
X519266Y805521D01*
G02X519204Y805474I-150J133D01*
G01X519168Y805458D01*
X518915Y805343D01*
G02X518890Y805335I-73J186D01*
G01X518826Y805364D01*
G02X518824Y805366I132J134D01*
G03X518743Y805402I-667J-1393D01*
G01X518741D01*
X518657Y805438D01*
X518649Y805450D01*
X518641Y805476D01*
G02X518632Y805535I191J59D01*
G01Y810293D01*
G02X518680Y810423I200J0D01*
G01X518703Y810450D01*
X518764Y810484D01*
X518801Y810490D01*
G03X520067Y811973I-236J1483D01*
G03X520052Y812188I-1502J3D01*
G01X520051Y812192D01*
G02X520055Y812263I199J24D01*
G02X520065Y812295I195J-43D01*
G01X520075Y812317D01*
X520106Y812357D01*
X520412Y812594D01*
G02X520448Y812614I114J-164D01*
G01X520542D01*
G02X520580Y812610I-2J-200D01*
G01X520634Y812600D01*
X520635D01*
G03X521178Y812499I542J1401D01*
G01X521196D01*
G03X522680Y814001I-18J1502D01*
G03X519676I-1502J0D01*
G03X519691Y813786I1502J-3D01*
G01Y813783D01*
G02X519678Y813680I-198J-27D01*
G01X519668Y813657D01*
X519653Y813638D01*
G02X519618Y813602I-160J120D01*
G01X519478Y813493D01*
X519333Y813381D01*
G02X519245Y813346I-116J163D01*
G01X519219Y813343D01*
X519167Y813349D01*
X519142Y813360D01*
G03X519008Y813409I-582J-1385D01*
G01X519007D01*
X518980Y813417D01*
G03X518903Y813437I-416J-1444D01*
G01X518901D01*
G03X518838Y813450I-335J-1464D01*
G01X518836D01*
G03X518802Y813456I-278J-1476D01*
G01X518801D01*
X518789Y813458D01*
G02X518679Y813524I43J196D01*
G01X518657Y813550D01*
X518645Y813583D01*
G02X518632Y813653I187J71D01*
G01Y825328D01*
G02X518699Y825477I200J0D01*
G03Y827723I-996J1123D01*
G02X518632Y827872I133J149D01*
G01Y833181D01*
G02X518633Y833200I200J-1D01*
G02X518705Y833336I199J-18D01*
G03Y835780I-873J1222D01*
G02X518633Y835916I127J154D01*
G02X518632Y835935I199J20D01*
G01Y847555D01*
G02X518635Y847587I200J-3D01*
G01Y847589D01*
G02X518689Y847695I197J-34D01*
G01X524806Y853812D01*
G02X524912Y853866I140J-143D01*
G01X524914D01*
G02X524946Y853869I35J-197D01*
G01X538352D01*
G02X538512Y853789I0J-200D01*
G01Y844636D01*
G03X538511Y844590I1307J-51D01*
G03X538550Y844273I1308J0D01*
G01X538555Y844236D01*
G02X538355Y844036I-200J0D01*
G01X538262Y844068D01*
G02X538207Y844098I67J188D01*
G03X537300Y844402I-906J-1199D01*
G03X536020Y843685I0J-1501D01*
G02X535843Y843590I-170J105D01*
G01X535442Y843602D01*
X535351Y843659D01*
X535326Y843706D01*
G03X534000Y844502I-1326J-706D01*
G03Y841498I0J-1502D01*
G03X535280Y842215I0J1501D01*
G02X535457Y842310I170J-105D01*
G01X535858Y842298D01*
X535949Y842241D01*
X535974Y842194D01*
G03X537300Y841398I1326J706D01*
G03X538800Y842818I0J1502D01*
G02X538928Y842994I200J-11D01*
G01X539268Y843125D01*
G02X539481Y843079I71J-187D01*
G01X541632Y840928D01*
G02X541618Y840823I-198J-27D01*
G01X541521Y840616D01*
X541454Y840473D01*
G02X541374Y840386I-181J86D01*
G01X541348Y840371D01*
X541291Y840358D01*
X541258Y840361D01*
G03X541129Y840367I-134J-1496D01*
G03X542631Y838865I0J-1502D01*
G03X542626Y838993I-1502J5D01*
G01X542624Y839012D01*
G02X542651Y839111I200J-1D01*
G01X542666Y839137D01*
X542688Y839157D01*
G02X542737Y839190I135J-148D01*
G01X542880Y839257D01*
X543087Y839354D01*
G02X543192Y839368I78J-184D01*
G01X548721Y833838D01*
G02X548780Y833696I-141J-142D01*
G01Y830579D01*
X548765Y830549D01*
G03X548732Y830484I1322J-712D01*
G03X548709Y830435I1348J-663D01*
G03X548707Y830429I189J-66D01*
G03X548699Y830410I1380J-592D01*
G02X548697Y830404I-190J60D01*
G03X548677Y830355I1380J-592D01*
G01X548676Y830351D01*
G02X548670Y830337I-187J72D01*
G02X548425Y830233I-181J86D01*
G01X548401Y830244D01*
G02X548300Y830359I88J179D01*
G01X548297Y830368D01*
G03X546855Y831451I-1442J-419D01*
G03Y828447I0J-1502D01*
G03X548105Y829114I0J1505D01*
G01X548116Y829131D01*
G02X548179Y829181I153J-129D01*
G01X548202Y829193D01*
X548226Y829198D01*
G02X548277Y829203I45J-195D01*
G01X548625Y829191D01*
G02X548705Y829167I-16J-200D01*
G01X548735Y829149D01*
X548770Y829113D01*
X548783Y829090D01*
G03X550087Y828334I1304J747D01*
G03X551579Y829660I0J1502D01*
G01X551585Y829717D01*
G03X551590Y829836I-1498J123D01*
G03X551538Y830226I-1503J-2D01*
G03X551417Y830535I-1451J-390D01*
G02X551394Y830628I177J93D01*
G01Y834276D01*
G03X551395Y834322I-1307J51D01*
G03X551012Y835247I-1309J0D01*
G01X541185Y845074D01*
G02X541126Y845216I141J142D01*
G01Y853788D01*
G02X541286Y853869I161J-119D01*
G01X567620D01*
G02X567652Y853866I-3J-200D01*
G01X567654D01*
G02X567760Y853812I-34J-197D01*
G01X574811Y846761D01*
G02X574865Y846655I-143J-140D01*
G01Y846653D01*
G02X574868Y846621I-197J-35D01*
G01Y831101D01*
G02X574756Y830921I-200J0D01*
G01X574432Y830763D01*
G02X574223Y830784I-87J180D01*
G01X574222Y830785D01*
G03X573300Y831102I-923J-1185D01*
G03Y828098I0J-1502D01*
G03X574221Y828415I-2J1502D01*
G01X574223D01*
Y828416D01*
G02X574432Y828437I122J-159D01*
G01X574756Y828279D01*
G02X574868Y828099I-88J-180D01*
G01Y784942D01*
G02X574824Y784817I-200J0D01*
G03X574822Y784815I140J-142D01*
G02X574810Y784801I-157J123D01*
G01X574168Y784159D01*
G02X573953Y784114I-142J141D01*
G01X573605Y784265D01*
G37*
G36*
G01X594744Y54588D02*
X623251D01*
X623486Y54353D01*
Y52826D01*
X623251Y52591D01*
X594744D01*
G03X588807Y46654I0J-5937D01*
G01Y7874D01*
G02X582933Y2000I-5874J0D01*
G01X535689D01*
G02X529815Y7874I0J5874D01*
G01Y46526D01*
X531812D01*
Y7874D01*
G03X535687Y3998I3876J0D01*
G01X582933D01*
G03X586810Y7874I0J3877D01*
G01Y46654D01*
G02X594744Y54588I7934J0D01*
G37*
G36*
G01X566124Y773600D02*
X548576Y756052D01*
X534275D01*
X531390Y758938D01*
Y778896D01*
X532766Y780272D01*
X545041D01*
X545085Y780262D01*
X545106Y780252D01*
G03X545768Y780098I662J1348D01*
G01X549116D01*
X549168D01*
G03X549831Y780252I0J1502D01*
G01X549852Y780262D01*
X549895Y780272D01*
X565403D01*
G02X565572Y780179I0J-200D01*
G01X565781Y779851D01*
X565787Y779749D01*
X565766Y779703D01*
G03X565624Y779066I1360J-637D01*
G03X566124Y777947I1502J0D01*
G01Y773600D01*
G37*
G36*
G01X628228Y1060184D02*
X684195D01*
G02X684337Y1060125I0J-200D01*
G01X684389Y1060073D01*
G02X684440Y1059878I-141J-141D01*
G01X628276Y859014D01*
G02X628083Y858868I-193J54D01*
G01X603367D01*
G02X603225Y858927I0J200D01*
G01X602977Y859175D01*
G02X602918Y859316I141J142D01*
G01Y906789D01*
G02X602977Y906930I200J-1D01*
G01X607724Y911677D01*
G03X608106Y912601I-924J923D01*
G01Y917999D01*
G03X607724Y918923I-1306J1D01*
G01X601890Y924757D01*
G02X601831Y924898I141J142D01*
G01X601794Y941622D01*
G02X601853Y941764I200J0D01*
G01X611969Y951880D01*
G03X612352Y952804I-923J924D01*
G01Y995358D01*
G02X612410Y995499I200J0D01*
G01X613304Y996393D01*
X613346Y996418D01*
X613369Y996426D01*
G03X614425Y997860I-446J1434D01*
G03X612923Y999362I-1502J0D01*
G03X611489Y998306I0J-1502D01*
G01X611481Y998283D01*
X611456Y998241D01*
X610121Y996906D01*
G03X609738Y995982I923J-924D01*
G01Y990669D01*
G02X609664Y990513I-200J-1D01*
G01X609384Y990289D01*
X609296Y990269D01*
X609251Y990279D01*
G03X608923Y990315I-327J-1466D01*
G03Y987311I0J-1502D01*
G03X609251Y987347I1J1502D01*
G01X609296Y987357D01*
X609384Y987337D01*
X609664Y987113D01*
G02X609738Y986957I-126J-155D01*
G01Y968016D01*
G02X609538Y967816I-200J0D01*
G01X609504D01*
X609471Y967828D01*
G03X609411Y967848I-505J-1414D01*
G01X609388Y967856D01*
X609346Y967881D01*
X602245Y974982D01*
G03X601321Y975364I-923J-924D01*
G01X600518D01*
G02X600377Y975423I1J200D01*
G01X600344Y975456D01*
G03X600202Y975515I-142J-141D01*
G01X568295D01*
G02X568153Y975574I0J200D01*
G01X566361Y977366D01*
G02X566302Y977507I141J142D01*
G01Y979707D01*
G03X565920Y980631I-1306J1D01*
G01X562288Y984263D01*
G02X562230Y984404I142J141D01*
G01Y988045D01*
X562241Y988092D01*
X562252Y988114D01*
G03X562425Y988813I-1329J700D01*
G03X559421I-1502J0D01*
G03X559594Y988114I1502J1D01*
G01X559605Y988092D01*
X559616Y988045D01*
Y983780D01*
G03X559999Y982856I1306J0D01*
G01X560405Y982451D01*
G02X560460Y982274I-142J-141D01*
G01X560394Y981903D01*
X560335Y981826D01*
X560290Y981805D01*
G03X559421Y980443I633J-1362D01*
G03X560923Y978941I1502J0D01*
G03X562285Y979810I0J1502D01*
G01X562306Y979855D01*
X562383Y979914D01*
X562754Y979980D01*
G02X562931Y979925I36J-197D01*
G01X563631Y979224D01*
G02X563690Y979083I-141J-142D01*
G01Y976883D01*
G03X564072Y975959I1306J-1D01*
G01X564175Y975856D01*
G02X564218Y975638I-141J-141D01*
G01X564195Y975582D01*
X564095Y975515D01*
X556980D01*
G02X556838Y975574I0J200D01*
G01X551908Y980504D01*
G02X551849Y980646I141J142D01*
G01Y987034D01*
G02X551935Y987199I200J1D01*
G01X552247Y987414D01*
X552344Y987426D01*
X552391Y987408D01*
G03X552923Y987311I531J1405D01*
G03Y990315I0J1502D01*
G03X552391Y990218I-1J-1502D01*
G01X552344Y990200D01*
X552247Y990212D01*
X551935Y990427D01*
G02X551849Y990592I114J164D01*
G01Y997788D01*
G02X551908Y997930I200J0D01*
G01X554734Y1000756D01*
X554769D01*
X556649Y1002636D01*
G02X556791Y1002695I142J-141D01*
G01X559734D01*
G03X559876Y1002754I0J200D01*
G01X564445Y1007323D01*
G03X564504Y1007465I-141J142D01*
G01Y1008736D01*
X564516Y1008783D01*
X564528Y1008806D01*
G03X564684Y1009426I-1150J619D01*
G01Y1016044D01*
G02X564743Y1016185I200J-1D01*
G01X566158Y1017600D01*
G02X566300Y1017659I142J-141D01*
G01X570005D01*
G02X570161Y1017583I-1J-200D01*
G01X570385Y1017301D01*
X570405Y1017214D01*
X570394Y1017168D01*
G03X570355Y1016827I1463J-340D01*
G03X573359I1502J0D01*
G03X573320Y1017168I-1502J1D01*
G01X573309Y1017214D01*
X573329Y1017301D01*
X573553Y1017583D01*
G02X573709Y1017659I157J-124D01*
G01X575852D01*
G02X576008Y1017583I-1J-200D01*
G01X576232Y1017301D01*
X576252Y1017214D01*
X576241Y1017168D01*
G03X576202Y1016827I1463J-340D01*
G03X579206I1502J0D01*
G03X579167Y1017168I-1502J1D01*
G01X579156Y1017214D01*
X579176Y1017301D01*
X579400Y1017583D01*
G02X579556Y1017659I157J-124D01*
G01X582000D01*
G03X582142Y1017718I0J200D01*
G01X591959Y1027535D01*
G02X592100Y1027594I142J-141D01*
G01X606925D01*
G03X607849Y1027976I1J1306D01*
G01X617918Y1038045D01*
G03X618294Y1038843I-924J923D01*
G01X618298Y1038878D01*
X618327Y1038940D01*
X627969Y1048582D01*
G03X628028Y1048724I-141J142D01*
G01Y1059984D01*
G02X628228Y1060184I200J0D01*
G37*
G36*
G01X1102902Y1536033D02*
G03X1101948Y1534749I2609J-2935D01*
G01X1101251Y1533247D01*
X1101174Y1533187D01*
X1101127Y1533179D01*
G03X1099900Y1531702I275J-1477D01*
G03X1100097Y1530958I1503J0D01*
G01X1100121Y1530916D01*
X1100125Y1530820D01*
X1098665Y1527672D01*
G02X1098504Y1527557I-182J84D01*
G01X1098110Y1527516D01*
X1098014Y1527558D01*
X1097982Y1527600D01*
G03X1096780Y1528202I-1202J-899D01*
G03Y1525198I0J-1502D01*
G03X1096868Y1525201I-7J1502D01*
G01X1096870D01*
X1096922Y1525204D01*
X1097016Y1525157D01*
X1097239Y1524830D01*
G02X1097255Y1524633I-165J-113D01*
G01X1095468Y1520779D01*
G03X1095107Y1519295I3562J-1652D01*
G01X1094922Y1514985D01*
X1094834Y1514881D01*
X1094767Y1514867D01*
G03X1093578Y1513398I313J-1469D01*
G03X1094642Y1511961I1502J0D01*
G01X1094708Y1511941D01*
X1094786Y1511830D01*
X1094535Y1505986D01*
G02X1094335Y1505795I-200J9D01*
G01X1084956D01*
G02X1084817Y1505851I0J200D01*
G03X1077851Y1510272I-14346J-14906D01*
G01X1077811Y1510287D01*
X1077366Y1510732D01*
G02X1077307Y1510874I141J142D01*
G01Y1557631D01*
G03X1077248Y1557773I-200J0D01*
G01X1065512Y1569509D01*
G03X1065370Y1569568I-142J-141D01*
G01X1049172D01*
G03X1049030Y1569509I0J-200D01*
G01X1044319Y1564798D01*
G02X1044290Y1564774I-141J141D01*
G03X1038768Y1559252I11615J-17137D01*
G02X1038744Y1559223I-165J112D01*
G01X1024314Y1544793D01*
G02X1024172Y1544734I-142J141D01*
G01X1003928D01*
G02X1003786Y1544793I0J200D01*
G01X1002426Y1546153D01*
G02X1002367Y1546295I141J142D01*
G01Y1568338D01*
G03X1002308Y1568480I-200J0D01*
G01X998581Y1572207D01*
G03X998439Y1572266I-142J-141D01*
G01X967570D01*
G02X967428Y1572325I0J200D01*
G01X965980Y1573773D01*
G02X965921Y1573915I141J142D01*
G01Y1578065D01*
G03X965862Y1578207I-200J0D01*
G01X960638Y1583431D01*
G03X960496Y1583490I-142J-141D01*
G01X942870D01*
G02X942728Y1583549I0J200D01*
G01X938157Y1588120D01*
G02X938098Y1588262I141J142D01*
G01Y1624757D01*
G03X938039Y1624899I-200J0D01*
G01X931527Y1631411D01*
G03X931385Y1631470I-142J-141D01*
G01X816768D01*
G03X816626Y1631411I0J-200D01*
G01X802580Y1617365D01*
G03X802521Y1617223I141J-142D01*
G01Y1514008D01*
G02X802462Y1513866I-200J0D01*
G01X798662Y1510066D01*
G02X798520Y1510007I-142J141D01*
G01X778551D01*
G02X778474Y1510023I1J200D01*
G03X770472Y1511633I-8001J-19078D01*
G01X770471D01*
G03X762470Y1510023I0J-20688D01*
G01X762432Y1510007D01*
X751959D01*
G02X751817Y1510066I0J200D01*
G01X748748Y1513135D01*
G02X748689Y1513277I141J142D01*
G01Y1554535D01*
G02X748748Y1554677I200J0D01*
G01X774097Y1580027D01*
G02X774239Y1580086I142J-141D01*
G01X782860D01*
G03X783782Y1580468I-1J1306D01*
G01X790629Y1587315D01*
G03X791012Y1588239I-923J924D01*
G01Y1604850D01*
G03X790629Y1605774I-1306J0D01*
G01X786497Y1609906D01*
G03X785575Y1610288I-923J-924D01*
G01X777851D01*
G02X777758Y1610311I0J200D01*
G03X777059Y1610484I-700J-1329D01*
G03Y1607480I0J-1502D01*
G03X777758Y1607653I-1J1502D01*
G02X777851Y1607676I93J-177D01*
G01X784949D01*
G02X785091Y1607617I0J-200D01*
G01X788339Y1604368D01*
G02X788398Y1604226I-141J-142D01*
G01Y1588863D01*
G02X788339Y1588721I-200J0D01*
G01X783270Y1583651D01*
G02X783072Y1583601I-141J142D01*
G01X782680Y1583719D01*
X782606Y1583800D01*
X782595Y1583854D01*
G03X781124Y1585055I-1471J-300D01*
G03X780427Y1584883I1J-1502D01*
G02X780423Y1584881I-91J178D01*
G01X780402Y1584870D01*
X780358Y1584860D01*
X773781D01*
G03X772857Y1584477I0J-1306D01*
G01X765189Y1576809D01*
G02X764972Y1576766I-141J142D01*
G01X764915Y1576789D01*
X764848Y1576890D01*
Y1589394D01*
G02X764871Y1589487I200J0D01*
G03X765044Y1590186I-1329J700D01*
G03X762040I-1502J0D01*
G03X762213Y1589487I1502J1D01*
G02X762236Y1589394I-177J-93D01*
G01Y1575933D01*
G02X762177Y1575791I-200J0D01*
G01X761449Y1575064D01*
G02X761232Y1575021I-141J142D01*
G02X761108Y1575206I76J185D01*
G01Y1590072D01*
G02X761131Y1590165I200J0D01*
G03X761304Y1590864I-1329J700D01*
G03X758300I-1502J0D01*
G03X758473Y1590165I1502J1D01*
G02X758496Y1590072I-177J-93D01*
G01Y1574189D01*
G02X758437Y1574047I-200J0D01*
G01X745111Y1560722D01*
G02X744969Y1560663I-142J141D01*
G01X740790D01*
X740717Y1560633D01*
X740702Y1560618D01*
X736994D01*
G02X736794Y1560818I0J200D01*
G01Y1584064D01*
G02X736853Y1584206I200J0D01*
G01X748259Y1595611D01*
G02X748401Y1595670I142J-141D01*
G01X774581D01*
G03X775505Y1596053I0J1306D01*
G01X778524Y1599073D01*
G02X778666Y1599132I142J-141D01*
G01X783254D01*
G02X783347Y1599109I0J-200D01*
G03X784046Y1598936I700J1329D01*
G03Y1601940I0J1502D01*
G03X783347Y1601767I1J-1502D01*
G02X783254Y1601744I-93J177D01*
G01X778040D01*
G03X777118Y1601362I1J-1306D01*
G01X774099Y1598343D01*
G02X773957Y1598284I-142J141D01*
G01X749114D01*
G02X748929Y1598407I0J200D01*
G01X748906Y1598463D01*
X748929Y1598581D01*
X765899Y1615551D01*
G02X766041Y1615610I142J-141D01*
G01X770593D01*
G02X770682Y1615589I0J-200D01*
G01X770684Y1615588D01*
G03X771383Y1615415I700J1329D01*
G03Y1618419I0J1502D01*
G03X770686Y1618247I1J-1502D01*
G02X770682Y1618245I-91J178D01*
G01X770661Y1618234D01*
X770617Y1618224D01*
X765417D01*
G03X764493Y1617841I0J-1306D01*
G01X743415Y1596763D01*
G02X743197Y1596719I-142J141D01*
G01X743141Y1596742D01*
X743074Y1596842D01*
Y1616478D01*
G02X743205Y1616666I200J0D01*
G01X743557Y1616796D01*
G02X743778Y1616738I69J-188D01*
G01X743779Y1616737D01*
G03X744924Y1616207I1145J972D01*
G03Y1619211I0J1502D01*
G03X743467Y1618076I0J-1503D01*
G01Y1618075D01*
G02X743273Y1617924I-194J49D01*
G01X743191D01*
X743074Y1618041D01*
Y1618452D01*
G03X742691Y1619376I-1306J0D01*
G01X742109Y1619958D01*
G02X742054Y1620141I141J142D01*
G01X742134Y1620519D01*
X742199Y1620596D01*
X742247Y1620614D01*
G03X743207Y1622015I-542J1401D01*
G03X741705Y1623517I-1502J0D01*
G03X740304Y1622557I0J-1502D01*
G01X740286Y1622509D01*
X740209Y1622444D01*
X739831Y1622364D01*
G02X739648Y1622419I-41J196D01*
G01X735978Y1626089D01*
G03X735054Y1626472I-924J-923D01*
G01X730390D01*
G02X730301Y1626493I0J200D01*
G01X730299Y1626494D01*
G03X729600Y1626667I-700J-1329D01*
G03Y1623663I0J-1502D01*
G03X730297Y1623835I-1J1502D01*
G02X730301Y1623837I91J-178D01*
G01X730322Y1623848D01*
X730366Y1623858D01*
X734430D01*
G02X734572Y1623799I0J-200D01*
G01X740401Y1617970D01*
G02X740460Y1617828I-141J-142D01*
G01Y1599268D01*
G02X740340Y1599084I-200J-1D01*
G01X739950Y1598913D01*
X739834Y1598932D01*
X739790Y1598973D01*
G03X738775Y1599368I-1015J-1107D01*
G03Y1596364I0J-1502D01*
G03X740086Y1597133I0J1502D01*
G01X740112Y1597180D01*
X740206Y1597235D01*
X740260D01*
G02X740460Y1597035I0J-200D01*
G01Y1596491D01*
G02X740401Y1596349I-200J0D01*
G01X731744Y1587692D01*
G03X731362Y1586770I924J-923D01*
G01Y1560818D01*
G02X731162Y1560618I-200J0D01*
G01X731031D01*
G03X730831Y1560418I0J-200D01*
G01Y1482086D01*
G03X730890Y1481944I200J0D01*
G01X731303Y1481531D01*
G02X731362Y1481389I-141J-142D01*
G01Y1478765D01*
G03X731744Y1477843I1306J1D01*
G01X743603Y1465985D01*
G02X743662Y1465843I-141J-142D01*
G01Y1450585D01*
G02X743604Y1450444I-200J0D01*
G01X743404Y1450243D01*
G02X743262Y1450184I-142J141D01*
G01X721937D01*
G02X721897Y1450188I0J200D01*
G01X709520Y1452691D01*
X709432Y1452792D01*
X709427Y1452859D01*
G03X707520Y1454629I-1907J-142D01*
G03X705818Y1453589I0J-1913D01*
G01X705787Y1453529D01*
X705667Y1453471D01*
X702075Y1454198D01*
G02X701915Y1454394I40J196D01*
G01Y1598768D01*
G03X701856Y1598910I-200J0D01*
G01X698764Y1602002D01*
G03X698622Y1602061I-142J-141D01*
G01X695558D01*
G02X695428Y1602110I1J200D01*
G03X693753Y1602962I-2566J-2972D01*
G02X693624Y1603059I45J195D01*
G03X690197Y1605068I-3427J-1918D01*
G01X690196D01*
G03X688623Y1604739I0J-3926D01*
G02X688477Y1604733I-81J183D01*
G03X687984Y1604817I-495J-1418D01*
G03X686482Y1603315I0J-1502D01*
G01Y1603312D01*
G03X686574Y1602795I1502J1D01*
G02X686571Y1602649I-187J-69D01*
G03X686418Y1602207I3627J-1503D01*
G02X686225Y1602061I-193J54D01*
G01X683923D01*
X683811Y1602159D01*
X683801Y1602234D01*
G03X679269I-2266J-304D01*
G01X679259Y1602159D01*
X679147Y1602061D01*
X678235D01*
G02X678105Y1602109I0J200D01*
G01X678104Y1602110D01*
G03X676430Y1602962I-2566J-2972D01*
G02X676301Y1603059I45J195D01*
G03X672874Y1605068I-3427J-1918D01*
G01X672873D01*
G03X671300Y1604739I0J-3926D01*
G02X671154Y1604733I-81J183D01*
G03X670661Y1604817I-495J-1418D01*
G03X669159Y1603315I0J-1502D01*
G01Y1603312D01*
G03X669251Y1602795I1502J1D01*
G02X669248Y1602649I-187J-69D01*
G03X669095Y1602207I3627J-1503D01*
G02X668902Y1602061I-193J54D01*
G01X666601D01*
X666489Y1602159D01*
X666479Y1602234D01*
G03X661947I-2266J-304D01*
G01X661937Y1602159D01*
X661825Y1602061D01*
X660912D01*
G02X660782Y1602109I0J200D01*
G01X660781Y1602110D01*
G03X659107Y1602962I-2566J-2972D01*
G02X658978Y1603059I45J195D01*
G03X655551Y1605068I-3427J-1918D01*
G01X655550D01*
G03X653977Y1604739I0J-3926D01*
G02X653831Y1604733I-81J183D01*
G03X653338Y1604817I-495J-1418D01*
G03X651836Y1603315I0J-1502D01*
G01Y1603312D01*
G03X651928Y1602795I1502J1D01*
G02X651925Y1602649I-187J-69D01*
G03X651772Y1602207I3627J-1503D01*
G02X651579Y1602061I-193J54D01*
G01X649278D01*
X649166Y1602159D01*
X649156Y1602234D01*
G03X644624I-2266J-304D01*
G01X644614Y1602159D01*
X644502Y1602061D01*
X643589D01*
G02X643459Y1602109I0J200D01*
G01X643458Y1602110D01*
G03X641784Y1602962I-2566J-2972D01*
G02X641655Y1603059I45J195D01*
G03X638228Y1605068I-3427J-1918D01*
G01X638227D01*
G03X636654Y1604739I0J-3926D01*
G02X636508Y1604733I-81J183D01*
G03X636015Y1604817I-495J-1418D01*
G03X634513Y1603315I0J-1502D01*
G01Y1603312D01*
G03X634605Y1602795I1502J1D01*
G02X634602Y1602649I-187J-69D01*
G03X634449Y1602207I3627J-1503D01*
G02X634256Y1602061I-193J54D01*
G01X631955D01*
X631843Y1602159D01*
X631833Y1602234D01*
G03X627301I-2266J-304D01*
G01X627291Y1602159D01*
X627179Y1602061D01*
X625936D01*
G03X625794Y1602002I0J-200D01*
G01X608910Y1585118D01*
G02X608691Y1585075I-141J141D01*
G02X608568Y1585259I77J185D01*
G01Y1642098D01*
G02X608768Y1642298I200J0D01*
G01X787783D01*
G02X787925Y1642239I0J-200D01*
G01X793565Y1636599D01*
G03X793707Y1636540I142J141D01*
G01X1076991D01*
G03X1077133Y1636599I0J200D01*
G01X1077630Y1637096D01*
X1081656Y1641121D01*
G02X1081798Y1641180I142J-141D01*
G01X1112883D01*
G02X1113025Y1641121I0J-200D01*
G01X1115356Y1638790D01*
G02X1115415Y1638648I-141J-142D01*
G01Y1547064D01*
G02X1115317Y1546892I-200J0D01*
G01X1115066Y1546742D01*
G03X1114464Y1546303I2002J-3378D01*
G01X1102902Y1536033D01*
G37*
G36*
G01X697106Y54588D02*
X725589D01*
X725942Y54235D01*
Y52944D01*
X725589Y52591D01*
X697106D01*
G03X691169Y46654I0J-5937D01*
G01Y7874D01*
G02X685295Y2000I-5874J0D01*
G01X638051D01*
G02X632177Y7874I0J5874D01*
G01Y45760D01*
X634174D01*
Y7874D01*
G03X638049Y3998I3876J0D01*
G01X685295D01*
G03X689172Y7874I0J3877D01*
G01Y46654D01*
G02X697106Y54588I7934J0D01*
G37*
G36*
G01X821373Y1212839D02*
X829495D01*
G02X829637Y1212780I0J-200D01*
G01X829832Y1212585D01*
G02X829891Y1212443I-141J-142D01*
G01Y1134419D01*
G02X829832Y1134277I-200J0D01*
G01X827448Y1131893D01*
G02X827306Y1131834I-142J141D01*
G01X818734D01*
G02X818566Y1131926I0J200D01*
G01X818357Y1132253D01*
X818350Y1132354D01*
X818371Y1132401D01*
G03X818488Y1132783I-1365J627D01*
G01X818495Y1132827D01*
X818543Y1132898D01*
X818824Y1133070D01*
G02X818928Y1133100I105J-170D01*
G01X819001D01*
X819028Y1133092D01*
G03X819448Y1133032I420J1443D01*
G01X819449D01*
G03Y1136036I0J1502D01*
G03X817967Y1134778I0J-1502D01*
G01X817960Y1134734D01*
X817912Y1134663D01*
X817631Y1134491D01*
G02X817527Y1134461I-105J170D01*
G01X817454D01*
X817427Y1134469D01*
G03X817007Y1134529I-420J-1443D01*
G01X817006D01*
G03X816788Y1134513I1J-1502D01*
G01X816747Y1134507D01*
X816668Y1134528D01*
X816373Y1134758D01*
X816334Y1134829D01*
X816330Y1134871D01*
G03X814835Y1136231I-1495J-142D01*
G03Y1133227I0J-1502D01*
G03X815053Y1133243I-1J1502D01*
G01X815094Y1133249D01*
X815173Y1133228D01*
X815468Y1132998D01*
X815507Y1132927D01*
X815511Y1132885D01*
G03X815641Y1132401I1495J142D01*
G01X815662Y1132354D01*
X815655Y1132253D01*
X815446Y1131926D01*
G02X815278Y1131834I-168J108D01*
G01X811268D01*
G02X811176Y1131857I1J200D01*
G01X811175D01*
G02X811092Y1131940I94J177D01*
G01X810925Y1132250D01*
G02X810935Y1132455I176J94D01*
G01Y1132456D01*
G03X811184Y1133286I-1253J828D01*
G01Y1133311D01*
G03X809682Y1134786I-1502J-27D01*
G03X808928Y1134583I0J-1502D01*
G01X808883Y1134557D01*
X808783Y1134554D01*
X808391Y1134753D01*
X808334Y1134835D01*
X808329Y1134887D01*
G03X806835Y1136231I-1494J-158D01*
G03X805500Y1135416I0J-1501D01*
G01X805473Y1135366D01*
X805379Y1135308D01*
X804909D01*
X804815Y1135366D01*
X804788Y1135416D01*
G03X803453Y1136231I-1335J-686D01*
G03X802281Y1135669I0J-1503D01*
G01X802234Y1135609D01*
X802083Y1135584D01*
X799768Y1137045D01*
G03X798184Y1137617I-2095J-3321D01*
G01X798146Y1137622D01*
X798081Y1137658D01*
X797858Y1137929D01*
X797835Y1137999D01*
X797837Y1138038D01*
G03X797840Y1138130I-1499J95D01*
G03X794836I-1502J0D01*
G03X794837Y1138067I1502J-8D01*
G01X794839Y1138026D01*
X794810Y1137950D01*
X794582Y1137712D01*
G02X794438Y1137650I-145J138D01*
G01X787499D01*
G03X787252Y1137643I-12J-3926D01*
G02X787083Y1137718I-13J200D01*
G03X786063Y1138211I-1020J-809D01*
G03X785134Y1137821I0J-1301D01*
G01X785133Y1137820D01*
X785104Y1137791D01*
X784995Y1137744D01*
G02X784916Y1137728I-78J184D01*
G01X784710D01*
G02X784631Y1137744I-1J200D01*
G01X784522Y1137791D01*
X784493Y1137820D01*
X784492Y1137821D01*
G03X783563Y1138211I-929J-911D01*
G03X782394Y1137482I0J-1302D01*
G01X782369Y1137431D01*
X782272Y1137370D01*
X781114D01*
X781017Y1137431D01*
X780992Y1137482D01*
G03X778654I-1169J-573D01*
G01X778629Y1137431D01*
X778532Y1137370D01*
X777374D01*
X777277Y1137431D01*
X777252Y1137482D01*
G03X776445Y1138160I-1169J-573D01*
G02X776387Y1138187I54J192D01*
G03X774212Y1138866I-2176J-3148D01*
G01X773167D01*
G03X772383Y1138784I4J-3827D01*
G02X772301I-41J196D01*
G03X771831Y1138853I-790J-3744D01*
G02X771651Y1139013I16J199D01*
G03X771556Y1139298I-1179J-235D01*
G02X771823Y1139565I180J87D01*
G03X772342Y1139447I519J1084D01*
G03X771140Y1140649I0J1202D01*
G03X771161Y1140427I1202J2D01*
G01X771170Y1140378D01*
X771141Y1140285D01*
X770836Y1139980D01*
X770743Y1139951D01*
X770694Y1139960D01*
G03X770472Y1139981I-224J-1181D01*
G03X770250Y1139960I2J-1202D01*
G01X770201Y1139951D01*
X770108Y1139980D01*
X769803Y1140285D01*
X769774Y1140378D01*
X769783Y1140427D01*
G03X769804Y1140649I-1181J224D01*
G03X768602Y1139447I-1202J0D01*
G03X768824Y1139468I-2J1202D01*
G01X768873Y1139477D01*
X768966Y1139448D01*
X769271Y1139143D01*
X769300Y1139050D01*
X769291Y1139001D01*
G03X769270Y1138809I1181J-226D01*
G02X769140Y1138626I-200J4D01*
G03X768296Y1138187I1330J-3588D01*
G02X768238Y1138159I-115J164D01*
G03X767352Y1137272I364J-1250D01*
G02X767324Y1137214I-192J57D01*
G03X767008Y1136664I3148J-2175D01*
G02X766916Y1136570I-181J85D01*
G03X766758Y1136487I1686J-3401D01*
G01X766711Y1136461D01*
X766602Y1136463D01*
X766258Y1136675D01*
G02X766163Y1136853I105J170D01*
G01Y1136854D01*
G03X766164Y1136908I-1301J51D01*
G01Y1136910D01*
G03X766152Y1137093I-1302J6D01*
G01Y1137094D01*
G03X766103Y1137308I-1290J-183D01*
G01X766089Y1137347D01*
G03X764863Y1138212I-1227J-438D01*
G01X761122D01*
G03X759819Y1136909I0J-1303D01*
G03X759837Y1136695I1303J2D01*
G01X759845Y1136648D01*
X759817Y1136559D01*
X759530Y1136258D01*
X759442Y1136227D01*
X759395Y1136233D01*
G03X759252Y1136241I-139J-1194D01*
G03X760454Y1135039I0J-1202D01*
G03X760446Y1135182I-1202J4D01*
G01X760440Y1135229D01*
X760471Y1135317D01*
X760772Y1135604D01*
X760861Y1135632D01*
X760908Y1135624D01*
G03X761122Y1135606I216J1285D01*
G01X761399D01*
G02X761547Y1135540I0J-200D01*
G01X761775Y1135287D01*
X761801Y1135207D01*
X761797Y1135164D01*
G03X761790Y1135039I1195J-130D01*
G03X762992Y1133837I1202J0D01*
G03X763135Y1133846I-4J1202D01*
G01X763183Y1133851D01*
X763271Y1133820D01*
X763558Y1133519D01*
X763586Y1133430D01*
X763578Y1133383D01*
G03X763560Y1133169I1284J-216D01*
G03X763578Y1132955I1302J2D01*
G01X763586Y1132908D01*
X763558Y1132819D01*
X763271Y1132518D01*
X763183Y1132487D01*
X763135Y1132492D01*
G03X762992Y1132501I-147J-1193D01*
G03X761790Y1131299I0J-1202D01*
G03X761797Y1131172I1202J3D01*
G01X761801Y1131129D01*
X761775Y1131049D01*
X761548Y1130796D01*
G02X761399Y1130730I-149J134D01*
G01X761157D01*
X761156Y1130731D01*
X761122D01*
G03X760908Y1130713I2J-1303D01*
G01X760861Y1130705D01*
X760772Y1130733D01*
X760471Y1131020D01*
X760440Y1131108D01*
X760445Y1131156D01*
G03X760454Y1131299I-1193J147D01*
G03X759252Y1130097I-1202J0D01*
G03X759657Y1130167I1J1202D01*
G02X759910Y1129906I67J-188D01*
G03X759877Y1129812I1212J-478D01*
G01Y1129810D01*
G03X759862Y1129760I1240J-399D01*
G01Y1129759D01*
X759856Y1129735D01*
G03X759838Y1129650I1265J-312D01*
G01X759836Y1129634D01*
G03X759820Y1129428I1286J-204D01*
G03X759838Y1129215I1302J3D01*
G01X759845Y1129168D01*
X759818Y1129079D01*
X759531Y1128778D01*
X759443Y1128747D01*
X759395Y1128752D01*
G03X759252Y1128761I-147J-1193D01*
G03X760454Y1127559I0J-1202D01*
G03X760446Y1127702I-1202J4D01*
G01X760440Y1127749D01*
X760471Y1127837D01*
X760772Y1128124D01*
X760861Y1128152D01*
X760908Y1128144D01*
G03X761122Y1128126I216J1284D01*
G01X761399D01*
G02X761547Y1128060I0J-200D01*
G01X761775Y1127807D01*
X761801Y1127727D01*
X761797Y1127684D01*
G03X761790Y1127559I1195J-130D01*
G03X762992Y1126357I1202J0D01*
G03X763135Y1126366I-4J1202D01*
G01X763183Y1126371D01*
X763270Y1126340D01*
X763557Y1126039D01*
X763585Y1125950D01*
X763577Y1125902D01*
G03Y1125474I1284J-214D01*
G01X763585Y1125427D01*
X763557Y1125338D01*
X763270Y1125037D01*
X763182Y1125006D01*
X763135Y1125012D01*
G03X762992Y1125020I-139J-1194D01*
G03X761790Y1123818I0J-1202D01*
G03X761797Y1123692I1202J4D01*
G01X761801Y1123649D01*
X761775Y1123569D01*
X761548Y1123316D01*
G02X761399Y1123250I-149J134D01*
G01X761122D01*
G03X760908Y1123232I2J-1302D01*
G01X760861Y1123224D01*
X760772Y1123252D01*
X760471Y1123539D01*
X760440Y1123627D01*
X760445Y1123675D01*
G03X760454Y1123818I-1193J147D01*
G03X759252Y1122616I-1202J0D01*
G03X759395Y1122625I-4J1202D01*
G01X759443Y1122630D01*
X759531Y1122599D01*
X759818Y1122298D01*
X759846Y1122209D01*
X759838Y1122162D01*
G03X759820Y1121948I1284J-216D01*
G03X759838Y1121734I1302J2D01*
G01X759846Y1121687D01*
X759818Y1121598D01*
X759531Y1121297D01*
X759443Y1121266D01*
X759395Y1121271D01*
G03X759252Y1121280I-147J-1193D01*
G03X760454Y1120078I0J-1202D01*
G03X760445Y1120221I-1202J-4D01*
G01X760440Y1120269D01*
X760471Y1120357D01*
X760772Y1120644D01*
X760861Y1120672D01*
X760908Y1120664D01*
G03X761122Y1120646I216J1284D01*
G01X761399D01*
G02X761548Y1120580I0J-200D01*
G01X761775Y1120327D01*
X761801Y1120247D01*
X761797Y1120204D01*
G03X761790Y1120078I1195J-130D01*
G03X762992Y1118876I1202J0D01*
G03X763135Y1118885I-4J1202D01*
G01X763182Y1118890D01*
X763270Y1118859D01*
X763557Y1118558D01*
X763585Y1118469D01*
X763577Y1118422D01*
G03Y1117994I1284J-214D01*
G01X763585Y1117947D01*
X763557Y1117858D01*
X763270Y1117557D01*
X763182Y1117526D01*
X763135Y1117532D01*
G03X762992Y1117540I-139J-1194D01*
G03X761790Y1116338I0J-1202D01*
G03X761797Y1116212I1202J4D01*
G01X761801Y1116169D01*
X761775Y1116089D01*
X761548Y1115836D01*
G02X761399Y1115770I-149J134D01*
G01X761122D01*
G03X760908Y1115752I2J-1302D01*
G01X760861Y1115744D01*
X760772Y1115772D01*
X760471Y1116059D01*
X760440Y1116147D01*
X760445Y1116195D01*
G03X760454Y1116338I-1193J147D01*
G03X759252Y1115136I-1202J0D01*
G03X759395Y1115145I-4J1202D01*
G01X759443Y1115150D01*
X759531Y1115119D01*
X759818Y1114818D01*
X759846Y1114729D01*
X759838Y1114682D01*
G03X759820Y1114468I1284J-216D01*
G03X759838Y1114254I1302J2D01*
G01X759846Y1114207D01*
X759818Y1114118D01*
X759531Y1113817D01*
X759443Y1113786D01*
X759395Y1113791D01*
G03X759252Y1113800I-147J-1193D01*
G03X760454Y1112598I0J-1202D01*
G03X760445Y1112741I-1202J-4D01*
G01X760440Y1112789D01*
X760471Y1112877D01*
X760772Y1113164D01*
X760861Y1113192D01*
X760908Y1113184D01*
G03X761122Y1113166I216J1284D01*
G01X761399D01*
G02X761548Y1113100I0J-200D01*
G01X761775Y1112847D01*
X761801Y1112767D01*
X761797Y1112724D01*
G03X761790Y1112598I1195J-130D01*
G03X762992Y1111396I1202J0D01*
G03X763135Y1111405I-4J1202D01*
G01X763182Y1111410D01*
X763270Y1111379D01*
X763557Y1111078D01*
X763585Y1110989D01*
X763577Y1110942D01*
G03Y1110513I1284J-215D01*
G01X763585Y1110466D01*
X763557Y1110377D01*
X763270Y1110076D01*
X763182Y1110045D01*
X763135Y1110050D01*
G03X762991Y1110059I-147J-1193D01*
G03X761789Y1108857I0J-1202D01*
G03X761797Y1108715I1202J-3D01*
G01X761803Y1108668D01*
X761772Y1108580D01*
X761471Y1108293D01*
X761382Y1108266D01*
X761335Y1108273D01*
G03X761121Y1108291I-216J-1285D01*
G03X760908Y1108273I3J-1303D01*
G01X760861Y1108266D01*
X760772Y1108293D01*
X760471Y1108580D01*
X760440Y1108668D01*
X760446Y1108715D01*
G03X760454Y1108858I-1194J139D01*
G03X758050I-1202J0D01*
G03X758059Y1108715I1202J4D01*
G01X758064Y1108667D01*
X758033Y1108579D01*
X757732Y1108292D01*
X757643Y1108264D01*
X757596Y1108272D01*
G03X757382Y1108290I-216J-1284D01*
G03X757168Y1108272I2J-1302D01*
G01X757121Y1108264D01*
X757032Y1108292D01*
X756731Y1108579D01*
X756700Y1108667D01*
X756705Y1108715D01*
G03X756714Y1108858I-1193J147D01*
G03X754310I-1202J0D01*
G03X754319Y1108715I1202J4D01*
G01X754324Y1108668D01*
X754293Y1108580D01*
X753992Y1108293D01*
X753903Y1108265D01*
X753856Y1108273D01*
G03X753641Y1108291I-216J-1285D01*
G03X753428Y1108273I3J-1303D01*
G01X753381Y1108266D01*
X753292Y1108293D01*
X752991Y1108580D01*
X752960Y1108668D01*
X752966Y1108715D01*
G03X752974Y1108858I-1194J139D01*
G03X750570I-1202J0D01*
G03X750579Y1108714I1202J3D01*
G01X750584Y1108667D01*
X750553Y1108579D01*
X750252Y1108292D01*
X750163Y1108264D01*
X750116Y1108272D01*
G03X749901Y1108290I-216J-1284D01*
G03X749687Y1108272I2J-1302D01*
G01X749640Y1108264D01*
X749551Y1108292D01*
X749250Y1108579D01*
X749219Y1108667D01*
X749224Y1108715D01*
G03X749233Y1108858I-1193J147D01*
G03X746829I-1202J0D01*
G03X746837Y1108715I1202J-4D01*
G01X746843Y1108668D01*
X746812Y1108580D01*
X746511Y1108293D01*
X746422Y1108265D01*
X746375Y1108273D01*
G03X746161Y1108291I-216J-1285D01*
G03X745947Y1108273I2J-1303D01*
G01X745900Y1108265D01*
X745811Y1108293D01*
X745510Y1108580D01*
X745479Y1108668D01*
X745485Y1108715D01*
G03X745493Y1108858I-1194J139D01*
G03X743089I-1202J0D01*
G03X743098Y1108715I1202J4D01*
G01X743103Y1108667D01*
X743072Y1108579D01*
X742771Y1108292D01*
X742682Y1108264D01*
X742635Y1108272D01*
G03X742421Y1108290I-216J-1284D01*
G03X742207Y1108272I2J-1302D01*
G01X742160Y1108264D01*
X742071Y1108292D01*
X741770Y1108579D01*
X741739Y1108667D01*
X741744Y1108715D01*
G03X741753Y1108858I-1193J147D01*
G03X739349I-1202J0D01*
G03X739358Y1108714I1202J3D01*
G01X739363Y1108667D01*
X739332Y1108579D01*
X739031Y1108292D01*
X738942Y1108264D01*
X738895Y1108272D01*
G03X738680Y1108290I-216J-1284D01*
G03X738467Y1108272I3J-1302D01*
G01X738420Y1108265D01*
X738331Y1108292D01*
X738030Y1108579D01*
X737999Y1108667D01*
X738004Y1108715D01*
G03X738013Y1108858I-1193J147D01*
G03X735609I-1202J0D01*
G03X735618Y1108714I1202J3D01*
G01X735623Y1108666D01*
X735592Y1108579D01*
X735291Y1108291D01*
X735202Y1108263D01*
X735155Y1108271D01*
G03X734941Y1108289I-216J-1284D01*
G03X734727Y1108271I2J-1302D01*
G01X734680Y1108263D01*
X734591Y1108291D01*
X734290Y1108579D01*
X734259Y1108666D01*
X734264Y1108714D01*
G03X734273Y1108858I-1193J147D01*
G03X733071Y1110060I-1202J0D01*
G03X732927Y1110051I3J-1202D01*
G01X732879Y1110046D01*
X732792Y1110077D01*
X732504Y1110378D01*
X732477Y1110467D01*
X732484Y1110514D01*
G03X731928Y1111806I-1283J213D01*
G02X731840Y1111972I112J166D01*
G01Y1113222D01*
G02X731928Y1113388I200J0D01*
G03Y1115548I-727J1080D01*
G02X731840Y1115714I112J166D01*
G01Y1116962D01*
G02X731928Y1117128I200J0D01*
G03Y1119288I-727J1080D01*
G02X731840Y1119454I112J166D01*
G01Y1120702D01*
G02X731928Y1120868I200J0D01*
G03Y1123028I-727J1080D01*
G02X731840Y1123194I112J166D01*
G01Y1124442D01*
G02X731928Y1124608I200J0D01*
G03Y1126768I-727J1080D01*
G02X731840Y1126934I112J166D01*
G01Y1128183D01*
G02X731928Y1128349I200J0D01*
G03Y1130509I-727J1080D01*
G02X731840Y1130675I112J166D01*
G01Y1135663D01*
G02X731928Y1135829I200J0D01*
G03Y1137989I-727J1080D01*
G02X731840Y1138155I112J166D01*
G01Y1139403D01*
G02X731928Y1139569I200J0D01*
G03Y1141729I-727J1080D01*
G02X731840Y1141895I112J166D01*
G01Y1143143D01*
G02X731928Y1143309I200J0D01*
G03Y1145469I-727J1080D01*
G02X731840Y1145635I112J166D01*
G01Y1146883D01*
G02X731928Y1147049I200J0D01*
G03Y1149209I-727J1080D01*
G02X731840Y1149375I112J166D01*
G01Y1150623D01*
G02X731928Y1150789I200J0D01*
G03Y1152949I-727J1080D01*
G02X731840Y1153115I112J166D01*
G01Y1154364D01*
G02X731928Y1154530I200J0D01*
G03Y1156690I-727J1080D01*
G02X731840Y1156856I112J166D01*
G01Y1158104D01*
G02X731928Y1158270I200J0D01*
G03Y1160430I-727J1080D01*
G02X731840Y1160596I112J166D01*
G01Y1165584D01*
G02X731928Y1165750I200J0D01*
G03X732503Y1166830I-727J1080D01*
G03X732207Y1167657I-1303J0D01*
G01X732183Y1167686D01*
X732160Y1167755D01*
X732174Y1168061D01*
G02X732232Y1168193I200J-9D01*
G01X733578Y1169539D01*
G02X733710Y1169597I141J-142D01*
G01X734016Y1169611D01*
X734085Y1169588D01*
X734114Y1169564D01*
G03X734941Y1169268I827J1007D01*
G03X736241Y1170499I0J1302D01*
G01X736243Y1170536D01*
X736273Y1170603D01*
X736384Y1170714D01*
G02X736386Y1170716I142J-140D01*
G02X736526Y1170773I140J-143D01*
G01X737096D01*
G02X737129Y1170770I-2J-200D01*
G02X737236Y1170716I-32J-197D01*
G01X737349Y1170603D01*
X737379Y1170536D01*
X737381Y1170499D01*
G03X739981I1300J71D01*
G01X739983Y1170536D01*
X740013Y1170603D01*
X740124Y1170714D01*
G02X740126Y1170716I142J-140D01*
G02X740266Y1170773I140J-143D01*
G01X740444D01*
X740511Y1170748D01*
X740539Y1170724D01*
G03X741010Y1170410I1483J1714D01*
G01X741049Y1170391D01*
X741156Y1170260D01*
X741167Y1170220D01*
G03X742421Y1169268I1254J350D01*
G03X743616Y1170053I0J1302D01*
G01X743640Y1170109D01*
X743739Y1170174D01*
X744843D01*
X744942Y1170109D01*
X744966Y1170053D01*
G03X747356I1195J517D01*
G01X747380Y1170109D01*
X747479Y1170174D01*
X748583D01*
X748683Y1170109D01*
X748707Y1170053D01*
G03X750668Y1169517I1195J517D01*
G02X750811Y1169554I118J-161D01*
G01X750938Y1169537D01*
G02X751062Y1169472I-25J-198D01*
G03X751090Y1169442I531J467D01*
G01X752346Y1168186D01*
G03X752503Y1168068I499J501D01*
G01X752540Y1168048D01*
X752590Y1167982D01*
X752680Y1167613D01*
X752665Y1167532D01*
X752642Y1167497D01*
G03X752440Y1166830I1000J-667D01*
G03X754844I1202J0D01*
G03X754704Y1167392I-1202J-1D01*
G01X754680Y1167439D01*
X754682Y1167544D01*
X754886Y1167883D01*
G02X755058Y1167980I172J-103D01*
G01X755966D01*
G02X756138Y1167883I0J-200D01*
G01X756342Y1167544D01*
X756344Y1167439D01*
X756320Y1167392D01*
G03X756180Y1166830I1062J-563D01*
G03X758584I1202J0D01*
G03X758444Y1167392I-1202J-1D01*
G01X758420Y1167439D01*
X758422Y1167544D01*
X758626Y1167883D01*
G02X758798Y1167980I172J-103D01*
G01X759706D01*
G02X759878Y1167883I0J-200D01*
G01X760082Y1167544D01*
X760084Y1167439D01*
X760060Y1167392D01*
G03X759920Y1166830I1062J-563D01*
G03X762324I1202J0D01*
G03X762184Y1167392I-1202J-1D01*
G01X762160Y1167439D01*
X762162Y1167544D01*
X762366Y1167883D01*
G02X762538Y1167980I172J-103D01*
G01X763446D01*
G02X763618Y1167883I0J-200D01*
G01X763822Y1167544D01*
X763824Y1167439D01*
X763800Y1167392D01*
G03X763660Y1166830I1062J-563D01*
G03X766064I1202J0D01*
G03X765924Y1167392I-1202J-1D01*
G01X765900Y1167439D01*
X765902Y1167544D01*
X766106Y1167883D01*
G02X766278Y1167980I172J-103D01*
G01X767186D01*
G02X767358Y1167883I0J-200D01*
G01X767562Y1167544D01*
X767564Y1167439D01*
X767540Y1167392D01*
G03X767400Y1166830I1062J-563D01*
G03X769804I1202J0D01*
G03X769664Y1167392I-1202J-1D01*
G01X769640Y1167439D01*
X769642Y1167544D01*
X769846Y1167883D01*
G02X770018Y1167980I172J-103D01*
G01X770926D01*
G02X771098Y1167883I0J-200D01*
G01X771302Y1167544D01*
X771304Y1167439D01*
X771280Y1167392D01*
G03X771140Y1166830I1062J-563D01*
G03X773544I1202J0D01*
G03X773404Y1167392I-1202J-1D01*
G01X773380Y1167439D01*
X773382Y1167544D01*
X773586Y1167883D01*
G02X773758Y1167980I172J-103D01*
G01X774667D01*
G02X774839Y1167883I0J-200D01*
G01X775043Y1167544D01*
X775045Y1167439D01*
X775021Y1167392D01*
G03X774881Y1166830I1062J-563D01*
G03X777285I1202J0D01*
G03X777145Y1167392I-1202J-1D01*
G01X777121Y1167439D01*
X777123Y1167544D01*
X777327Y1167883D01*
G02X777499Y1167980I172J-103D01*
G01X778407D01*
G02X778579Y1167883I0J-200D01*
G01X778783Y1167544D01*
X778785Y1167439D01*
X778761Y1167392D01*
G03X778621Y1166830I1062J-563D01*
G03X781025I1202J0D01*
G03X780885Y1167392I-1202J-1D01*
G01X780861Y1167439D01*
X780863Y1167544D01*
X781067Y1167883D01*
G02X781239Y1167980I172J-103D01*
G01X782147D01*
G02X782319Y1167883I0J-200D01*
G01X782523Y1167544D01*
X782525Y1167439D01*
X782501Y1167392D01*
G03X782361Y1166830I1062J-563D01*
G03X784765I1202J0D01*
G03X784447Y1167644I-1201J0D01*
G01X784422Y1167672D01*
X784395Y1167741D01*
Y1167780D01*
G02X784595Y1167980I200J0D01*
G01X784626D01*
G03X785126Y1168186I1J707D01*
G01X787055Y1170115D01*
G02X787196Y1170174I142J-141D01*
G01X788382D01*
G03X789834Y1170701I-1J2266D01*
G01X789860Y1170723D01*
X789957Y1170760D01*
G02X790028Y1170773I71J-187D01*
G01X793059D01*
G03X793201Y1170832I0J200D01*
G01X793578Y1171209D01*
X793592Y1171219D01*
G03X794123Y1171750I-1315J1846D01*
G01X794133Y1171764D01*
X794145Y1171776D01*
X795461Y1173092D01*
G02X795602Y1173150I141J-142D01*
G01X796601D01*
G02X796767Y1173061I0J-200D01*
G01X796979Y1172741D01*
X796989Y1172641D01*
X796969Y1172595D01*
G03X796851Y1172011I1384J-584D01*
G03X799855I1502J0D01*
G03X799645Y1172776I-1502J-1D01*
G01X799623Y1172814D01*
X799614Y1172901D01*
X799740Y1173272D01*
X799800Y1173335D01*
X799841Y1173352D01*
G03X801268Y1175438I-840J2106D01*
G02X801273Y1175479I200J-4D01*
G03X801294Y1175589I-2255J487D01*
G01X801306Y1175662D01*
X801417Y1175756D01*
X803214D01*
G02X803322Y1175725I1J-200D01*
G03X804558Y1175366I1236J1948D01*
G01X805821D01*
G03X807452Y1176041I1J2306D01*
G01X807758Y1176347D01*
G02X807900Y1176406I142J-141D01*
G01X809390D01*
G03X810283Y1176776I-2J1267D01*
G01X812209Y1178703D01*
G02X812350Y1178762I142J-141D01*
G01X816928D01*
G03X817750Y1178913I1J2306D01*
G01X817784Y1178926D01*
X818271D01*
G03X819167Y1179297I0J1267D01*
G01X819810Y1179940D01*
G02X819812Y1179942I142J-140D01*
G02X819952Y1179999I140J-143D01*
G01X821664D01*
G02X821857Y1179851I0J-200D01*
G01Y1179850D01*
G03X823309Y1178733I1452J385D01*
G03X824811Y1180235I0J1502D01*
G01Y1180236D01*
G03X824771Y1180578I-1502J-2D01*
G01X824769Y1180588D01*
X824763Y1180635D01*
X824768Y1180676D01*
X824770Y1180688D01*
X824771Y1180694D01*
G03X824811Y1181034I-1462J344D01*
G01Y1181035D01*
G03X823773Y1182463I-1501J0D01*
G01X823711Y1182483D01*
X823635Y1182588D01*
Y1182828D01*
X823734Y1182941D01*
X823810Y1182950D01*
G03Y1187526I-295J2288D01*
G01X823734Y1187535D01*
X823635Y1187648D01*
Y1191351D01*
G02X823759Y1191536I200J0D01*
G01X823785Y1191547D01*
X823802Y1191550D01*
G03X824989Y1193019I-315J1469D01*
G03X823794Y1194489I-1502J0D01*
G01X823724Y1194504D01*
X823635Y1194614D01*
Y1198682D01*
G03X823578Y1198822I-200J0D01*
G01X823577Y1198823D01*
G02X823529Y1199020I144J139D01*
G01X823631Y1199358D01*
G02X823688Y1199448I191J-58D01*
G02X823783Y1199496I134J-148D01*
G03X824991Y1200969I-294J1473D01*
G03X823489Y1202471I-1502J0D01*
G03X822016Y1201263I0J-1502D01*
G01X822005Y1201208D01*
X821931Y1201127D01*
X821540Y1201009D01*
G02X821341Y1201059I-58J192D01*
G01X820928Y1201472D01*
X820913Y1201517D01*
G03X819967Y1202463I-1424J-478D01*
G01X819922Y1202478D01*
X819315Y1203085D01*
G02X819256Y1203227I141J142D01*
G01Y1210265D01*
G02X819310Y1210402I200J0D01*
G01X819523Y1210631D01*
X819590Y1210663D01*
X819629Y1210666D01*
G03X821024Y1212164I-107J1498D01*
G03X821001Y1212428I-1502J2D01*
G01X820992Y1212477D01*
X821021Y1212570D01*
X821231Y1212780D01*
G02X821373Y1212839I142J-141D01*
G37*
G36*
G01X799468Y54588D02*
X827614D01*
X827756Y54446D01*
Y52733D01*
X827614Y52591D01*
X799468D01*
G03X793531Y46654I0J-5937D01*
G01Y7874D01*
G02X787657Y2000I-5874J0D01*
G01X740413D01*
G02X734539Y7874I0J5874D01*
G01Y46261D01*
X736536D01*
Y7874D01*
G03X740411Y3998I3876J0D01*
G01X787657D01*
G03X791534Y7874I0J3877D01*
G01Y46654D01*
G02X799468Y54588I7934J0D01*
G37*
G36*
G01X809055Y1442438D02*
X823343D01*
G02X823484Y1442380I0J-200D01*
G01X823843Y1442021D01*
G02X823902Y1441879I-141J-142D01*
G01Y1439680D01*
G03X823961Y1439538I200J0D01*
G01X826056Y1437443D01*
G03X826198Y1437384I142J141D01*
G01X828775D01*
G02X828917Y1437325I0J-200D01*
G01X832070Y1434172D01*
G02X832129Y1434030I-141J-142D01*
G01Y1427579D01*
G02X832070Y1427437I-200J0D01*
G01X830908Y1426275D01*
G02X830766Y1426216I-142J141D01*
G01X821170D01*
G02X821028Y1426275I0J200D01*
G01X816529Y1430774D01*
G03X816387Y1430833I-142J-141D01*
G01X810168D01*
G02X810026Y1430892I0J200D01*
G01X809265Y1431653D01*
G02X809206Y1431794I141J142D01*
G01Y1434292D01*
G03X808824Y1435216I-1306J1D01*
G01X808349Y1435691D01*
G02X808290Y1435833I141J142D01*
G01Y1441673D01*
G02X808349Y1441815I200J0D01*
G01X808914Y1442380D01*
G02X809055Y1442438I141J-142D01*
G37*
G36*
G01X822554Y1626504D02*
X927703D01*
G02X927845Y1626445I0J-200D01*
G01X932332Y1621958D01*
G02X932391Y1621816I-141J-142D01*
G01Y1585734D01*
G03X932450Y1585592I200J0D01*
G01X940497Y1577545D01*
G03X940639Y1577486I142J141D01*
G01X956366D01*
G02X956508Y1577427I0J-200D01*
G01X960090Y1573845D01*
G02X960149Y1573703I-141J-142D01*
G01Y1545224D01*
G03X960208Y1545082I200J0D01*
G01X960222Y1545068D01*
Y1543190D01*
G03X960281Y1543048I200J0D01*
G01X964685Y1538644D01*
G03X964827Y1538585I142J141D01*
G01X1020051D01*
G02X1020193Y1538526I0J-200D01*
G01X1031736Y1526983D01*
G02X1031795Y1526841I-141J-142D01*
G01Y1492779D01*
G02X1031736Y1492637I-200J0D01*
G01X1031447Y1492348D01*
G02X1031305Y1492289I-142J141D01*
G01X957250D01*
X957246Y1492293D01*
X947172D01*
G02X947030Y1492352I0J200D01*
G01X944500Y1494882D01*
G03X944358Y1494941I-142J-141D01*
G01X933345D01*
G03X933203Y1494882I0J-200D01*
G01X930770Y1492449D01*
G02X930629Y1492390I-142J141D01*
G01X930399D01*
G03X929337Y1491951I-1J-1501D01*
G01X919309Y1481923D01*
G03X918870Y1480861I1062J-1061D01*
G01Y1480631D01*
G02X918811Y1480490I-200J1D01*
G01X917090Y1478769D01*
G03X917031Y1478627I141J-142D01*
G01Y1464953D01*
G02X916972Y1464811I-200J0D01*
G01X914131Y1461970D01*
G03X914072Y1461828I141J-142D01*
G01Y1460856D01*
G02X914013Y1460714I-200J0D01*
G01X913858Y1460559D01*
X913852D01*
X913446Y1460153D01*
G03X913387Y1460011I141J-142D01*
G01Y1446377D01*
G02X913328Y1446235I-200J0D01*
G01X913012Y1445919D01*
G02X912870Y1445860I-142J141D01*
G01X900424D01*
G02X900282Y1445919I0J200D01*
G01X900057Y1446144D01*
G02X899998Y1446286I141J142D01*
G01Y1459953D01*
G03X899939Y1460095I-200J0D01*
G01X899336Y1460698D01*
G02X899277Y1460840I141J142D01*
G01Y1462388D01*
G03X899218Y1462530I-200J0D01*
G01X894243Y1467505D01*
G02X894184Y1467647I141J142D01*
G01Y1473419D01*
G03X894125Y1473561I-200J0D01*
G01X888556Y1479130D01*
G03X888414Y1479189I-142J-141D01*
G01X880246D01*
G03X880104Y1479130I0J-200D01*
G01X872204Y1471230D01*
G03X872145Y1471088I141J-142D01*
G01Y1460906D01*
G02X872086Y1460764I-200J0D01*
G01X871408Y1460086D01*
G03X871349Y1459944I141J-142D01*
G01Y1446298D01*
G02X871290Y1446156I-200J0D01*
G01X871040Y1445906D01*
G02X870898Y1445847I-142J141D01*
G01X858576D01*
G02X858434Y1445906I0J200D01*
G01X857939Y1446401D01*
G02X857880Y1446543I141J142D01*
G01Y1459845D01*
G03X857821Y1459987I-200J0D01*
G01X853265Y1464543D01*
G03X853123Y1464602I-142J-141D01*
G01X828106D01*
G03X827964Y1464543I0J-200D01*
G01X826987Y1463566D01*
G03X826928Y1463424I141J-142D01*
G01Y1461709D01*
G02X826869Y1461567I-200J0D01*
G01X826719Y1461417D01*
G02X826577Y1461359I-141J142D01*
G01X824706D01*
G03X824564Y1461300I0J-200D01*
G01X822174Y1458910D01*
G03X822115Y1458768I141J-142D01*
G01Y1458505D01*
G02X822056Y1458363I-200J0D01*
G01X822029Y1458336D01*
X819764D01*
G03X819622Y1458277I0J-200D01*
G01X819287Y1457942D01*
G03X819228Y1457800I141J-142D01*
G01Y1446668D01*
G02X819028Y1446468I-200J0D01*
G01X805971D01*
G02X805771Y1446668I0J200D01*
G01Y1459991D01*
G02X805830Y1460133I200J0D01*
G01X806276Y1460579D01*
G03X806335Y1460721I-141J142D01*
G01Y1467878D01*
G02X806429Y1468048I200J0D01*
G01X806762Y1468255D01*
X806865Y1468260D01*
X806912Y1468237D01*
G03X807576Y1468082I664J1347D01*
G03Y1471086I0J1502D01*
G03X806912Y1470931I0J-1502D01*
G01X806865Y1470908D01*
X806762Y1470913D01*
X806429Y1471120D01*
G02X806335Y1471290I106J170D01*
G01Y1474404D01*
G02X806394Y1474546I200J0D01*
G01X806713Y1474865D01*
G03X806772Y1475007I-141J142D01*
G01Y1523862D01*
G02X806831Y1524004I200J0D01*
G01X816897Y1534070D01*
G03X816956Y1534212I-141J142D01*
G01Y1620906D01*
G02X817015Y1621048I200J0D01*
G01X822412Y1626445D01*
G02X822554Y1626504I142J-141D01*
G37*
G36*
G01X914633Y1227235D02*
X914427Y1227112D01*
G02X914183Y1227142I-103J172D01*
G01X910443Y1230882D01*
G02X910384Y1231024I141J142D01*
G01Y1231934D01*
G02X910405Y1232023I200J0D01*
G01X910406Y1232025D01*
G03X910579Y1232724I-1329J700D01*
G03X907575I-1502J0D01*
G03X907747Y1232027I1502J1D01*
G02X907749Y1232023I-178J-91D01*
G01X907760Y1232002D01*
X907770Y1231958D01*
Y1230400D01*
G03X908153Y1229476I1306J0D01*
G01X909585Y1228044D01*
G02X909637Y1227854I-142J-141D01*
G01X909539Y1227469D01*
X909465Y1227393D01*
X909438Y1227385D01*
G03X908336Y1225937I400J-1448D01*
G03X909387Y1224504I1502J0D01*
G01X909437Y1224489D01*
X909509Y1224413D01*
X909618Y1223981D01*
X909591Y1223882D01*
X909554Y1223844D01*
G03X909131Y1222799I1079J-1045D01*
G03X912135I1502J0D01*
G03X911585Y1223961I-1502J0D01*
G01X911536Y1224001D01*
X911502Y1224122D01*
X911651Y1224537D01*
G02X911839Y1224670I188J-67D01*
G01X912933D01*
G02X912961Y1224668I0J-200D01*
G01X914726Y1222903D01*
G02X914728Y1222875I-198J-28D01*
G01Y1222588D01*
G02X914528Y1222388I-200J0D01*
G01X914482D01*
X914441Y1222408D01*
G03X913785Y1222559I-656J-1351D01*
G01X913784D01*
G03Y1219555I0J-1502D01*
G03X914213Y1219618I-1J1502D01*
G01X914215D01*
X914260Y1219631D01*
X914352Y1219615D01*
X914647Y1219395D01*
G02X914728Y1219235I-119J-161D01*
G01Y1218194D01*
G02X914706Y1218103I-200J0D01*
G02X914670Y1218053I-178J90D01*
G01X914638Y1218021D01*
G03X914579Y1217879I141J-142D01*
G01Y1216520D01*
G02X914531Y1216390I-200J0D01*
G01X914508Y1216363D01*
X914445Y1216328D01*
X914409Y1216323D01*
G03Y1213353I227J-1485D01*
G02X914532Y1213285I-29J-198D01*
G01X914554Y1213259D01*
X914579Y1213192D01*
Y1212250D01*
G02X914531Y1212120I-200J0D01*
G01X914508Y1212093D01*
X914445Y1212058D01*
X914409Y1212053D01*
G03Y1209083I227J-1485D01*
G02X914532Y1209015I-29J-198D01*
G01X914554Y1208989D01*
X914579Y1208922D01*
Y1147443D01*
G03X914638Y1147301I200J0D01*
G01X915203Y1146736D01*
G02X915262Y1146594I-141J-142D01*
G01Y1108072D01*
G02X915203Y1107930I-200J0D01*
G01X913482Y1106209D01*
G03X913202Y1105793I924J-924D01*
G01X913187Y1105757D01*
X911510Y1104080D01*
G03X911451Y1103938I141J-142D01*
G01Y1091894D01*
G02X911392Y1091752I-200J0D01*
G01X909641Y1090001D01*
X909516Y1089980D01*
X909458Y1090009D01*
G03X908800Y1090161I-658J-1350D01*
G01X908799D01*
G03X907596Y1089558I0J-1502D01*
G02X907436Y1089478I-160J120D01*
G01X897495D01*
G02X897353Y1089537I0J200D01*
G01X896344Y1090546D01*
G02X896285Y1090688I141J142D01*
G01Y1096628D01*
G02X896344Y1096770I200J0D01*
G01X899493Y1099919D01*
G03X899552Y1100061I-141J142D01*
G01Y1133323D01*
G02X899611Y1133465I200J0D01*
G01X900493Y1134347D01*
G03X900552Y1134489I-141J142D01*
G01Y1141880D01*
G03X900493Y1142022I-200J0D01*
G01X899611Y1142904D01*
G02X899552Y1143046I141J142D01*
G01Y1143215D01*
G03X899493Y1143357I-200J0D01*
G01X899206Y1143644D01*
G02X899147Y1143778I141J142D01*
G01X899137Y1144051D01*
G02X899184Y1144188I200J8D01*
G01X899185Y1144189D01*
G03X899549Y1145169I-1137J980D01*
G03X898047Y1146671I-1502J0D01*
G03X897060Y1146301I0J-1501D01*
G01X897059D01*
Y1146300D01*
G02X896929Y1146252I-130J152D01*
G01X896665D01*
G02X896535Y1146300I0J200D01*
G01X896534Y1146301D01*
G03X895547Y1146671I-987J-1131D01*
G03X894046Y1145236I0J-1503D01*
G01X894045Y1145198D01*
X894013Y1145127D01*
X893785Y1144909D01*
G02X893647Y1144854I-138J145D01*
G01X870585D01*
G03X870443Y1144795I0J-200D01*
G01X865156Y1139508D01*
G03X865097Y1139366I141J-142D01*
G01Y1115149D01*
G02X865038Y1115007I-200J0D01*
G01X862511Y1112480D01*
G02X862369Y1112421I-142J141D01*
G01X859695D01*
X859622Y1112451D01*
X859613Y1112460D01*
X843732D01*
G02X843646Y1112480I1J200D01*
G03X842650Y1112706I-996J-2080D01*
G01X837245D01*
G02X837103Y1112765I0J200D01*
G01X834977Y1114891D01*
G02X834918Y1115033I141J142D01*
G01Y1117093D01*
G03X834243Y1118723I-2306J0D01*
G01X832913Y1120053D01*
G03X831283Y1120728I-1630J-1631D01*
G01X830054D01*
G02X829858Y1120889I0J200D01*
G03X828385Y1122101I-1473J-289D01*
G03X826883Y1120599I0J-1502D01*
G03X826977Y1120076I1502J0D01*
G03X826954Y1120053I1619J-1642D01*
G01X826225Y1119324D01*
G03X825550Y1117694I1631J-1630D01*
G01Y1116251D01*
G03X827773Y1113946I2307J0D01*
G02X827907Y1113888I-7J-200D01*
G01X827991Y1113804D01*
G02X828050Y1113662I-141J-142D01*
G01Y1113415D01*
G03X828099Y1112942I2306J0D01*
G01X828108Y1112897D01*
X828087Y1112811D01*
X827862Y1112534D01*
G02X827707Y1112460I-155J126D01*
G01X827101D01*
G02X826962Y1112516I0J200D01*
G01X824326Y1115061D01*
G02X824265Y1115205I139J144D01*
G01Y1126006D01*
G02X824324Y1126148I200J0D01*
G01X827532Y1129356D01*
G02X827589Y1129496I200J0D01*
G01X832318Y1134225D01*
G03X832377Y1134367I-141J142D01*
G01Y1208874D01*
G02X832381Y1208912I200J-2D01*
G02X832434Y1209014I196J-37D01*
G01X835024Y1211604D01*
G02X835126Y1211657I139J-143D01*
G02X835164Y1211661I40J-196D01*
G01X858118D01*
G03X858260Y1211720I0J200D01*
G01X859140Y1212600D01*
G03X859165Y1212630I-140J142D01*
G01X859262Y1212774D01*
X859277Y1212786D01*
X859323Y1212805D01*
G03X867593Y1225118I-5031J12313D01*
G03X862040Y1235930I-13302J0D01*
G03X861585Y1236243I-7765J-10800D01*
G03X859335Y1237430I-7303J-11118D01*
G01X859307Y1237442D01*
X859286Y1237459D01*
G02X859245Y1237503I124J157D01*
G01X859189Y1237586D01*
G02X859170Y1237621I165J112D01*
G02X859155Y1237675I183J80D01*
G02X859154Y1237699I199J20D01*
G01Y1264262D01*
G02X859158Y1264301I200J-1D01*
G02X859211Y1264402I196J-39D01*
G01X860275Y1265466D01*
G02X860377Y1265519I139J-143D01*
G02X860415Y1265523I40J-196D01*
G01X909101D01*
G02X909118Y1265522I-3J-200D01*
G02X909145Y1265518I-16J-199D01*
G02X909285Y1265400I-45J-195D01*
G01X914568Y1252646D01*
G02X914578Y1252596I-189J-64D01*
G02X914579Y1252581I-199J-21D01*
G01Y1234931D01*
G03X914638Y1234789I200J0D01*
G01X914671Y1234756D01*
G02X914724Y1234654I-143J-139D01*
G02X914728Y1234616I-196J-40D01*
G01Y1227405D01*
G02X914727Y1227389I-200J4D01*
G02X914633Y1227235I-199J16D01*
G37*
G36*
G01X949468Y54588D02*
X978644D01*
X978785Y54447D01*
Y52732D01*
X978644Y52591D01*
X949468D01*
G03X943531Y46654I0J-5937D01*
G01Y7874D01*
G02X937657Y2000I-5874J0D01*
G01X842776D01*
G02X836902Y7874I0J5874D01*
G01Y46658D01*
G03X836896Y46925I-5938J0D01*
G01X838895D01*
G02X838900Y46654I-7930J-282D01*
G01Y7874D01*
G03X842776Y3998I3876J0D01*
G01X937657D01*
G03X941534Y7874I0J3877D01*
G01Y46654D01*
G02X949468Y54588I7934J0D01*
G37*
G36*
G01X999222Y462244D02*
X1001399Y460067D01*
G02X1001453Y459960I-143J-139D01*
G02X1001456Y459927I-197J-35D01*
G01Y458026D01*
G02X1001411Y457900I-200J0D01*
G02X1001398Y457885I-157J123D01*
G01X973938Y430425D01*
G02X973746Y430373I-141J141D01*
G01X973414Y430459D01*
G02X973323Y430511I50J194D01*
G01X973322Y430512D01*
G02X973272Y430597I142J141D01*
G01X973271Y430599D01*
G03X972532Y431513I-1445J-412D01*
G03X972273Y431621I-705J-1327D01*
G01X972271D01*
X972248Y431629D01*
X972208Y431653D01*
X963054Y440807D01*
G02X963002Y440999I141J141D01*
G01X963102Y441384D01*
X963176Y441460D01*
X963227Y441474D01*
G03X964318Y442919I-411J1445D01*
G03X962816Y444421I-1502J0D01*
G03X961371Y443330I0J-1502D01*
G01X961357Y443279D01*
X961281Y443205D01*
X960896Y443105D01*
G02X960704Y443157I-51J193D01*
G01X953839Y450021D01*
G02X953780Y450163I141J142D01*
G01Y472429D01*
G03X953398Y473351I-1306J-1D01*
G01X930531Y496217D01*
G02X930472Y496359I141J142D01*
G01Y556033D01*
G02X930524Y556081I160J-121D01*
G01X930779Y556244D01*
G02X930887Y556276I108J-168D01*
G01X930998D01*
X931036Y556260D01*
G03X931065Y556248I589J1382D01*
G03X931428Y556152I563J1393D01*
G01X931464Y556147D01*
X931494Y556131D01*
G02X931547Y556090I-94J-176D01*
G01X931631Y555999D01*
G02X931680Y555876I-151J-131D01*
G01Y522528D01*
X931710Y522455D01*
X931731Y522434D01*
G03X931738Y522427I145J138D01*
G01X934211Y519954D01*
G03X934217Y519948I145J139D01*
G01X934219Y519947D01*
G03X934223Y519943I143J139D01*
G01X934240Y519926D01*
X934313Y519896D01*
X938526D01*
G02X938686Y519816I0J-200D01*
G01Y519662D01*
G03X939068Y518740I1306J1D01*
G01X948935Y508874D01*
G02X948994Y508732I-141J-142D01*
G01Y504005D01*
G03X949376Y503083I1306J1D01*
G01X950735Y501725D01*
G02X950794Y501583I-141J-142D01*
G01Y497663D01*
G02X950775Y497641I-161J120D01*
G02X950750Y497620I-141J142D01*
G01X950552Y497479D01*
X950550D01*
X950479Y497427D01*
G02X950370Y497394I-110J167D01*
G01X950305Y497405D01*
X950291Y497410D01*
G03X949826Y497484I-466J-1428D01*
G01X949823D01*
G03Y494480I0J-1502D01*
G01X949826D01*
G03X950305Y494559I-2J1502D01*
G01X950306D01*
G02X950400Y494568I66J-189D01*
G01X950446Y494561D01*
X950558Y494481D01*
X950560D01*
X950751Y494343D01*
G02X950794Y494301I-117J-163D01*
G01Y493663D01*
G02X950775Y493641I-161J120D01*
G02X950750Y493620I-141J142D01*
G01X950552Y493479D01*
X950550D01*
X950479Y493427D01*
G02X950370Y493394I-110J167D01*
G01X950305Y493405D01*
X950291Y493410D01*
G03X949826Y493484I-466J-1428D01*
G01X949823D01*
G03Y490480I0J-1502D01*
G01X949826D01*
G03X950305Y490559I-2J1502D01*
G01X950306D01*
G02X950400Y490568I66J-189D01*
G01X950446Y490561D01*
X950558Y490481D01*
X950560D01*
X950751Y490343D01*
G02X950794Y490301I-117J-163D01*
G01Y488799D01*
G03X951176Y487877I1306J1D01*
G01X957253Y481800D01*
G02X957302Y481720I-141J-142D01*
G01Y481719D01*
G03X958736Y480663I1434J446D01*
G03X960238Y482165I0J1502D01*
G03X959183Y483599I-1502J0D01*
G01X959181D01*
G02X959101Y483648I62J190D01*
G01X953465Y489283D01*
G02X953406Y489425I141J142D01*
G01Y502209D01*
G03X953024Y503131I-1306J-1D01*
G01X952885Y503270D01*
G02Y503553I141J141D01*
G01X952936Y503604D01*
X953077Y503618D01*
X953137Y503578D01*
G03X953974Y503323I837J1246D01*
G03X954961Y503693I0J1501D01*
G01X954962D01*
Y503694D01*
G02X955092Y503742I130J-152D01*
G01X955356D01*
G02X955486Y503694I0J-200D01*
G01X955487Y503693D01*
G03X957461I987J1131D01*
G01X957462D01*
Y503694D01*
G02X957592Y503742I130J-152D01*
G01X957856D01*
G02X957986Y503694I0J-200D01*
G01X957987Y503693D01*
G03X958974Y503323I987J1131D01*
G03Y506327I0J1502D01*
G03X957987Y505957I0J-1501D01*
G01X957986D01*
Y505956D01*
G02X957856Y505908I-130J152D01*
G01X957592D01*
G02X957462Y505956I0J200D01*
G01X957461Y505957D01*
G03X955487I-987J-1131D01*
G01X955486D01*
Y505956D01*
G02X955356Y505908I-130J152D01*
G01X955092D01*
G02X954962Y505956I0J200D01*
G01X954961Y505957D01*
G03X953974Y506327I-987J-1131D01*
G03X952472Y504825I0J-1502D01*
G03X952479Y504678I1502J-2D01*
G01X952485Y504615D01*
X952423Y504505D01*
X952025Y504317D01*
G02X951798Y504356I-86J181D01*
G01X951665Y504489D01*
G02X951606Y504631I141J142D01*
G01Y509358D01*
G03X951224Y510280I-1306J-1D01*
G01X941949Y519555D01*
G02X941906Y519772I142J141D01*
G01X941949Y519877D01*
G02X942034Y519896I85J-181D01*
G01X942211D01*
X942284Y519926D01*
X942312Y519954D01*
X943908Y521549D01*
X947076Y524717D01*
G03X947083Y524724I-138J145D01*
G01X947104Y524745D01*
X947134Y524818D01*
Y533591D01*
G02X947169Y533704I200J0D01*
G02X947256Y533775I165J-113D01*
G01X947287Y533788D01*
X947582Y533907D01*
G02X947736Y533904I73J-186D01*
G01X947821Y533867D01*
X947849Y533840D01*
G03X948905Y533406I1056J1068D01*
G03X948961Y533407I1J1503D01*
G01X948997Y533410D01*
G03X950407Y534909I-92J1499D01*
G03X948905Y536411I-1502J0D01*
G01X948855D01*
G03X947846Y535975I50J-1502D01*
G01X947818Y535948D01*
X947720Y535907D01*
G02X947588Y535909I-63J190D01*
G01X947461Y535960D01*
X947259Y536041D01*
G02X947134Y536226I75J185D01*
G01Y539516D01*
G02X947224Y539683I200J0D01*
G01X947234Y539689D01*
X947486Y539830D01*
G02X947583Y539855I97J-175D01*
G01X947684D01*
G02X947783Y539829I0J-200D01*
G03X948532Y539629I750J1306D01*
G03X950038Y541135I0J1506D01*
G03X948713Y542630I-1506J0D01*
G01X948703Y542632D01*
G03X948422Y542753I-191J-58D01*
G01X948025Y542554D01*
G02X948005Y542545I-92J178D01*
G03X947711Y542398I522J-1412D01*
G02X947542Y542409I-73J186D01*
G01X947532Y542415D01*
X947237Y542579D01*
G02X947134Y542754I97J175D01*
G01Y544977D01*
G02X947240Y545153I200J-1D01*
G01X947419Y545248D01*
X947552Y545319D01*
G02X947657Y545342I94J-177D01*
G01X947710Y545339D01*
X947756Y545309D01*
G02X947758Y545307I-138J-140D01*
G03X948006Y545172I839J1246D01*
G03X948529Y545052I592J1381D01*
G03X950100Y546553I68J1501D01*
G03X948598Y548055I-1502J0D01*
G01X948597D01*
G03X947757Y547798I0J-1502D01*
G02X947656Y547764I-112J166D01*
G01X947601Y547761D01*
X947419Y547858D01*
X947240Y547953D01*
G02X947134Y548129I94J177D01*
G01Y551165D01*
G02X947241Y551342I200J0D01*
G01X947402Y551427D01*
X947561Y551510D01*
G02X947645Y551529I85J-181D01*
G01X947692Y551526D01*
X947736Y551511D01*
X947762Y551493D01*
G03X948619Y551224I858J1234D01*
G01X948621D01*
G03Y554228I0J1502D01*
G03X947762Y553958I0J-1501D01*
G02X947660Y553922I-115J164D01*
G01X947606Y553919D01*
X947267Y554096D01*
X947241Y554110D01*
G02X947134Y554287I93J177D01*
G01Y579676D01*
G02X947165Y579783I200J0D01*
G01X947180Y579807D01*
X947222Y579843D01*
X947249Y579856D01*
X947251Y579857D01*
X947254Y579858D01*
G03Y582586I-628J1364D01*
G01X947251Y582587D01*
X947245Y582590D01*
G02X947160Y582670I89J179D01*
G02X947134Y582769I174J99D01*
G01Y589669D01*
G02X947165Y589776I200J0D01*
G01X947180Y589800D01*
X947222Y589836D01*
X947249Y589849D01*
X947251Y589850D01*
X947254Y589851D01*
G03Y592579I-628J1364D01*
G01X947251Y592580D01*
X947245Y592583D01*
G02X947160Y592663I89J179D01*
G02X947134Y592762I174J99D01*
G01Y632574D01*
G02X947138Y632612I200J-2D01*
G02X947191Y632714I196J-37D01*
G01X947326Y632849D01*
G03X947333Y632856I-138J145D01*
G01X947354Y632877D01*
X947384Y632950D01*
Y635251D01*
X947354Y635324D01*
X947333Y635345D01*
G03X947326Y635352I-145J-138D01*
G01X947325Y635353D01*
X946516Y636161D01*
G03X946374Y636220I-142J-141D01*
G01X933638D01*
G03X933496Y636162I-1J-200D01*
G01X932907Y635573D01*
X931738Y634404D01*
G03X931731Y634397I138J-145D01*
G01X931710Y634376D01*
X931680Y634303D01*
Y583351D01*
Y583343D01*
G02X931631Y583220I-200J8D01*
G01X931538Y583119D01*
G02X931452Y583070I-139J144D01*
G01X931428Y583067D01*
G03X930125Y581578I199J-1489D01*
G03X931427Y580089I1502J0D01*
G01X931464Y580084D01*
X931494Y580068D01*
G02X931549Y580026I-92J-178D01*
G01X931628Y579939D01*
G02X931680Y579805I-148J-135D01*
G01Y579351D01*
Y579343D01*
G02X931631Y579220I-200J8D01*
G01X931538Y579119D01*
G02X931452Y579070I-139J144D01*
G01X931428Y579067D01*
G03X930125Y577578I199J-1489D01*
G03X931427Y576089I1502J0D01*
G01X931464Y576084D01*
X931494Y576068D01*
G02X931549Y576026I-92J-178D01*
G01X931628Y575939D01*
G02X931680Y575805I-148J-135D01*
G01Y575351D01*
Y575343D01*
G02X931631Y575220I-200J8D01*
G01X931538Y575119D01*
G02X931452Y575070I-139J144D01*
G01X931428Y575067D01*
G03X930125Y573578I199J-1489D01*
G03X931427Y572089I1502J0D01*
G01X931464Y572084D01*
X931494Y572068D01*
G02X931549Y572026I-92J-178D01*
G01X931628Y571939D01*
G02X931680Y571805I-148J-135D01*
G01Y571351D01*
Y571343D01*
G02X931631Y571220I-200J8D01*
G01X931538Y571119D01*
G02X931452Y571070I-139J144D01*
G01X931428Y571067D01*
G03X930125Y569578I199J-1489D01*
G03X931427Y568089I1502J0D01*
G01X931464Y568084D01*
X931494Y568068D01*
G02X931549Y568026I-92J-178D01*
G01X931628Y567939D01*
G02X931680Y567805I-148J-135D01*
G01Y559414D01*
G02X931628Y559280I-200J1D01*
G01X931549Y559193D01*
G02X931451Y559134I-148J135D01*
G01X931429Y559131D01*
G03X931065Y559034I202J-1489D01*
G03X931036Y559022I560J-1394D01*
G01X930998Y559006D01*
X930887D01*
G02X930779Y559038I0J200D01*
G01X930524Y559201D01*
G02X930472Y559249I108J169D01*
G01Y563867D01*
G03X930090Y564789I-1306J-1D01*
G01X925329Y569550D01*
G02Y569606I198J28D01*
G01X928824Y573101D01*
G03X929206Y574023I-924J923D01*
G01Y628500D01*
G03X928824Y629422I-1306J-1D01*
G01X924109Y634137D01*
G02X924060Y634217I141J142D01*
G01Y634218D01*
G03X922626Y635274I-1434J-446D01*
G03X921124Y633772I0J-1502D01*
G03X922179Y632338I1502J0D01*
G01X922181D01*
G02X922261Y632289I-62J-190D01*
G01X926546Y628004D01*
G02X926548Y627976I-198J-28D01*
G01Y614254D01*
G02X926531Y614174I-200J1D01*
G01X926513Y614134D01*
X926258Y613907D01*
G02X926187Y613866I-133J149D01*
G01X926147Y613853D01*
X926105Y613857D01*
G03X925971Y613865I-156J-1494D01*
G01X925943D01*
G03X924447Y612363I6J-1502D01*
G03X925949Y610861I1502J0D01*
G03X926302Y610902I4J1502D01*
G01X926325Y610907D01*
X926368D01*
G02X926548Y610708I-20J-199D01*
G01Y610518D01*
G02X926362Y610318I-201J0D01*
G01X926333D01*
G02X926317Y610320I17J200D01*
G01X926301Y610324D01*
G03X925949Y610365I-349J-1461D01*
G03X924447Y608863I0J-1502D01*
G03X925943Y607361I1502J0D01*
G01X925951D01*
G03X926105Y607369I-1J1502D01*
G01X926147Y607373D01*
X926187Y607360D01*
G02X926258Y607319I-62J-190D01*
G01X926489Y607114D01*
G02X926531Y607053I-141J-142D01*
G01X926548Y607014D01*
Y574547D01*
G02X926546Y574519I-200J0D01*
G01X923088Y571061D01*
G02X923008Y571012I-142J141D01*
G01X923007D01*
G03X923006Y568144I445J-1434D01*
G01X923008D01*
G02X923088Y568095I-62J-190D01*
G01X927801Y563383D01*
G02X927860Y563241I-141J-142D01*
G01Y496984D01*
G02X927736Y496799I-200J0D01*
G01X927680Y496775D01*
X927562Y496799D01*
X900585Y523775D01*
G02X900526Y523917I141J142D01*
G01Y528405D01*
G02X900585Y528547I200J0D01*
G01X901161Y529122D01*
G03X901836Y530752I-1631J1630D01*
G01Y530753D01*
G03X901023Y532511I-2307J0D01*
G01X900981Y532546D01*
X900973Y532564D01*
G02X900954Y532634I180J86D01*
G01X900944Y532891D01*
G02X900994Y533032I200J8D01*
G01X901001Y533039D01*
G03X901433Y534093I-1070J1054D01*
G03X899931Y535595I-1502J0D01*
G03X898430Y534154I0J-1502D01*
G01X898429Y534122D01*
Y534093D01*
G03X898640Y533324I1502J-1D01*
G01X898642Y533321D01*
G02X898669Y533245I-171J-104D01*
G01X898674Y533207D01*
X898585Y532896D01*
X898533Y532833D01*
X898495Y532814D01*
G03X897899Y532384I1034J-2062D01*
G01X896589Y531074D01*
G03X895914Y529444I1631J-1630D01*
G01Y525967D01*
G02X895790Y525782I-200J0D01*
G01X895734Y525758D01*
X895616Y525782D01*
X888297Y533101D01*
G02X888238Y533243I141J142D01*
G01Y534093D01*
G03X883624I-2307J0D01*
G01Y532205D01*
G03X884300Y530574I2307J1D01*
G01X939369Y475505D01*
G02X939413Y475287I-141J-142D01*
G01X939390Y475231D01*
X939290Y475164D01*
X929714D01*
G02X929572Y475223I0J200D01*
G01X928874Y475921D01*
G02X928901Y476054I198J29D01*
G01X928964Y476154D01*
Y476156D01*
G03X928984Y476196I-168J109D01*
G01X929009Y476271D01*
G02X929063Y476353I189J-66D01*
G01X929071Y476360D01*
X929148Y476423D01*
G02X929193Y476451I127J-154D01*
G01X929216Y476461D01*
X929243Y476466D01*
G03X930501Y477948I-244J1482D01*
G03X928999Y479450I-1502J0D01*
G03X927516Y478191I0J-1503D01*
G01X927512Y478164D01*
X927490Y478117D01*
X927464Y478085D01*
X927406Y478014D01*
G02X927331Y477961I-150J132D01*
G01X927023Y477856D01*
G02X926943Y477852I-50J194D01*
G01X926482Y478313D01*
G02X926433Y478393I141J142D01*
G01Y478394D01*
G03X924999Y479450I-1434J-446D01*
G03X923497Y477948I0J-1502D01*
G03X924552Y476514I1502J0D01*
G01X924554D01*
G02X924634Y476465I-62J-190D01*
G01X928166Y472933D01*
G03X929090Y472550I924J923D01*
G01X939219D01*
G02X939361Y472491I0J-200D01*
G01X942835Y469018D01*
G02X942894Y468876I-141J-142D01*
G01Y447531D01*
G03X943276Y446609I1306J1D01*
G01X943595Y446290D01*
G02X943654Y446148I-141J-142D01*
G01Y445827D01*
G03X943729Y445396I1266J-2D01*
G03X944024Y444931I1191J430D01*
G01X957775Y431179D01*
G02X957782Y431170I-154J-127D01*
G01Y415668D01*
G02X957723Y415526I-200J0D01*
G01X933102Y390905D01*
G02X932960Y390846I-142J141D01*
G01X892144D01*
G02X892097Y390896I120J160D01*
G01X892057Y390959D01*
X891934Y391155D01*
G02X891903Y391262I169J107D01*
G01Y391378D01*
X891921Y391418D01*
G03X892055Y392038I-1367J620D01*
G03X889051I-1502J0D01*
G01Y392037D01*
G03X889203Y391379I1502J0D01*
G02X889223Y391280I-180J-88D01*
G01X889220Y391232D01*
X889008Y390894D01*
G02X888962Y390846I-165J112D01*
G01X887150D01*
G03X886226Y390463I0J-1306D01*
G01X880371Y384608D01*
G02X880291Y384559I-142J141D01*
G01X880290D01*
G03X879234Y383125I446J-1434D01*
G03X880736Y381623I1502J0D01*
G03X882170Y382678I0J1502D01*
G01Y382680D01*
G02X882219Y382760I190J-62D01*
G01X887632Y388173D01*
G02X887774Y388232I142J-141D01*
G01X889509D01*
G02X889538Y388205I-121J-159D01*
G01X889618Y388107D01*
X889739Y387958D01*
G02X889783Y387812I-155J-126D01*
G01X889781Y387794D01*
X889779Y387784D01*
G03X889749Y387483I1472J-299D01*
G01Y387477D01*
G03X890375Y386264I1502J7D01*
G02X890454Y386144I-117J-163D01*
G02X890458Y386117I-195J-43D01*
G01X890472Y385949D01*
G02X890413Y385792I-199J-15D01*
G01X890116Y385495D01*
G03X889440Y383864I1631J-1632D01*
G01Y383167D01*
G02X889381Y383025I-200J0D01*
G01X881921Y375565D01*
G03X881457Y374898I1632J-1630D01*
G02X881453Y374890I-181J85D01*
G03X881200Y373850I2014J-1041D01*
G01Y347915D01*
G03X883466Y345648I2267J0D01*
G03X885514Y346944I0J2266D01*
G02X885575Y347019I181J-85D01*
G01X885594Y347034D01*
X885637Y347052D01*
X885830Y347085D01*
X885993Y347112D01*
G02X886159Y347055I25J-198D01*
G01X886489Y346725D01*
G02X886543Y346618I-143J-139D01*
G02X886546Y346585I-197J-35D01*
G01Y346191D01*
G03X888812Y343924I2267J0D01*
G01X888814D01*
G03X889036Y343935I-1J2267D01*
G01X889078Y343939D01*
X889158Y343913D01*
X889410Y343686D01*
G02X889476Y343537I-134J-149D01*
G01Y339757D01*
G02X889417Y339615I-200J0D01*
G01X889077Y339275D01*
G03X888706Y338379I896J-896D01*
G01Y335399D01*
G03X889077Y334503I1267J0D01*
G01X889417Y334163D01*
G02X889476Y334021I-141J-142D01*
G01Y293186D01*
G02X889276Y292986I-200J0D01*
G01X885870D01*
G02X885779Y293008I0J200D01*
G02X885729Y293044I90J178D01*
G01X885378Y293395D01*
G02X885342Y293445I142J140D01*
G02X885320Y293536I178J91D01*
G01Y299540D01*
X885336Y299577D01*
G03X885453Y300159I-1386J581D01*
G01Y300162D01*
G03X883951Y301664I-1502J0D01*
G03X882797Y301124I0J-1503D01*
G01X882779Y301102D01*
X882703Y301065D01*
X882368Y301052D01*
G02X882218Y301110I-9J200D01*
G01X880595Y302734D01*
G02X880546Y302814I141J142D01*
G01Y302815D01*
G03X879420Y303839I-1434J-446D01*
G01X879419D01*
G02X879273Y303964I41J196D01*
G01X879136Y304328D01*
X879150Y304428D01*
X879166Y304450D01*
G03X879479Y305368I-1190J918D01*
G03X876475I-1502J0D01*
G01Y305311D01*
G03X876709Y304561I1502J57D01*
G02X876732Y304511I-168J-108D01*
G01X876757Y304428D01*
G02X876557Y304228I-200J0D01*
G01X876521Y304231D01*
G03X876246Y304256I-273J-1477D01*
G03X875385Y303985I0J-1503D01*
G02X875309Y303953I-114J164D01*
G01X874987Y304275D01*
G03X873357Y304950I-1630J-1631D01*
G01X872046D01*
G03X871823Y304939I2J-2306D01*
G02X871666Y304993I-19J199D01*
G01X871579Y305075D01*
X871486Y305164D01*
G02X871439Y305234I139J144D01*
G01X871424Y305271D01*
X871425Y305315D01*
G03X871426Y305367I-1501J55D01*
G01Y305369D01*
G03X871425Y305412I-1501J-13D01*
G01Y305414D01*
G03X870290Y306825I-1502J-46D01*
G01X870247Y306836D01*
G02X870141Y306903I48J194D01*
G01X870138Y306907D01*
Y311828D01*
G02X870228Y311896I161J-119D01*
G01X870290Y311911D01*
G03Y314825I-366J1457D01*
G01X870247Y314836D01*
G02X870141Y314903I48J194D01*
G01X870138Y314907D01*
Y319828D01*
G02X870228Y319896I161J-119D01*
G01X870290Y319911D01*
G03Y322825I-366J1457D01*
G01X870247Y322836D01*
G02X870141Y322903I48J194D01*
G01X870138Y322907D01*
Y327182D01*
G02X870228Y327250I161J-119D01*
G01X870290Y327265D01*
G03Y330179I-366J1457D01*
G01X870247Y330190D01*
G02X870141Y330257I48J194D01*
G01X870138Y330261D01*
Y332182D01*
G02X870228Y332250I161J-119D01*
G01X870290Y332265D01*
G03Y335179I-366J1457D01*
G01X870247Y335190D01*
G02X870141Y335257I48J194D01*
G01X870138Y335261D01*
Y341011D01*
G02X870154Y341030I161J-119D01*
G01X870320Y341203D01*
X870346Y341230D01*
X870477Y341290D01*
X870514Y341292D01*
G03X871915Y342791I-101J1499D01*
G03X870717Y344262I-1502J0D01*
G01X870672Y344271D01*
X870649Y344283D01*
X870529Y344404D01*
G02X870518Y344501I187J70D01*
G01X870742Y344725D01*
G03X871418Y346356I-1631J1632D01*
G01Y355304D01*
G03X870742Y356935I-2307J-1D01*
G01X854876Y372801D01*
G02X854875Y372843I199J26D01*
G01X854897Y373145D01*
G02X854898Y373154I199J-18D01*
G02X854971Y373286I199J-24D01*
G01X854972D01*
X854982Y373294D01*
G03X855588Y374500I-897J1206D01*
G03X854086Y376002I-1502J0D01*
G03X854025Y376001I-6J-1502D01*
G01X853992Y376000D01*
X853917Y376030D01*
X853888Y376058D01*
X853683Y376257D01*
G02X853622Y376401I139J144D01*
G01Y391086D01*
X853619Y391129D01*
X853634Y391168D01*
G02X853681Y391239I186J-72D01*
G01X853897Y391449D01*
G02X854023Y391498I131J-151D01*
G03X854086Y391497I55J1501D01*
G03Y394501I0J1502D01*
G01Y394502D01*
G03X853134Y394162I0J-1503D01*
G01X853108Y394139D01*
X853024Y394108D01*
G02X852908Y394101I-70J188D01*
G01X852614Y394171D01*
G02X852491Y394260I47J194D01*
G01X852487Y394266D01*
X852317Y394675D01*
X852041Y395343D01*
X852038Y395356D01*
G03X851931Y395680I-2238J-559D01*
G01X847051Y407459D01*
G02X847067Y407514I198J-28D01*
G01X847080Y407543D01*
X847092Y407571D01*
G02X847121Y407613I178J-92D01*
G01X847133Y407625D01*
G03X847600Y408713I-1036J1089D01*
G01Y408715D01*
G03X846098Y410217I-1502J0D01*
G03X846044Y410216I1J-1502D01*
G01X846010Y410215D01*
G02X845894Y410256I5J200D01*
G01X844115Y414550D01*
G02X844100Y414627I185J76D01*
G01Y419961D01*
G02X844159Y420103I200J0D01*
G01X875188Y451132D01*
G03X875864Y452763I-1631J1632D01*
G01Y513142D01*
G03X875827Y513550I-2307J-4D01*
G01X875824Y513567D01*
Y516798D01*
G03X875160Y518401I-2267J0D01*
G01X841902Y551658D01*
G02X841866Y551708I142J140D01*
G02X841844Y551799I178J91D01*
G01Y627924D01*
G02X841848Y627962I200J-2D01*
G02X841901Y628064I196J-37D01*
G01X849175Y635338D01*
G02X849332Y635435I283J-283D01*
G02X849395Y635445I62J-190D01*
G01X849548D01*
G02X849594Y635432I-86J-391D01*
G01Y631899D01*
G03X850269Y630269I2306J0D01*
G01X851716Y628822D01*
G03X853347Y628146I1632J1631D01*
G01X853989D01*
G03X856296Y630453I0J2307D01*
G03X855988Y631603I-2307J-2D01*
G02Y631803I173J100D01*
G03X856296Y632953I-1999J1152D01*
G01Y634858D01*
G02X856355Y635000I200J0D01*
G01X859889Y638535D01*
G02X860031Y638594I142J-141D01*
G01X863011D01*
G03X864641Y639269I0J2306D01*
G01X867520Y642149D01*
G02X867662Y642208I142J-141D01*
G01X977212D01*
G02X977348Y642155I0J-200D01*
G01X977359Y642144D01*
X977371Y642028D01*
G03X980359I1494J156D01*
G01X980363Y642069D01*
G02X980426Y642195I199J-21D01*
G01X980440Y642208D01*
X994849D01*
G02X994991Y642149I0J-200D01*
G01X997235Y639905D01*
G02X997294Y639763I-141J-142D01*
G01Y622525D01*
G03X997969Y620895I2306J0D01*
G01X999104Y619760D01*
G02X999163Y619618I-141J-142D01*
G01Y598402D01*
G02X999161Y598376I-200J2D01*
G02X999071Y598234I-198J26D01*
G01X998769Y598054D01*
G02X998672Y598025I-104J171D01*
G01X998620Y598024D01*
X998614Y598027D01*
X998573Y598050D01*
G03X997859Y598231I-715J-1321D01*
G01X997829D01*
G03Y595227I28J-1502D01*
G01X997859D01*
G03X998572Y595407I0J1502D01*
G02X998574Y595409I136J-134D01*
G01X998615Y595430D01*
X998620Y595433D01*
X998671Y595432D01*
G02X998769Y595404I-4J-200D01*
G01X998946Y595299D01*
X999070Y595225D01*
G02X999163Y595058I-107J-169D01*
G01Y580839D01*
G02X999093Y580687I-200J0D01*
G01X998842Y580486D01*
G02X998762Y580448I-124J157D01*
G01X998719Y580438D01*
X998673Y580449D01*
G03X998334Y580488I-340J-1463D01*
G01X998332D01*
G03Y577484I0J-1502D01*
G01X998344D01*
G03X998673Y577523I-11J1502D01*
G01X998719Y577534D01*
X998762Y577524D01*
G02X998842Y577486I-44J-195D01*
G01X999093Y577285D01*
G02X999163Y577133I-130J-152D01*
G01Y462386D01*
G03X999222Y462244I200J0D01*
G37*
G36*
G01X855301Y359004D02*
G03I-679J0D01*
G37*
G36*
G01X906816Y1025780D02*
Y1014008D01*
G02X906757Y1013866I-200J0D01*
G01X905291Y1012400D01*
G02X905149Y1012341I-142J141D01*
G01X863432D01*
X857102Y1018671D01*
Y1027160D01*
X858020Y1028077D01*
X866336D01*
G03X866478Y1028018I142J141D01*
G01X891821D01*
X904578D01*
X906816Y1025780D01*
G37*
G36*
G01X895895Y1076488D02*
X902507D01*
X905773Y1073222D01*
Y1032779D01*
X903355Y1030361D01*
X891842D01*
X891814Y1030332D01*
X891740Y1030302D01*
X867307D01*
X862446D01*
X859600Y1033148D01*
Y1092795D01*
X859666Y1092861D01*
X879522D01*
X883567Y1088816D01*
X895895Y1076488D01*
G37*
G36*
G01X893548Y1442644D02*
X918637D01*
G02X918779Y1442585I0J-200D01*
G01X919404Y1441960D01*
G02X919463Y1441818I-141J-142D01*
G01Y1426294D01*
G02X919404Y1426152I-200J0D01*
G01X918205Y1424953D01*
G02X918063Y1424894I-142J141D01*
G01X858634D01*
X851853D01*
G02X851838Y1424970I185J76D01*
G01Y1437454D01*
G02X851896Y1437595I200J0D01*
G01X856887Y1442585D01*
G02X857028Y1442644I142J-141D01*
G01X879940D01*
G02X880126Y1442518I0J-200D01*
G01X880286Y1442115D01*
X880260Y1441995D01*
X880215Y1441953D01*
G03X879742Y1440859I1029J-1094D01*
G03X882746I1502J0D01*
G03X882273Y1441953I-1502J0D01*
G01X882228Y1441995D01*
X882202Y1442115D01*
X882362Y1442518D01*
G02X882548Y1442644I186J-74D01*
G01X890940D01*
G02X891126Y1442518I0J-200D01*
G01X891286Y1442115D01*
X891260Y1441995D01*
X891215Y1441953D01*
G03X890742Y1440859I1029J-1094D01*
G03X893746I1502J0D01*
G03X893273Y1441953I-1502J0D01*
G01X893228Y1441995D01*
X893202Y1442115D01*
X893362Y1442518D01*
G02X893548Y1442644I186J-74D01*
G37*
G36*
G01X871615Y1143026D02*
X898073D01*
X899551Y1141548D01*
Y1134821D01*
X898076Y1133346D01*
Y1126730D01*
Y1100986D01*
X896522Y1099433D01*
G03X896380Y1099374I0J-200D01*
G01X894866Y1097860D01*
G03X894807Y1097718I141J-142D01*
G01Y1089638D01*
G03X894866Y1089496I200J0D01*
G01X896148Y1088214D01*
G03X896290Y1088155I142J141D01*
G01X904135D01*
G02X904277Y1088096I0J-200D01*
G01X904626Y1087747D01*
G02X904685Y1087605I-141J-142D01*
G01Y1080489D01*
X904148Y1079952D01*
X899044D01*
X888392Y1090604D01*
G03X888250Y1090663I-142J-141D01*
G01X885848D01*
G02X885706Y1090722I0J200D01*
G01X881565Y1094863D01*
G03X881423Y1094922I-142J-141D01*
G01X868476D01*
G02X868334Y1094981I0J200D01*
G01X866663Y1096652D01*
G02X866604Y1096794I141J142D01*
G01Y1105853D01*
G03X866545Y1105995I-200J0D01*
G01Y1137956D01*
G02X866602Y1138096I200J0D01*
G01X866603Y1138097D01*
X871473Y1142967D01*
G02X871475Y1142969I142J-140D01*
G02X871615Y1143026I140J-143D01*
G37*
G36*
G01X876297Y1299700D02*
G03I-597J0D01*
G37*
G36*
G01X943680Y241235D02*
X943668Y241230D01*
G03Y238458I581J-1386D01*
G01X943680Y238453D01*
G02X943786Y238318I-89J-179D01*
G02X943791Y238274I-195J-44D01*
G01Y237615D01*
G02X943732Y237473I-200J0D01*
G01X938664Y232405D01*
G02X938478Y232352I-141J142D01*
G01X938476D01*
G03X938125Y232393I-349J-1461D01*
G03X936623Y230914I0J-1502D01*
G01Y230907D01*
G02X936563Y230774I-200J10D01*
G01X936364Y230577D01*
G02X936360Y230573I-143J139D01*
G02X936223Y230519I-137J146D01*
G01X921806D01*
X921799Y230520D01*
X921789D01*
G02X921658Y230581I13J199D01*
G01X921459Y230788D01*
G02X921415Y230857I143J140D01*
G01X921401Y230895D01*
X921403Y230936D01*
G03X921404Y230999I-1501J55D01*
G01Y231001D01*
G03X920882Y232139I-1502J0D01*
G01X920866Y232153D01*
X920840Y232187D01*
X920831Y232206D01*
G02X920813Y232288I182J83D01*
G01X920809Y232590D01*
G02X920826Y232671I200J0D01*
G01X920843Y232711D01*
X920876Y232740D01*
G03X921375Y233858I-1003J1118D01*
G03X920836Y235011I-1503J0D01*
G02X920785Y235077I129J153D01*
G01X920728Y235194D01*
Y235201D01*
X920738Y235523D01*
G02X920763Y235613I200J-7D01*
G01X920774Y235633D01*
X920806Y235667D01*
X920826Y235681D01*
G03X921480Y236921I-849J1240D01*
G03X919978Y238423I-1502J0D01*
G01X919977D01*
G03X919868Y238419I1J-1502D01*
G01X919865D01*
G02X919841I-12J199D01*
G01X919838D01*
G03X919729Y238423I-110J-1498D01*
G01X919708D01*
G02X919702I-3J200D01*
G01X919682D01*
G03X918180Y236921I0J-1502D01*
G03X918772Y235726I1502J0D01*
G01X918792Y235711D01*
X918822Y235673D01*
X918833Y235650D01*
G02X918851Y235557I-182J-83D01*
G01X918836Y235274D01*
G02X918778Y235143I-200J10D01*
G01X918761Y235126D01*
G02X918732Y235102I-141J141D01*
G03X918071Y233858I840J-1244D01*
G03X918607Y232708I1502J0D01*
G01X918610Y232706D01*
G03X918613Y232703I1063J1060D01*
G01X918628Y232688D01*
G02X918686Y232553I-142J-141D01*
G01X918694Y232292D01*
G02X918677Y232207I-200J-4D01*
G01X918660Y232167D01*
X918625Y232137D01*
G03X918104Y231000I980J-1137D01*
G03X918108Y230896I1502J6D01*
G01X918111Y230853D01*
X918096Y230814D01*
G02X918053Y230745I-188J69D01*
G01X917895Y230580D01*
G02X917751Y230519I-144J139D01*
G01X914659D01*
X914652Y230520D01*
X914642D01*
G02X914595Y230529I14J200D01*
G02X914564Y230542I62J190D01*
G02X914515Y230578I93J177D01*
G01X914315Y230778D01*
G02X914303Y230791I141J142D01*
G02X914257Y230908I154J128D01*
G01Y230920D01*
G03X909521Y235506I-4602J-14D01*
G01X909509D01*
G03X904761Y230727I-149J-4600D01*
G01Y230719D01*
G02X904561Y230519I-200J0D01*
G01X904374D01*
G02X904232Y230578I0J200D01*
G01X898405Y236405D01*
G02X898365Y236631I141J142D01*
G01X898523Y236972D01*
G02X898605Y237062I182J-83D01*
G01X898631Y237077D01*
X898689Y237090D01*
X898722Y237087D01*
G03X898850Y237081I134J1496D01*
G01X898852D01*
G03X898981Y237087I-5J1502D01*
G01X898983D01*
G02X899007Y237088I20J-199D01*
G03X899147Y237081I145J1494D01*
G03Y240085I0J1502D01*
G03X899007Y240078I5J-1501D01*
G02X898983Y240079I-4J200D01*
G01X898981D01*
G03X898851Y240085I-134J-1496D01*
G03X897365Y238802I0J-1502D01*
G01X897361Y238774D01*
X897339Y238725D01*
X897286Y238661D01*
X897264Y238653D01*
X897216Y238637D01*
G02X897134Y238631I-55J192D01*
G01X897117Y238634D01*
G02X897035Y238675I46J194D01*
G01X897034D01*
G03X896077Y239020I-958J-1158D01*
G01X896075D01*
G03X895932Y239014I-9J-1503D01*
G01X895903D01*
G03X895865Y239017I-137J-1496D01*
G01X895828Y239019D01*
X895796Y239033D01*
G02X895735Y239075I81J183D01*
G01X895480Y239330D01*
G02X895461Y239352I141J141D01*
G02X895421Y239472I160J120D01*
G01Y241475D01*
G02X895500Y241634I200J0D01*
G01X895692Y241779D01*
G02X895761Y241813I121J-159D01*
G01X895798Y241823D01*
X895838Y241818D01*
G03X896034Y241805I197J1489D01*
G03X896163Y241811I-5J1502D01*
G01X896165D01*
G02X896188Y241812I20J-199D01*
G03X896327Y241805I145J1495D01*
G01X896330D01*
G03X897832Y243307I0J1502D01*
G03X897624Y244069I-1502J-1D01*
G01X897618Y244080D01*
G02X897604Y244113I176J94D01*
G01X897603Y244120D01*
G02X897596Y244170I193J52D01*
G01Y244333D01*
G02X897796Y244533I200J0D01*
G01X897830D01*
X897893Y244512D01*
X897920Y244490D01*
G03X898851Y244167I931J1180D01*
G03X898981Y244173I-4J1502D01*
G01X898983D01*
G02X899007Y244174I20J-199D01*
G03X899147Y244167I145J1495D01*
G03Y247171I0J1502D01*
G03X899007Y247164I5J-1502D01*
G02X898983Y247165I-4J200D01*
G01X898981D01*
G03X898851Y247171I-134J-1496D01*
G03X897871Y246807I0J-1501D01*
G01X897853Y246792D01*
X897814Y246771D01*
X897791Y246765D01*
G02X897702Y246763I-49J194D01*
G01X897672Y246769D01*
G02X897587Y246808I39J196D01*
G01X897519Y246862D01*
G02X897463Y246930I123J158D01*
G03X897456Y246945I-1151J-528D01*
G03X897226Y247261I-1127J-579D01*
G01X896261Y248225D01*
X896151Y248335D01*
G02X896137Y248351I143J139D01*
G02X896093Y248485I156J125D01*
G01X896114Y248708D01*
X896123Y248800D01*
G02X896150Y248884I199J-18D01*
G01X896152Y248888D01*
G02X896171Y248913I168J-108D01*
G01X896191Y248934D01*
X896209Y248947D01*
X896211Y248948D01*
G03X896862Y250186I-852J1238D01*
G03X895590Y251670I-1502J0D01*
G01X895555Y251676D01*
X895515Y251698D01*
G02X895471Y251736I107J169D01*
G01X895469Y251738D01*
G02X895424Y251835I152J130D01*
G02X895421Y251868I197J35D01*
G01Y256284D01*
G02X895422Y256304I200J0D01*
G02X895531Y256463I199J-20D01*
G02X895555Y256473I89J-179D01*
G01X895644Y256505D01*
X895646D01*
X895684Y256518D01*
G02X895798Y256524I67J-188D01*
G01X895799Y256523D01*
G02X895896Y256466I-49J-194D01*
G01X895897Y256465D01*
G03X897004Y255978I1107J1015D01*
G03X897134Y255984I-4J1502D01*
G01X897136D01*
G02X897160Y255985I20J-199D01*
G03X897300Y255978I145J1494D01*
G03X898802Y257480I0J1502D01*
G03X898757Y257844I-1502J-1D01*
G01X898755Y257852D01*
X898754Y257860D01*
G02X898794Y258016I197J33D01*
G01X898988Y258264D01*
G02X899145Y258341I158J-123D01*
G01X899147D01*
G03Y261345I0J1502D01*
G03X899007Y261338I5J-1502D01*
G02X898983Y261339I-4J200D01*
G01X898981D01*
G03X898851Y261345I-134J-1496D01*
G03X897349Y259843I0J-1502D01*
G01Y259840D01*
G03X897427Y259364I1502J2D01*
G02X897435Y259333I-189J-65D01*
G01X897443Y259283D01*
G02X897411Y259174I-200J-1D01*
G01X897366Y259106D01*
G02X897301Y259045I-166J112D01*
G01X897189Y258978D01*
X897183Y258977D01*
G03X897160Y258975I119J-1496D01*
G02X897136Y258976I-4J200D01*
G01X897134D01*
G03X897004Y258982I-134J-1496D01*
G03X895898Y258496I0J-1501D01*
G02X895896Y258494I-142J140D01*
G02X895799Y258437I-146J137D01*
G01X895798Y258436D01*
G02X895684Y258442I-47J194D01*
G01X895645Y258455D01*
X895555Y258487D01*
G02X895531Y258497I65J189D01*
G02X895422Y258656I90J179D01*
G02X895421Y258676I199J20D01*
G01Y263544D01*
G02X895436Y263621I200J1D01*
G02X895591Y263742I185J-77D01*
G01X895599Y263743D01*
G03X896938Y265236I-163J1493D01*
G03X896907Y265543I-1502J3D01*
G01X896906Y265547D01*
G02X896902Y265586I196J40D01*
G01Y267795D01*
Y267798D01*
G02X897005Y267970I200J-3D01*
G02X897007Y267971I90J-178D01*
G01X897163Y268055D01*
G02X897256Y268079I95J-176D01*
G01X897306Y268080D01*
X897350Y268058D01*
G02X897352Y268056I-140J-142D01*
G03X897365Y268050I635J1359D01*
G02X897424Y268004I-91J-178D01*
G01X897475Y267945D01*
G02X897514Y267877I-151J-132D01*
G01X897541Y267796D01*
G02X897549Y267759I-191J-61D01*
G02X897527Y267638I-198J-26D01*
G03X897349Y266929I1323J-709D01*
G03X898851Y265427I1502J0D01*
G03X898981Y265433I-4J1502D01*
G01X898983D01*
G02X899007Y265434I20J-199D01*
G03X899147Y265427I145J1495D01*
G03X900649Y266929I0J1502D01*
G03X899877Y268242I-1503J0D01*
G01X899843Y268261D01*
X899820Y268289D01*
G02X899784Y268354I154J128D01*
G01X899700Y268613D01*
G02X899690Y268676I190J62D01*
G01X899703Y268738D01*
G02X899716Y268777I196J-44D01*
G03X899846Y269387I-1372J611D01*
G03X898344Y270889I-1502J0D01*
G03X898204Y270882I5J-1502D01*
G02X898180Y270883I-4J200D01*
G01X898178D01*
G03X898048Y270889I-134J-1496D01*
G03X897149Y270590I0J-1502D01*
G02X897147Y270588I-141J139D01*
G01X897112Y270563D01*
X897070Y270554D01*
G02X896984Y270555I-41J196D01*
G01X896904Y270573D01*
G02X896821Y270613I43J195D01*
G01X896805Y270626D01*
X896777Y270662D01*
X896767Y270684D01*
G03X896473Y271105I-1331J-616D01*
G01X895480Y272098D01*
G02X895421Y272240I141J142D01*
G01Y272953D01*
G02X895443Y273044I200J0D01*
G02X895479Y273094I178J-90D01*
G01X896288Y273903D01*
G02X896333Y273937I142J-141D01*
G01X896355Y273949D01*
X896376Y273955D01*
X896382Y273956D01*
G03X896823Y274105I-705J2815D01*
G01X896857Y274119D01*
X896902Y274117D01*
G02X896988Y274092I-11J-200D01*
G01X897266Y273937D01*
G02X897333Y273876I-98J-175D01*
G01X897359Y273839D01*
X897366Y273792D01*
G03X898851Y272514I1485J224D01*
G03X898981Y272520I-4J1502D01*
G01X898983D01*
G02X899007Y272521I20J-199D01*
G03X899147Y272514I145J1495D01*
G03X900649Y274016I0J1502D01*
G03X900606Y274372I-1502J-1D01*
G01X900595Y274417D01*
X900605Y274462D01*
G02X900642Y274541I195J-43D01*
G01X900836Y274790D01*
G02X900960Y274864I158J-123D01*
G02X900993Y274867I35J-197D01*
G01X904558D01*
G02X904758Y274667I0J-200D01*
G01Y274664D01*
G03X909486Y270006I4602J-57D01*
G01X909487D01*
G03X914257Y274664I168J4599D01*
G01Y274667D01*
G02X914443Y274866I199J0D01*
G01X914452D01*
X914459Y274867D01*
X917878D01*
G02X918015Y274812I-1J-200D01*
G01X918166Y274669D01*
G02X918211Y274604I-139J-144D01*
G01X918226Y274571D01*
X918228Y274531D01*
G03X919729Y273078I1501J49D01*
G01X919799D01*
G03X919885Y273082I-27J1502D01*
G01X919888D01*
G02X919912I12J-199D01*
G01X919915D01*
G03X920024Y273078I110J1498D01*
G01X920025D01*
G03X921524Y274489I0J1502D01*
G01Y274491D01*
X921527Y274529D01*
X921543Y274563D01*
G02X921587Y274624I181J-84D01*
G01X921785Y274812D01*
G02X921906Y274866I137J-145D01*
G01X921915D01*
X921923Y274867D01*
X936592D01*
G02X936624Y274864I-3J-200D01*
G01X936626D01*
G02X936732Y274810I-34J-197D01*
G01X943732Y267810D01*
G02X943751Y267788I-141J-141D01*
G02X943791Y267668I-160J-120D01*
G01Y241414D01*
G02X943786Y241370I-200J0D01*
G02X943680Y241235I-195J44D01*
G37*
G36*
G01X891335Y1311132D02*
G03I-597J0D01*
G37*
G36*
G01X911559Y800510D02*
G03I-506J0D01*
G37*
G36*
G01X914454Y855750D02*
X914630D01*
G02X914805Y855645I-1J-200D01*
G01X914858Y855548D01*
G02X914877Y855404I-175J-96D01*
G01X914864Y855354D01*
X914854Y855333D01*
G03X914712Y854742I1159J-591D01*
G03X917316I1302J0D01*
G03X917217Y855241I-1302J1D01*
G01X917193Y855298D01*
X917218Y855418D01*
X917262Y855461D01*
G02X917543Y855459I139J-143D01*
G01X917866Y855136D01*
X917895Y855040D01*
X917885Y854991D01*
G03X917861Y854750I1278J-249D01*
G01Y854733D01*
G03X918037Y854088I1302J9D01*
G01X918057Y854054D01*
X918068Y853979D01*
X917984Y853634D01*
X917940Y853572D01*
X917907Y853550D01*
G03X916836Y851592I1256J-1959D01*
G03X917344Y850142I2327J1D01*
G02Y849892I-156J-125D01*
G03X917205Y849698I1819J-1450D01*
G01X917184Y849665D01*
X917122Y849621D01*
X916777Y849538D01*
X916701Y849548D01*
X916667Y849568D01*
G03X916014Y849744I-654J-1126D01*
G03Y847140I0J-1302D01*
G03X916667Y847316I-1J1302D01*
G01X916701Y847336D01*
X916777Y847346D01*
X917122Y847263D01*
X917184Y847219D01*
X917205Y847186D01*
G03X917907Y846484I1958J1256D01*
G01X917940Y846463D01*
X917984Y846401D01*
X918067Y846056D01*
X918057Y845980D01*
X918037Y845946D01*
G03X917861Y845293I1126J-654D01*
G03X919163Y843991I1302J0D01*
G03X919884Y844209I0J1301D01*
G02X919994Y844242I110J-167D01*
G01X921482D01*
G02X921592Y844209I0J-200D01*
G03X923034I721J1083D01*
G02X923144Y844242I110J-167D01*
G01X924448D01*
G02X924590Y844183I0J-200D01*
G01X924964Y843809D01*
G03X925955Y843398I992J991D01*
G01X930900D01*
G03X931219Y843435I-1J1402D01*
G01X931253Y843443D01*
X931322Y843435D01*
X931615Y843288D01*
X931662Y843238D01*
X931677Y843205D01*
G03X932074Y842666I1377J599D01*
G01X932108Y842636D01*
X932144Y842557D01*
X932140Y842161D01*
X932102Y842082D01*
X932067Y842053D01*
G03X931519Y840893I954J-1160D01*
G03X933021Y839391I1502J0D01*
G03X934501Y840637I0J1502D01*
G01X934511Y840693D01*
X934584Y840777D01*
X934976Y840901D01*
G02X935178Y840852I61J-191D01*
G01X937236Y838794D01*
G02X937238Y838792I-140J-142D01*
G02X937295Y838652I-143J-140D01*
G01Y823952D01*
G02X937236Y823810I-200J0D01*
G01X934711Y821285D01*
X934683Y821256D01*
X934609Y821226D01*
X908086D01*
G02X907944Y821285I0J200D01*
G01X900628Y828601D01*
X900599Y828629D01*
X900569Y828703D01*
Y834272D01*
G02X900627Y834413I200J0D01*
G01X900924Y834711D01*
G02X900941Y834726I141J-142D01*
G01X900966Y834746D01*
X900974Y834751D01*
G03X901568Y835844I-709J1093D01*
G03X900702Y837071I-1302J0D01*
G01X900642Y837092D01*
X900569Y837195D01*
Y837641D01*
X900642Y837743D01*
X900702Y837765D01*
G03X901569Y838992I-435J1227D01*
G03X900853Y840155I-1303J0D01*
G01X900824Y840169D01*
X900628Y840366D01*
G02X900569Y840507I141J142D01*
G01Y840792D01*
X900642Y840894D01*
X900702Y840916D01*
G03Y843370I-435J1227D01*
G01X900642Y843392D01*
X900569Y843494D01*
Y843942D01*
X900642Y844044D01*
X900702Y844066D01*
G03Y846520I-435J1227D01*
G01X900642Y846542D01*
X900569Y846644D01*
Y847091D01*
X900642Y847193D01*
X900702Y847215D01*
G03Y849669I-435J1227D01*
G01X900642Y849691D01*
X900569Y849793D01*
Y850241D01*
X900642Y850343D01*
X900702Y850365D01*
G03Y852819I-435J1227D01*
G01X900642Y852841D01*
X900569Y852943D01*
Y853391D01*
X900642Y853493D01*
X900702Y853515D01*
G03X901569Y854742I-435J1227D01*
G03X901477Y855222I-1302J-1D01*
G01X901455Y855278D01*
X901479Y855394D01*
X901776Y855691D01*
G02X901778Y855693I142J-140D01*
G02X901918Y855750I140J-143D01*
G01X904975D01*
G02X905140Y855663I0J-200D01*
G01X905355Y855351D01*
X905367Y855254D01*
X905349Y855207D01*
G03X905263Y854742I1216J-465D01*
G03X907867I1302J0D01*
G03X907781Y855207I-1302J0D01*
G01X907763Y855254D01*
X907775Y855351D01*
X907990Y855663D01*
G02X908155Y855750I165J-113D01*
G01X908330D01*
G02X908505Y855645I-1J-200D01*
G01X908558Y855548D01*
G02X908577Y855404I-175J-96D01*
G01X908564Y855354D01*
X908554Y855333D01*
G03X908412Y854742I1159J-591D01*
G03X911016I1302J0D01*
G03X910930Y855207I-1302J0D01*
G01X910912Y855254D01*
X910924Y855351D01*
X911139Y855663D01*
G02X911304Y855750I165J-113D01*
G01X911480D01*
G02X911655Y855645I-1J-200D01*
G01X911708Y855548D01*
G02X911727Y855404I-175J-96D01*
G01X911714Y855354D01*
X911704Y855333D01*
G03X911562Y854742I1159J-591D01*
G03X914166I1302J0D01*
G03X914080Y855207I-1302J0D01*
G01X914062Y855254D01*
X914074Y855351D01*
X914289Y855663D01*
G02X914454Y855750I165J-113D01*
G37*
G36*
G01X982406Y1144698D02*
X1003253D01*
G02X1003395Y1144639I0J-200D01*
G01X1004833Y1143201D01*
G02X1004892Y1143059I-141J-142D01*
G01Y1060869D01*
G02X1004833Y1060727I-200J0D01*
G01X975719Y1031613D01*
G02X975577Y1031554I-142J141D01*
G01X975366D01*
G03X975224Y1031495I0J-200D01*
G01X972660Y1028931D01*
G03X972601Y1028789I141J-142D01*
G01Y1015498D01*
G02X972542Y1015356I-200J0D01*
G01X969421Y1012235D01*
G02X969279Y1012176I-142J141D01*
G01X924777D01*
G02X924635Y1012235I0J200D01*
G01X922931Y1013939D01*
X922902Y1013967D01*
X922872Y1014041D01*
Y1067037D01*
G02X922931Y1067179I200J0D01*
G01X925188Y1069436D01*
G02X925330Y1069495I142J-141D01*
G01X961377D01*
G03X961519Y1069554I0J200D01*
G01X979419Y1087454D01*
G02X979553Y1087513I142J-141D01*
G01X979671Y1087517D01*
G02X979802Y1087475I8J-200D01*
G03X980726Y1087157I924J1183D01*
G03X982228Y1088659I0J1502D01*
G03X981736Y1089771I-1503J0D01*
G01X981718Y1089787D01*
G03X980726Y1090161I-992J-1129D01*
G03X980683Y1090160I13J-1502D01*
G01X980643Y1090159D01*
X980567Y1090189D01*
X980333Y1090417D01*
G02X980272Y1090560I139J144D01*
G01Y1090762D01*
G02X980332Y1090905I200J0D01*
G01X980567Y1091134D01*
X980643Y1091164D01*
X980683Y1091163D01*
G03X980726Y1091162I56J1501D01*
G03X982228Y1092664I0J1502D01*
G03X982191Y1092995I-1502J0D01*
G01X982181Y1093040D01*
X982201Y1093128D01*
X982425Y1093408D01*
G02X982581Y1093484I157J-124D01*
G01X987620D01*
G03X989251Y1094159I1J2306D01*
G01X991144Y1096052D01*
G03X991820Y1097683I-1631J1632D01*
G03X989513Y1099990I-2307J0D01*
G03X987882Y1099314I1J-2307D01*
G01X986723Y1098155D01*
G02X986582Y1098096I-142J141D01*
G01X982748D01*
G02X982602Y1098161I2J200D01*
G01X982373Y1098407D01*
X982346Y1098485D01*
X982350Y1098527D01*
G03X982354Y1098643I-1498J110D01*
G03X981712Y1099875I-1503J0D01*
G01X981668Y1099906D01*
X981623Y1100000D01*
X981655Y1100449D01*
X981713Y1100536D01*
X981761Y1100560D01*
G03X982589Y1101902I-674J1342D01*
G03X982576Y1102102I-1502J3D01*
G01X982577D01*
G03X981960Y1103125I-1489J-201D01*
G02X981878Y1103262I117J163D01*
G01X981835Y1103592D01*
X981858Y1103671D01*
X981885Y1103704D01*
G03X982228Y1104659I-1158J955D01*
G01Y1104674D01*
X982227Y1104699D01*
G03X980726Y1106161I-1501J-40D01*
G03X980683Y1106160I13J-1502D01*
G01X980643Y1106159D01*
X980567Y1106189D01*
X980456Y1106297D01*
G02X980396Y1106440I140J143D01*
G01Y1110970D01*
G02X980519Y1111155I200J0D01*
G01X980576Y1111178D01*
X980693Y1111155D01*
X985014Y1106834D01*
G03X986645Y1106158I1632J1631D01*
G03X988952Y1108465I0J2307D01*
G03X988276Y1110096I-2307J-1D01*
G01X982264Y1116108D01*
G02X982206Y1116249I142J141D01*
G01Y1144498D01*
G02X982406Y1144698I200J0D01*
G37*
G36*
G01X924392Y1265523D02*
X958313D01*
G02X958455Y1265464I0J-200D01*
G01X959470Y1264449D01*
G02X959514Y1264384I-140J-142D01*
G01X972132Y1233918D01*
G02X972148Y1233841I-184J-78D01*
G01Y1218233D01*
G02X972046Y1218059I-200J0D01*
G01X971694Y1217861D01*
X971587Y1217863D01*
X971540Y1217891D01*
G03X970761Y1218109I-779J-1283D01*
G03Y1215105I0J-1502D01*
G03X971540Y1215323I0J1501D01*
G01X971587Y1215351D01*
X971694Y1215353D01*
X972046Y1215155D01*
G02X972148Y1214981I-98J-174D01*
G01Y1209471D01*
G03X972823Y1207840I2306J-1D01*
G01X975724Y1204939D01*
G02X975782Y1204798I-142J-141D01*
G01Y1097941D01*
G03X976458Y1096310I2307J1D01*
G01X977445Y1095323D01*
G02Y1095041I-142J-141D01*
G01X972571Y1090167D01*
X972519Y1090139D01*
X972489Y1090133D01*
G03X971410Y1089284I287J-1474D01*
G01X971385Y1089230D01*
X971288Y1089167D01*
X961075D01*
G02X960933Y1089226I0J200D01*
G01X960274Y1089885D01*
G02X960215Y1090027I141J142D01*
G01Y1096394D01*
G02X960274Y1096536I200J0D01*
G01X963423Y1099685D01*
G03X963482Y1099827I-141J142D01*
G01Y1131705D01*
G02X963541Y1131847I200J0D01*
G01X964667Y1132973D01*
G03X964726Y1133115I-141J142D01*
G01Y1142904D01*
G03X964667Y1143046I-200J0D01*
G01X963373Y1144340D01*
X963352Y1144464D01*
X963380Y1144522D01*
G03X963526Y1145169I-1356J646D01*
G03X962024Y1146671I-1502J0D01*
G03X961037Y1146301I0J-1501D01*
G01X961009Y1146277D01*
X960942Y1146252D01*
X960606D01*
X960539Y1146277D01*
X960511Y1146301D01*
G03X959524Y1146671I-987J-1131D01*
G03X958090Y1145616I0J-1502D01*
G01X958070Y1145553D01*
X957965Y1145476D01*
X928099D01*
G02X927957Y1145535I0J200D01*
G01X926500Y1146992D01*
X926475Y1147108D01*
X926497Y1147164D01*
G03X926599Y1147708I-1400J544D01*
G03X925097Y1149210I-1502J0D01*
G03X924553Y1149108I0J-1502D01*
G01X924497Y1149086D01*
X924381Y1149111D01*
X923947Y1149545D01*
G02X923888Y1149687I141J142D01*
G01Y1239461D01*
G03X923789Y1239955I-1292J-2D01*
G01X923146Y1241506D01*
G02X923131Y1241583I185J76D01*
G01Y1264262D01*
G02X923190Y1264404I200J0D01*
G01X924250Y1265464D01*
G02X924392Y1265523I142J-141D01*
G37*
G36*
G01X934053Y635219D02*
X945959D01*
G02X946101Y635160I0J-200D01*
G01X946323Y634938D01*
G02X946382Y634796I-141J-142D01*
G01Y633405D01*
G02X946323Y633263I-200J0D01*
G01X946191Y633131D01*
G03X946132Y632989I141J-142D01*
G01Y612318D01*
G02X946002Y612131I-200J0D01*
G01X945592Y611978D01*
X945471Y612008D01*
X945430Y612056D01*
G03X944296Y612573I-1134J-985D01*
G03Y609569I0J-1502D01*
G03X945430Y610086I0J1502D01*
G01X945471Y610134D01*
X945592Y610164D01*
X946002Y610011D01*
G02X946132Y609824I-70J-187D01*
G01Y592710D01*
X946068Y592611D01*
X946013Y592587D01*
G03X945519Y592232I612J-1372D01*
G02X945372Y592167I-148J135D01*
G01X945078D01*
G02X944931Y592232I1J200D01*
G03X943825Y592717I-1105J-1017D01*
G03Y589713I0J-1502D01*
G03X944931Y590198I1J1502D01*
G02X945078Y590263I148J-135D01*
G01X945372D01*
G02X945519Y590198I-1J-200D01*
G03X946013Y589843I1106J1017D01*
G01X946068Y589819D01*
X946132Y589720D01*
Y582717D01*
X946068Y582618D01*
X946013Y582594D01*
G03X945519Y582239I612J-1372D01*
G02X945372Y582174I-148J135D01*
G01X945078D01*
G02X944931Y582239I1J200D01*
G03X943825Y582724I-1105J-1017D01*
G03Y579720I0J-1502D01*
G03X944931Y580205I1J1502D01*
G02X945078Y580270I148J-135D01*
G01X945372D01*
G02X945519Y580205I-1J-200D01*
G03X946013Y579850I1106J1017D01*
G01X946068Y579826D01*
X946132Y579727D01*
Y525273D01*
G02X946073Y525131I-200J0D01*
G01X941898Y520956D01*
G02X941756Y520897I-142J141D01*
G01X941498D01*
G02X941298Y521097I0J200D01*
G01Y526958D01*
X941310Y527005D01*
X941321Y527027D01*
G03X941494Y527726I-1329J700D01*
G03X940614Y529093I-1502J0D01*
G01X940562Y529117D01*
X940499Y529209D01*
X940476Y529678D01*
X940530Y529775D01*
X940579Y529804D01*
G03X941329Y531104I-752J1300D01*
G03X938325I-1502J0D01*
G03X939205Y529737I1502J0D01*
G01X939257Y529713D01*
X939320Y529621D01*
X939343Y529152D01*
X939289Y529055D01*
X939240Y529026D01*
G03X938490Y527726I752J-1300D01*
G03X938663Y527027I1502J1D01*
G01X938674Y527005D01*
X938686Y526958D01*
Y521097D01*
G02X938486Y520897I-200J0D01*
G01X934768D01*
G02X934626Y520956I0J200D01*
G01X932741Y522841D01*
G02X932682Y522983I141J142D01*
G01Y556491D01*
G02X932735Y556626I200J-1D01*
G03X933129Y557641I-1108J1014D01*
G03X932735Y558656I-1502J1D01*
G02X932682Y558791I147J136D01*
G01Y560428D01*
G02X932735Y560563I200J-1D01*
G03X933129Y561578I-1108J1014D01*
G03X932735Y562593I-1502J1D01*
G02X932682Y562728I147J136D01*
G01Y564428D01*
G02X932735Y564563I200J-1D01*
G03X933129Y565578I-1108J1014D01*
G03X932735Y566593I-1502J1D01*
G02X932682Y566728I147J136D01*
G01Y568428D01*
G02X932735Y568563I200J-1D01*
G03X933129Y569578I-1108J1014D01*
G03X932735Y570593I-1502J1D01*
G02X932682Y570728I147J136D01*
G01Y572428D01*
G02X932735Y572563I200J-1D01*
G03X933129Y573578I-1108J1014D01*
G03X932735Y574593I-1502J1D01*
G02X932682Y574728I147J136D01*
G01Y576428D01*
G02X932735Y576563I200J-1D01*
G03X933129Y577578I-1108J1014D01*
G03X932735Y578593I-1502J1D01*
G02X932682Y578728I147J136D01*
G01Y580428D01*
G02X932735Y580563I200J-1D01*
G03X933129Y581578I-1108J1014D01*
G03X932735Y582593I-1502J1D01*
G02X932682Y582728I147J136D01*
G01Y583275D01*
G02X932734Y583409I200J0D01*
G03X933053Y583966I-1114J1008D01*
G02X933140Y584078I191J-59D01*
G01X933245Y584141D01*
G02X933386Y584166I103J-172D01*
G03X933725Y584134I338J1770D01*
G03X935528Y585936I0J1803D01*
G01Y589336D01*
G03X933725Y591138I-1802J0D01*
G03X933298Y591087I-1J-1802D01*
G02X933161Y591103I-47J195D01*
G01X933054Y591157D01*
G02X932960Y591258I90J178D01*
G03X932729Y591634I-1381J-590D01*
G01X932706Y591662D01*
X932682Y591727D01*
Y592100D01*
G02X932737Y592237I200J-1D01*
G03X933051Y592737I-1090J1033D01*
G02X933141Y592841I187J-71D01*
G01X933246Y592899D01*
G02X933383Y592920I97J-175D01*
G03X933741Y592884I358J1767D01*
G03X935544Y594687I0J1803D01*
G01Y598087D01*
G03X933741Y599890I-1803J0D01*
G03X933314Y599838I3J-1803D01*
G02X933177Y599854I-47J195D01*
G01X933070Y599908D01*
G02X932976Y600009I90J178D01*
G03X932731Y600402I-1382J-589D01*
G02X932682Y600533I151J131D01*
G01Y633848D01*
G02X932741Y633990I200J0D01*
G01X933911Y635160D01*
G02X934053Y635219I142J-141D01*
G37*
G36*
G01X957628Y828793D02*
X958558D01*
G02X958700Y828734I0J-200D01*
G01X960810Y826624D01*
G02X960868Y826483I-142J-141D01*
G01Y825762D01*
G03X961544Y824131I2307J1D01*
G01X964543Y821133D01*
G02X964581Y820904I-142J-141D01*
G01X964388Y820506D01*
X964277Y820445D01*
X964213Y820453D01*
G03X964036Y820463I-173J-1492D01*
G03X965538Y818961I0J-1502D01*
G03X965197Y819913I-1502J-1D01*
G01X965148Y819973D01*
X965156Y820127D01*
X965211Y820182D01*
G02X965493I141J-142D01*
G01X965933Y819742D01*
G02X965992Y819600I-141J-142D01*
G01Y796952D01*
G03X966051Y796810I200J0D01*
G01X975433Y787428D01*
X975454Y787300D01*
X975424Y787242D01*
G03X975262Y786563I1340J-679D01*
G03X976764Y785061I1502J0D01*
G01X976796D01*
X976837Y785062D01*
X976910Y785033D01*
X977144Y784804D01*
G02X977204Y784661I-140J-143D01*
G01Y764646D01*
G03X977263Y764504I200J0D01*
G01X977848Y763919D01*
G02X977906Y763778I-142J-141D01*
G01Y761306D01*
G03X978289Y760382I1306J0D01*
G01X983003Y755668D01*
G02X983062Y755526I-141J-142D01*
G01Y749331D01*
G02X983032Y749226I-200J0D01*
G03Y747638I1275J-794D01*
G02X983062Y747533I-170J-105D01*
G01Y746911D01*
G02X982970Y746743I-200J0D01*
G01X982645Y746533D01*
X982543Y746526D01*
X982497Y746547D01*
G03X981876Y746681I-620J-1368D01*
G03Y743677I0J-1502D01*
G03X982497Y743811I1J1502D01*
G01X982543Y743832D01*
X982645Y743825D01*
X982970Y743615D01*
G02X983062Y743447I-108J-168D01*
G01Y723539D01*
G02X982962Y723365I-200J-1D01*
G03Y720763I749J-1301D01*
G02X983062Y720589I-100J-173D01*
G01Y665220D01*
G02X983003Y665078I-200J0D01*
G01X974250Y656325D01*
G02X974108Y656266I-142J141D01*
G01X943942D01*
G02X943800Y656325I0J200D01*
G01X942487Y657638D01*
G02X942428Y657780I141J142D01*
G01Y667344D01*
G02X942487Y667486I200J0D01*
G01X944372Y669371D01*
G02X944514Y669430I142J-141D01*
G01X949836D01*
G02X949978Y669371I0J-200D01*
G01X953059Y666290D01*
X953084Y666248D01*
X953092Y666225D01*
G03X954526Y665169I1434J446D01*
G03X956028Y666671I0J1502D01*
G03X954972Y668105I-1502J0D01*
G01X954949Y668113D01*
X954907Y668138D01*
X953956Y669089D01*
G02X953913Y669307I141J141D01*
G01X953936Y669363D01*
X954036Y669430D01*
X958943D01*
G03X959085Y669489I0J200D01*
G01X965287Y675691D01*
G03X965346Y675833I-141J142D01*
G01Y705005D01*
G02X965406Y705148I200J0D01*
G01X965638Y705376D01*
X965711Y705406D01*
X965752Y705405D01*
X965774D01*
G03Y708409I0J1502D01*
G01X965752D01*
X965711Y708408D01*
X965638Y708438D01*
X965406Y708666D01*
G02X965346Y708809I140J143D01*
G01Y720675D01*
X965423Y720780D01*
X965487Y720799D01*
G03Y723669I-446J1435D01*
G01X965423Y723688D01*
X965346Y723793D01*
Y724784D01*
X965349Y724801D01*
G03X965371Y725057I-1480J256D01*
G03X965349Y725313I-1502J0D01*
G01X965346Y725330D01*
Y729415D01*
G02X965405Y729557I200J0D01*
G01X966907Y731059D01*
G03X967290Y731983I-923J924D01*
G01Y762799D01*
X967301Y762846D01*
X967312Y762868D01*
G03X967485Y763567I-1329J700D01*
G03X965983Y765069I-1502J0D01*
G03X965796Y765057I2J-1502D01*
G01X965753Y765052D01*
X965671Y765077D01*
X965414Y765304D01*
G02X965346Y765454I132J150D01*
G01Y773939D01*
G03X965287Y774081I-200J0D01*
G01X958995Y780373D01*
X958966Y780468D01*
X958975Y780517D01*
G03X959002Y780800I-1475J284D01*
G03X957500Y782302I-1502J0D01*
G03X957217Y782275I1J-1502D01*
G01X957168Y782266D01*
X957073Y782295D01*
X956136Y783232D01*
G02X956078Y783373I142J141D01*
G01Y783696D01*
X956108Y783769D01*
X956137Y783798D01*
G03X956578Y784861I-1061J1063D01*
G03X955076Y786363I-1502J0D01*
G03X954013Y785922I0J-1502D01*
G01X953984Y785893D01*
X953911Y785863D01*
X953588D01*
G02X953447Y785921I0J200D01*
G01X951534Y787834D01*
G02X951475Y787976I141J142D01*
G01Y788194D01*
X951505Y788268D01*
X951534Y788296D01*
G03Y790426I-1059J1065D01*
G02X951475Y790568I141J142D01*
G01Y806221D01*
G02X951530Y806359I200J0D01*
G01X951749Y806587D01*
X951818Y806619D01*
X951857Y806620D01*
G03Y809622I-66J1501D01*
G01X951818Y809623D01*
X951749Y809655D01*
X951530Y809883D01*
G02X951475Y810021I145J138D01*
G01Y810611D01*
X951574Y810723D01*
X951650Y810733D01*
G03Y813713I-189J1490D01*
G01X951574Y813723D01*
X951475Y813835D01*
Y816999D01*
G02X951528Y817134I200J-1D01*
G01X951735Y817361D01*
X951802Y817394D01*
X951840Y817398D01*
G03X953210Y818894I-132J1496D01*
G03X952120Y820338I-1501J0D01*
G01X952054Y820357D01*
X951974Y820463D01*
Y828161D01*
G02X952033Y828302I200J-1D01*
G01X952465Y828734D01*
G02X952607Y828793I142J-141D01*
G01X954850D01*
G02X955013Y828709I0J-200D01*
G03X957465I1226J868D01*
G02X957628Y828793I163J-116D01*
G37*
G36*
G01X946590Y809474D02*
X946638D01*
G02X946780Y809415I0J-200D01*
G01X947955Y808240D01*
G02X948014Y808098I-141J-142D01*
G01Y788902D01*
G02X947955Y788760I-200J0D01*
G01X947414Y788219D01*
G02X947272Y788160I-142J141D01*
G01X944434D01*
G02X944268Y788249I0J200D01*
G01X944055Y788567D01*
X944045Y788666D01*
X944064Y788713D01*
G03X944178Y789286I-1388J574D01*
G03X941174I-1502J0D01*
G03X941288Y788713I1502J1D01*
G01X941307Y788666D01*
X941297Y788567D01*
X941084Y788249D01*
G02X940918Y788160I-166J111D01*
G01X935407D01*
G02X935265Y788219I0J200D01*
G01X934459Y789025D01*
G02X934400Y789167I141J142D01*
G01Y797328D01*
G02X934436Y797442I200J0D01*
G03Y799152I-1235J855D01*
G02X934400Y799266I164J114D01*
G01Y807158D01*
G02X934459Y807299I200J-1D01*
G01X936176Y809017D01*
G02X936388Y809063I142J-141D01*
G01X936784Y808913D01*
X936854Y808819D01*
X936858Y808760D01*
G03X938357Y807354I1499J96D01*
G03X939859Y808856I0J1502D01*
G03X939849Y809028I-1502J-1D01*
G01X939844Y809072D01*
X939869Y809152D01*
X940097Y809407D01*
G02X940246Y809474I149J-133D01*
G01X943017D01*
G02X943163Y809411I0J-200D01*
G01X943391Y809169D01*
X943419Y809093D01*
X943416Y809051D01*
G03X943414Y808965I1500J-78D01*
G03X946418I1502J0D01*
G03X946393Y809238I-1503J0D01*
G01X946390Y809256D01*
Y809274D01*
G02X946590Y809474I200J0D01*
G37*
G36*
G01X968557Y1079153D02*
X968208Y1078804D01*
G02X968066Y1078745I-142J141D01*
G01X964225D01*
X964151Y1078775D01*
X964123Y1078804D01*
X952323Y1090604D01*
G03X952181Y1090663I-142J-141D01*
G01X949739D01*
X949665Y1090693D01*
X949637Y1090722D01*
X945496Y1094863D01*
G03X945354Y1094922I-142J-141D01*
G01X932367D01*
X932293Y1094952D01*
X932265Y1094981D01*
X930594Y1096652D01*
G02X930535Y1096794I141J142D01*
G01Y1105853D01*
G03X930506Y1105957I-200J0D01*
G01X930505Y1105958D01*
X930491Y1105982D01*
X930484Y1106007D01*
G02X930476Y1106062I192J56D01*
G01Y1137956D01*
G02X930535Y1138098I200J0D01*
G01X935404Y1142967D01*
G02X935546Y1143026I142J-141D01*
G01X961921D01*
G02X962063Y1142967I0J-200D01*
G01X963423Y1141607D01*
G02X963482Y1141465I-141J-142D01*
G01Y1134904D01*
G02X963423Y1134762I-200J0D01*
G01X962066Y1133405D01*
G03X962007Y1133263I141J-142D01*
G01Y1101069D01*
G02X961948Y1100927I-200J0D01*
G01X960500Y1099480D01*
G02X960455Y1099446I-142J141D01*
G01X960433Y1099434D01*
X960406Y1099427D01*
X960405D01*
G03X960311Y1099374I48J-194D01*
G01X958797Y1097860D01*
G03X958738Y1097718I141J-142D01*
G01Y1089638D01*
G03X958797Y1089496I200J0D01*
G01X960079Y1088214D01*
G03X960221Y1088155I142J141D01*
G01X968106D01*
X968180Y1088125D01*
X968208Y1088096D01*
X968557Y1087747D01*
G02X968616Y1087605I-141J-142D01*
G01Y1079255D01*
X968586Y1079181D01*
X968557Y1079153D01*
G37*
G36*
G01X933851Y1308273D02*
G03I-597J0D01*
G37*
G36*
G01X933960Y1441688D02*
X1047083D01*
G02X1047225Y1441629I0J-200D01*
G01X1048580Y1440274D01*
G02X1048639Y1440132I-141J-142D01*
G01Y1425825D01*
G02X1048582Y1425686I-200J1D01*
G01X1047405Y1424477D01*
G02X1047403Y1424475I-142J140D01*
G01X1028084Y1405156D01*
G02X1027942Y1405097I-142J141D01*
G01X994541D01*
G02X994399Y1405156I0J200D01*
G01X983173Y1416382D01*
G03X983031Y1416441I-142J-141D01*
G01X971645D01*
G02X971503Y1416500I0J200D01*
G01X971488Y1416515D01*
X971415Y1416545D01*
X937669D01*
G02X937527Y1416604I0J200D01*
G01X932557Y1421574D01*
G02X932498Y1421716I141J142D01*
G01Y1440226D01*
G02X932557Y1440368I200J0D01*
G01X933818Y1441629D01*
G02X933960Y1441688I142J-141D01*
G37*
G36*
G01X954038Y1480156D02*
Y1451122D01*
G02X953979Y1450980I-200J0D01*
G01X953597Y1450598D01*
G02X953455Y1450539I-142J141D01*
G01X933021D01*
G02X932879Y1450598I0J200D01*
G01X930606D01*
G02X930464Y1450657I0J200D01*
G01X929532Y1451589D01*
G02X929473Y1451731I141J142D01*
G01Y1480759D01*
G02X929532Y1480901I200J0D01*
G01X930711Y1482080D01*
G02X930853Y1482139I142J-141D01*
G01X952055D01*
G02X952197Y1482080I0J-200D01*
G01X953979Y1480298D01*
G02X954038Y1480156I-141J-142D01*
G37*
G36*
G01X958794Y1450939D02*
X955821D01*
G02X955679Y1450998I0J200D01*
G01X955197Y1451480D01*
G02X955138Y1451622I141J142D01*
G01Y1485156D01*
G02X955197Y1485298I200J0D01*
G01X957028Y1487129D01*
G02X957170Y1487188I142J-141D01*
G01X1039023D01*
G02X1039221Y1487013I0J-200D01*
G03X1049670Y1467295I31231J3923D01*
G02X1049738Y1467144I-132J-150D01*
G01Y1452449D01*
G02X1049679Y1452307I-200J0D01*
G01X1048392Y1451020D01*
G02X1048250Y1450961I-142J141D01*
G01X958816D01*
X958794Y1450939D01*
G37*
G36*
G01X964962Y1566784D02*
X993823D01*
G02X993965Y1566725I0J-200D01*
G01X995797Y1564893D01*
G02X995856Y1564751I-141J-142D01*
G01Y1547091D01*
G02X995797Y1546949I-200J0D01*
G01X993903Y1545055D01*
G02X993761Y1544996I-142J141D01*
G01X965293D01*
G02X965151Y1545055I0J200D01*
G01X963569Y1546637D01*
G02X963510Y1546779I141J142D01*
G01Y1565332D01*
G02X963569Y1565474I200J0D01*
G01X964820Y1566725D01*
G02X964962Y1566784I142J-141D01*
G37*
G36*
G01X1051831Y54588D02*
X1080886D01*
X1081101Y54373D01*
Y52806D01*
X1080886Y52591D01*
X1051831D01*
G03X1045894Y46654I0J-5937D01*
G01Y7874D01*
G02X1040020Y2000I-5874J0D01*
G01X992776D01*
G02X986902Y7874I0J5874D01*
G01Y46654D01*
G03Y46659I-5936J2D01*
G01X988900D01*
G02Y46654I-7934J-2D01*
G01Y7874D01*
G03X992776Y3998I3876J0D01*
G01X1040020D01*
G03X1043896Y7874I0J3876D01*
G01Y46654D01*
G02X1051831Y54588I7935J-1D01*
G37*
G36*
G01X1009550Y1398727D02*
X1030131D01*
G02X1030273Y1398668I0J-200D01*
G01X1031581Y1397360D01*
G02X1031640Y1397218I-141J-142D01*
G01Y1387255D01*
G02X1031625Y1387180I-200J1D01*
G01X1030594Y1384655D01*
G02X1030408Y1384531I-185J76D01*
G01X1008923D01*
G02X1008781Y1384590I0J200D01*
G01X1008174Y1385197D01*
G02X1008115Y1385339I141J142D01*
G01Y1397292D01*
G02X1008174Y1397434I200J0D01*
G01X1009408Y1398668D01*
G02X1009550Y1398727I142J-141D01*
G37*
G36*
G01X1145295Y1087619D02*
X1145275D01*
G03X1144073Y1086417I0J-1202D01*
G03X1145209Y1085217I1202J0D01*
G01X1145211D01*
X1145249Y1085215D01*
X1145317Y1085183D01*
X1145533Y1084955D01*
G02X1145588Y1084817I-145J-138D01*
G01Y1084277D01*
G02X1145533Y1084139I-200J0D01*
G01X1145343Y1083939D01*
G02X1145211Y1083877I-145J138D01*
G01X1145210D01*
G03X1145209Y1081477I65J-1200D01*
G01X1145211D01*
X1145249Y1081475D01*
X1145317Y1081443D01*
X1145533Y1081215D01*
G02X1145588Y1081077I-145J-138D01*
G01Y1080793D01*
G02X1145500Y1080628I-200J1D01*
G01X1145499Y1080627D01*
G03X1145002Y1080235I2113J-3190D01*
G02X1144920Y1080189I-136J147D01*
G03X1144022Y1079291I355J-1253D01*
G02X1143976Y1079209I-193J54D01*
G03X1142944Y1076596I2794J-2614D01*
G01Y1076440D01*
G02X1142830Y1076260I-200J1D01*
G01X1142451Y1076079D01*
X1142337Y1076093D01*
X1142292Y1076130D01*
G03X1141535Y1076398I-757J-935D01*
G03Y1073994I0J-1202D01*
G03X1142292Y1074262I0J1203D01*
G01X1142337Y1074299D01*
X1142451Y1074313D01*
X1142830Y1074132D01*
G02X1142944Y1073952I-86J-181D01*
G01Y1070493D01*
G02X1142930Y1070421I-200J1D01*
G03X1142664Y1068999I3660J-1420D01*
G01Y1063972D01*
G02X1142657Y1063919I-200J-1D01*
G01X1108990Y943516D01*
G02X1108939Y943429I-192J54D01*
G01X1108068Y942558D01*
G02X1108018Y942522I-140J142D01*
G02X1107927Y942500I-91J178D01*
G01X1095131D01*
G02X1094989Y942559I0J200D01*
G01X1092129Y945418D01*
G02X1092070Y945560I141J142D01*
G01Y1050956D01*
G03X1092009Y1051350I-1306J0D01*
G01X1092000Y1051380D01*
Y1051708D01*
G03X1091941Y1051850I-200J0D01*
G01X1075483Y1068308D01*
G02X1075425Y1068451I142J141D01*
G01X1075443Y1068761D01*
G02X1075465Y1068842I200J-11D01*
G01X1075484Y1068878D01*
X1075503Y1068893D01*
G03X1076052Y1070006I-854J1113D01*
G03X1074650Y1071408I-1402J0D01*
G03X1073537Y1070859I0J-1403D01*
G01X1073522Y1070840D01*
X1073486Y1070821D01*
G02X1073405Y1070799I-92J178D01*
G01X1073095Y1070781D01*
G02X1072952Y1070839I-2J200D01*
G01X1072684Y1071107D01*
G03X1072542Y1071166I-142J-141D01*
G01X1066547D01*
G03X1066405Y1071107I0J-200D01*
G01X1065888Y1070590D01*
G02X1065877Y1070580I-140J143D01*
G01X1065872Y1070576D01*
G02X1065799Y1070539I-125J156D01*
G02X1065747Y1070532I-52J193D01*
G01X1063598D01*
G02X1063456Y1070591I0J200D01*
G01X1037417Y1096630D01*
G03X1036495Y1097012I-923J-924D01*
G01X1036263D01*
G02X1036241Y1097031I120J161D01*
G01X1035445Y1097827D01*
G03X1035303Y1097886I-142J-141D01*
G01X1020738D01*
G02X1020597Y1097945I1J200D01*
G01X1015475Y1103067D01*
G02X1015416Y1103209I141J142D01*
G01Y1108370D01*
G02X1015550Y1108559I200J0D01*
G01X1015906Y1108684D01*
G02X1016128Y1108621I66J-189D01*
G03X1017297Y1108062I1169J943D01*
G03Y1111066I0J1502D01*
G03X1016128Y1110507I0J-1502D01*
G02X1015906Y1110444I-156J126D01*
G01X1015550Y1110569D01*
G02X1015416Y1110758I66J189D01*
G01Y1114222D01*
G02X1015616Y1114422I200J0D01*
G01X1015661D01*
G02X1015783Y1114381I1J-200D01*
G01X1015808Y1114362D01*
X1015843Y1114310D01*
X1015853Y1114277D01*
G03X1018741I1444J414D01*
G01X1018742Y1114279D01*
G02X1018812Y1114382I192J-55D01*
G01X1018838Y1114401D01*
X1018899Y1114422D01*
X1021470D01*
G02X1021592Y1114381I1J-200D01*
G01X1021617Y1114362D01*
X1021652Y1114310D01*
X1021662Y1114277D01*
G03X1024550I1444J414D01*
G01Y1114279D01*
G02X1024622Y1114383I192J-56D01*
G01X1024648Y1114403D01*
X1024709Y1114423D01*
X1025980D01*
G03X1026122Y1114482I0J200D01*
G01X1026896Y1115256D01*
G03X1026955Y1115398I-141J142D01*
G01Y1125681D01*
G02X1026993Y1125797I200J-1D01*
G01X1027010Y1125822D01*
X1027059Y1125858D01*
X1027090Y1125869D01*
G03Y1128713I-484J1422D01*
G01X1027089D01*
G02X1026992Y1128786I66J189D01*
G01X1026974Y1128811D01*
X1026955Y1128869D01*
Y1138281D01*
G02X1026993Y1138397I200J-1D01*
G01X1027010Y1138422D01*
X1027059Y1138458D01*
X1027090Y1138469D01*
G03Y1141313I-484J1422D01*
G01X1027089D01*
G02X1026992Y1141386I66J189D01*
G01X1026974Y1141411D01*
X1026955Y1141469D01*
Y1150881D01*
G02X1026993Y1150997I200J-1D01*
G01X1027010Y1151022D01*
X1027059Y1151058D01*
X1027090Y1151069D01*
G03Y1153913I-484J1422D01*
G01X1027089D01*
G02X1026992Y1153986I66J189D01*
G01X1026974Y1154011D01*
X1026955Y1154069D01*
Y1163481D01*
G02X1026993Y1163597I200J-1D01*
G01X1027010Y1163622D01*
X1027059Y1163658D01*
X1027090Y1163669D01*
G03Y1166513I-484J1422D01*
G01X1027089D01*
G02X1026992Y1166586I66J189D01*
G01X1026974Y1166611D01*
X1026955Y1166669D01*
Y1176081D01*
G02X1026993Y1176197I200J-1D01*
G01X1027010Y1176222D01*
X1027059Y1176258D01*
X1027090Y1176269D01*
G03Y1179113I-484J1422D01*
G01X1027089D01*
G02X1026992Y1179186I66J189D01*
G01X1026974Y1179211D01*
X1026955Y1179269D01*
Y1182955D01*
G03X1026896Y1183097I-200J0D01*
G01X1026598Y1183395D01*
G02X1026552Y1183604I142J141D01*
G01X1026555Y1183612D01*
G02X1026629Y1183703I185J-75D01*
G01X1026652Y1183719D01*
X1026709Y1183736D01*
X1029005D01*
G02X1029082Y1183721I1J-200D01*
G01X1034808Y1181348D01*
G03X1036306Y1181050I1500J3629D01*
G01X1037358D01*
G02X1037558Y1180850I0J-200D01*
G01Y1180840D01*
X1037557Y1180831D01*
G03X1037551Y1180695I1496J-134D01*
G01Y1180691D01*
G03X1038147Y1179493I1502J0D01*
G01X1038172Y1179474D01*
X1038185Y1179465D01*
X1038206Y1179424D01*
G02X1038227Y1179337I-179J-89D01*
G01X1038229Y1179187D01*
X1038231Y1179020D01*
G02X1038212Y1178932I-200J-3D01*
G01X1038203Y1178912D01*
X1038175Y1178877D01*
X1038157Y1178862D01*
G03X1037596Y1177691I942J-1171D01*
G03X1040600I1502J0D01*
G03X1040004Y1178889I-1502J0D01*
G01X1039979Y1178908D01*
X1039966Y1178917D01*
X1039945Y1178958D01*
G02X1039924Y1179045I179J89D01*
G01X1039922Y1179195D01*
X1039920Y1179362D01*
G02X1039939Y1179450I200J3D01*
G01X1039948Y1179470D01*
X1039976Y1179505D01*
X1039994Y1179520D01*
G03X1040547Y1180532I-941J1171D01*
G01X1040551Y1180575D01*
X1040572Y1180611D01*
G02X1040627Y1180672I173J-101D01*
G01X1040745Y1180759D01*
X1040747D01*
X1040870Y1180851D01*
G02X1041016Y1180883I113J-165D01*
G01X1042053Y1180677D01*
X1042934Y1180502D01*
G02X1043034Y1180450I-38J-196D01*
G01X1043077Y1180409D01*
X1043083Y1180381D01*
X1043090Y1180351D01*
G03X1044553Y1179189I1463J340D01*
G03X1044753Y1179202I3J1502D01*
G01Y1179201D01*
G03X1045089Y1179286I-198J1490D01*
G03X1045247Y1179357I-536J1404D01*
G03X1045776Y1179817I-695J1333D01*
G01X1045793Y1179841D01*
X1045838Y1179876D01*
X1045864Y1179886D01*
G02X1045977Y1179897I75J-185D01*
G01X1046838Y1179726D01*
G02X1046946Y1179664I-41J-196D01*
G01X1046947D01*
G03X1047896Y1179196I1096J1027D01*
G01X1047931Y1179193D01*
X1048034Y1179144D01*
G02X1048076Y1179114I-94J-176D01*
G01X1048145Y1179043D01*
G02X1048198Y1178908I-147J-136D01*
G01Y1098972D01*
G03X1048257Y1098830I200J0D01*
G01X1057041Y1090046D01*
G02X1057097Y1089873I-141J-141D01*
G01Y1089870D01*
X1057032Y1089539D01*
G02X1056992Y1089453I-196J39D01*
G01X1056978Y1089434D01*
X1056939Y1089405D01*
X1056914Y1089395D01*
G03X1056179Y1088287I468J-1108D01*
G03X1058583I1202J0D01*
G03X1058507Y1088708I-1204J0D01*
G01X1058502Y1088722D01*
X1058489Y1088794D01*
G02X1058518Y1088897I200J-1D01*
G01X1058618Y1089043D01*
X1058710Y1089178D01*
G02X1058875Y1089265I165J-113D01*
G01X1059627D01*
G02X1059792Y1089178I0J-200D01*
G01X1059884Y1089043D01*
X1059984Y1088897D01*
G02X1060013Y1088794I-171J-104D01*
G01X1060000Y1088722D01*
X1059995Y1088708D01*
G03X1059919Y1088287I1128J-421D01*
G03X1062323I1202J0D01*
G03X1062247Y1088708I-1204J0D01*
G01X1062242Y1088722D01*
X1062229Y1088794D01*
G02X1062258Y1088897I200J-1D01*
G01X1062358Y1089043D01*
X1062450Y1089178D01*
G02X1062615Y1089265I165J-113D01*
G01X1088141D01*
G02X1088278Y1089210I-1J-200D01*
G03X1090066I894J946D01*
G02X1090203Y1089265I138J-145D01*
G01X1091882D01*
G02X1092019Y1089210I-1J-200D01*
G03X1093807I894J946D01*
G02X1093944Y1089265I138J-145D01*
G01X1095622D01*
G02X1095759Y1089210I-1J-200D01*
G03X1097547I894J946D01*
G02X1097684Y1089265I138J-145D01*
G01X1099362D01*
G02X1099499Y1089210I-1J-200D01*
G03X1101287I894J946D01*
G02X1101424Y1089265I138J-145D01*
G01X1103102D01*
G02X1103239Y1089210I-1J-200D01*
G03X1105027I894J946D01*
G02X1105164Y1089265I138J-145D01*
G01X1106842D01*
G02X1106979Y1089210I-1J-200D01*
G03X1108767I894J946D01*
G02X1108904Y1089265I138J-145D01*
G01X1110582D01*
G02X1110719Y1089210I-1J-200D01*
G03X1112507I894J946D01*
G02X1112644Y1089265I138J-145D01*
G01X1114323D01*
G02X1114460Y1089210I-1J-200D01*
G03X1116248I894J946D01*
G02X1116385Y1089265I138J-145D01*
G01X1118063D01*
G02X1118200Y1089210I-1J-200D01*
G03X1119988I894J946D01*
G02X1120125Y1089265I138J-145D01*
G01X1121803D01*
G02X1121940Y1089210I-1J-200D01*
G03X1123728I894J946D01*
G02X1123865Y1089265I138J-145D01*
G01X1125543D01*
G02X1125680Y1089210I-1J-200D01*
G03X1127468I894J946D01*
G02X1127605Y1089265I138J-145D01*
G01X1129283D01*
G02X1129420Y1089210I-1J-200D01*
G03X1131208I894J946D01*
G02X1131345Y1089265I138J-145D01*
G01X1133023D01*
G02X1133160Y1089210I-1J-200D01*
G03X1134948I894J946D01*
G02X1135085Y1089265I138J-145D01*
G01X1136764D01*
G02X1136901Y1089210I-1J-200D01*
G03X1138689I894J946D01*
G02X1138826Y1089265I138J-145D01*
G01X1140504D01*
G02X1140641Y1089210I-1J-200D01*
G03X1142429I894J946D01*
G02X1142566Y1089265I138J-145D01*
G01X1144274D01*
G02X1144336Y1089255I0J-200D01*
G03X1144525Y1089092I941J900D01*
G01X1144539Y1089083D01*
X1145531Y1088091D01*
G02X1145585Y1087984I-143J-139D01*
G02X1145588Y1087951I-197J-35D01*
G01Y1087902D01*
G02X1145524Y1087755I-200J0D01*
G01X1145434Y1087672D01*
G02X1145295Y1087619I-136J147D01*
G37*
G36*
G01X1025264Y1116312D02*
G02X1025251Y1116297I-157J123D01*
G01X1024720Y1115766D01*
G02X1024580Y1115708I-141J142D01*
G01X1024438Y1115707D01*
X1024291Y1115706D01*
G02X1024158Y1115764I8J200D01*
G03X1023117Y1116193I-1051J-1073D01*
G01X1023108D01*
G03X1021850Y1115515I-2J-1502D01*
G02X1021687Y1115424I-168J109D01*
G01X1018721D01*
X1018720D01*
G02X1018605Y1115461I1J200D01*
G03X1015989I-1308J-769D01*
G02X1015874Y1115424I-116J163D01*
G01X1015616D01*
G02X1015416Y1115624I0J200D01*
G01Y1126097D01*
G02X1015550Y1126286I200J0D01*
G01X1015906Y1126411D01*
G02X1016128Y1126348I66J-189D01*
G03X1017297Y1125789I1169J943D01*
G03Y1128793I0J1502D01*
G03X1016128Y1128234I0J-1502D01*
G02X1015906Y1128171I-156J126D01*
G01X1015550Y1128296D01*
G02X1015416Y1128485I66J189D01*
G01Y1138697D01*
G02X1015550Y1138886I200J0D01*
G01X1015906Y1139011D01*
G02X1016128Y1138948I66J-189D01*
G03X1017297Y1138389I1169J943D01*
G03Y1141393I0J1502D01*
G03X1016128Y1140834I0J-1502D01*
G02X1015906Y1140771I-156J126D01*
G01X1015550Y1140896D01*
G02X1015416Y1141085I66J189D01*
G01Y1151297D01*
G02X1015550Y1151486I200J0D01*
G01X1015906Y1151611D01*
G02X1016128Y1151548I66J-189D01*
G03X1017297Y1150989I1169J943D01*
G03Y1153993I0J1502D01*
G03X1016128Y1153434I0J-1502D01*
G02X1015906Y1153371I-156J126D01*
G01X1015550Y1153496D01*
G02X1015416Y1153685I66J189D01*
G01Y1163897D01*
G02X1015550Y1164086I200J0D01*
G01X1015906Y1164211D01*
G02X1016128Y1164148I66J-189D01*
G03X1017297Y1163589I1169J943D01*
G03Y1166593I0J1502D01*
G03X1016128Y1166034I0J-1502D01*
G02X1015906Y1165971I-156J126D01*
G01X1015550Y1166096D01*
G02X1015416Y1166285I66J189D01*
G01Y1174807D01*
G03X1015317Y1175305I-1306J-1D01*
G01X1014961Y1176164D01*
G02X1014946Y1176241I185J76D01*
G01Y1185286D01*
G02X1014950Y1185324I200J-2D01*
G02X1015003Y1185426I196J-37D01*
G01X1015571Y1185994D01*
G02X1015713Y1186053I142J-141D01*
G01X1023412D01*
G02X1023489Y1186038I1J-200D01*
G01X1023768Y1185922D01*
G02X1023833Y1185879I-76J-185D01*
G01X1025191Y1184521D01*
G02X1025250Y1184379I-141J-142D01*
G01Y1183326D01*
G02X1025309Y1183185I-141J-142D01*
G01Y1178526D01*
G02X1025303Y1178477I-200J0D01*
G01X1025286Y1178409D01*
X1025275Y1178388D01*
G03X1025103Y1177691I1331J-698D01*
G03X1025275Y1176994I1503J1D01*
G01X1025286Y1176973D01*
X1025303Y1176905D01*
G02X1025309Y1176856I-194J-49D01*
G01Y1165926D01*
G02X1025303Y1165877I-200J0D01*
G01X1025286Y1165809D01*
X1025275Y1165788D01*
G03X1025103Y1165091I1331J-698D01*
G03X1025275Y1164394I1503J1D01*
G01X1025286Y1164373D01*
X1025303Y1164305D01*
G02X1025309Y1164256I-194J-49D01*
G01Y1153326D01*
G02X1025303Y1153277I-200J0D01*
G01X1025286Y1153209D01*
X1025275Y1153188D01*
G03X1025103Y1152491I1331J-698D01*
G03X1025275Y1151794I1503J1D01*
G01X1025286Y1151773D01*
X1025303Y1151705D01*
G02X1025309Y1151656I-194J-49D01*
G01Y1140726D01*
G02X1025303Y1140677I-200J0D01*
G01X1025286Y1140609D01*
X1025275Y1140588D01*
G03X1025103Y1139891I1331J-698D01*
G03X1025275Y1139194I1503J1D01*
G01X1025286Y1139173D01*
X1025303Y1139105D01*
G02X1025309Y1139056I-194J-49D01*
G01Y1128126D01*
G02X1025303Y1128077I-200J0D01*
G01X1025286Y1128009D01*
X1025275Y1127988D01*
G03X1025103Y1127291I1331J-698D01*
G03X1025275Y1126594I1503J1D01*
G01X1025286Y1126573D01*
X1025303Y1126505D01*
G02X1025309Y1126456I-194J-49D01*
G01Y1116438D01*
G02X1025264Y1116312I-200J0D01*
G37*
G36*
G01X1197069Y1095758D02*
X1197068Y1095763D01*
Y1095781D01*
G03X1197056Y1095944I-1302J-14D01*
G01Y1095946D01*
G03X1197051Y1095981I-1292J-167D01*
G01X1197043Y1096028D01*
X1197071Y1096118D01*
X1197325Y1096384D01*
G02X1197493Y1096444I144J-139D01*
G01X1197494D01*
G03X1197637Y1096435I147J1193D01*
G03Y1098839I0J1202D01*
G03X1196435Y1097638I0J-1202D01*
G01Y1097636D01*
G03X1196444Y1097496I1202J7D01*
G01Y1097495D01*
G02X1196384Y1097327I-199J-24D01*
G01X1196117Y1097073D01*
X1196027Y1097045D01*
X1195981Y1097053D01*
G03X1195767Y1097070I-210J-1285D01*
G01X1195765D01*
G03X1195526Y1097048I-1J-1302D01*
G01X1195523D01*
X1195505Y1097045D01*
X1195416Y1097072D01*
X1195116Y1097359D01*
X1195084Y1097447D01*
X1195090Y1097494D01*
G03X1195098Y1097637I-1194J139D01*
G03X1193896Y1096435I-1202J0D01*
G03X1194038Y1096444I-5J1202D01*
G01X1194041D01*
G02X1194207Y1096384I22J-199D01*
G01X1194461Y1096118D01*
X1194489Y1096028D01*
X1194481Y1095982D01*
G03X1194464Y1095769I1285J-210D01*
G01Y1095490D01*
G02X1194398Y1095341I-200J0D01*
G01X1194177Y1095142D01*
G02X1194023Y1095092I-134J149D01*
G01X1194022D01*
G03X1193896Y1095099I-130J-1195D01*
G03X1192694Y1093897I0J-1202D01*
G03X1192715Y1093677I1202J4D01*
G01Y1093675D01*
G02X1192660Y1093498I-197J-36D01*
G01X1192392Y1093229D01*
X1192297Y1093200D01*
X1192248Y1093209D01*
G03X1192018Y1093229I-219J-1182D01*
G03X1191935Y1093225I16J-1202D01*
G01X1191933D01*
G03X1191805Y1093209I85J-1199D01*
G01X1191757Y1093200D01*
X1191662Y1093229D01*
X1191393Y1093498D01*
G02X1191338Y1093675I142J141D01*
G01Y1093677D01*
G03X1191359Y1093897I-1181J224D01*
G03X1190157Y1095099I-1202J0D01*
G03X1190033Y1095092I6J-1202D01*
G01X1190031D01*
G02X1189877Y1095142I-20J199D01*
G01X1189656Y1095341D01*
G02X1189590Y1095490I134J149D01*
G01Y1095731D01*
G03X1189589Y1095758I-1303J-35D01*
G01X1189588Y1095763D01*
Y1095781D01*
G03X1189576Y1095944I-1302J-14D01*
G01Y1095946D01*
G03X1189571Y1095981I-1292J-167D01*
G01X1189563Y1096028D01*
X1189591Y1096118D01*
X1189845Y1096384D01*
G02X1190013Y1096444I144J-139D01*
G01X1190014D01*
G03X1190157Y1096435I147J1193D01*
G03Y1098839I0J1202D01*
G03X1188955Y1097638I0J-1202D01*
G01Y1097636D01*
G03X1188964Y1097496I1202J7D01*
G01Y1097495D01*
G02X1188904Y1097327I-199J-24D01*
G01X1188637Y1097073D01*
X1188547Y1097045D01*
X1188501Y1097053D01*
G03X1188287Y1097070I-210J-1285D01*
G01X1188285D01*
G03X1188046Y1097048I-1J-1302D01*
G01X1188043D01*
X1188025Y1097045D01*
X1187936Y1097072D01*
X1187636Y1097359D01*
X1187604Y1097447D01*
X1187610Y1097494D01*
G03X1187618Y1097637I-1194J139D01*
G03X1186416Y1096435I-1202J0D01*
G03X1186558Y1096444I-5J1202D01*
G01X1186561D01*
G02X1186727Y1096384I22J-199D01*
G01X1186981Y1096118D01*
X1187009Y1096028D01*
X1187001Y1095982D01*
G03X1186984Y1095769I1285J-210D01*
G01Y1095490D01*
G02X1186918Y1095341I-200J0D01*
G01X1186697Y1095142D01*
G02X1186543Y1095092I-134J149D01*
G01X1186542D01*
G03X1186416Y1095099I-130J-1195D01*
G03X1185214Y1093897I0J-1202D01*
G03X1185235Y1093677I1202J4D01*
G01Y1093675D01*
G02X1185180Y1093498I-197J-36D01*
G01X1184910Y1093228D01*
X1184817Y1093199D01*
X1184785Y1093205D01*
G03X1184308I-239J-1178D01*
G01X1184305D01*
X1184275Y1093199D01*
X1184182Y1093228D01*
X1183912Y1093498D01*
G02X1183857Y1093675I142J141D01*
G01Y1093677D01*
G03X1183878Y1093897I-1181J224D01*
G03X1182676Y1095099I-1202J0D01*
G03X1182550Y1095093I-6J-1202D01*
G01X1182508Y1095089D01*
X1182428Y1095115D01*
X1182176Y1095341D01*
G02X1182110Y1095490I134J149D01*
G01Y1095731D01*
G03X1182109Y1095758I-1302J-35D01*
G01X1182108Y1095763D01*
Y1095781D01*
G03X1182096Y1095944I-1302J-14D01*
G01Y1095946D01*
G03X1182091Y1095981I-1292J-167D01*
G01X1182083Y1096028D01*
X1182111Y1096118D01*
X1182365Y1096384D01*
G02X1182531Y1096444I144J-139D01*
G01X1182533D01*
G03X1182676Y1096435I147J1193D01*
G03X1181474Y1097637I0J1202D01*
G03X1181482Y1097494I1202J-4D01*
G01X1181488Y1097447D01*
X1181456Y1097359D01*
X1181156Y1097072D01*
X1181067Y1097045D01*
X1181047Y1097048D01*
G03X1180807Y1097070I-238J-1280D01*
G01X1180805D01*
G03X1180591Y1097053I-4J-1302D01*
G01X1180545Y1097045D01*
X1180455Y1097073D01*
X1180188Y1097327D01*
G02X1180128Y1097495I139J144D01*
G01Y1097496D01*
G03X1180137Y1097636I-1193J147D01*
G01Y1097638D01*
G03X1178935Y1098839I-1202J-1D01*
G03Y1096435I0J-1202D01*
G03X1179078Y1096444I-4J1202D01*
G01X1179079D01*
G02X1179247Y1096384I24J-199D01*
G01X1179501Y1096118D01*
X1179529Y1096028D01*
X1179521Y1095982D01*
G03X1179504Y1095769I1285J-210D01*
G01Y1095490D01*
G02X1179438Y1095341I-200J0D01*
G01X1179216Y1095142D01*
G02X1179062Y1095092I-133J149D01*
G01X1179061D01*
G03X1178935Y1095099I-130J-1195D01*
G03X1177733Y1093897I0J-1202D01*
G03X1177754Y1093677I1202J4D01*
G01Y1093675D01*
G02X1177699Y1093498I-197J-36D01*
G01X1177431Y1093229D01*
X1177336Y1093200D01*
X1177287Y1093209D01*
G03X1177057Y1093229I-219J-1182D01*
G03X1176974Y1093225I16J-1202D01*
G01X1176972D01*
G03X1176844Y1093209I85J-1199D01*
G01X1176796Y1093200D01*
X1176701Y1093229D01*
X1176432Y1093498D01*
G02X1176377Y1093675I142J141D01*
G01Y1093677D01*
G03X1176398Y1093897I-1181J224D01*
G03X1175196Y1095099I-1202J0D01*
G03X1175072Y1095092I6J-1202D01*
G01X1175070D01*
G02X1174916Y1095142I-20J199D01*
G01X1174695Y1095341D01*
G02X1174629Y1095490I134J149D01*
G01Y1095667D01*
G03X1174628Y1095689I-1302J-48D01*
G01Y1095767D01*
G03X1174604Y1096013I-1303J-3D01*
G01Y1096017D01*
X1174602Y1096027D01*
X1174630Y1096117D01*
X1174884Y1096384D01*
G02X1175052Y1096444I144J-139D01*
G01X1175053D01*
G03X1175196Y1096435I147J1193D01*
G03Y1098839I0J1202D01*
G03X1173994Y1097638I0J-1202D01*
G01Y1097636D01*
G03X1174003Y1097496I1202J7D01*
G01Y1097495D01*
G02X1173943Y1097327I-199J-24D01*
G01X1173710Y1097105D01*
G02X1173540Y1097052I-138J144D01*
G01X1173539D01*
G03X1173325Y1097070I-216J-1285D01*
G03X1173086Y1097048I-1J-1303D01*
G02X1173080Y1097047I-36J196D01*
G01X1173064Y1097044D01*
X1172975Y1097072D01*
X1172675Y1097359D01*
X1172643Y1097447D01*
X1172649Y1097494D01*
G03X1172657Y1097637I-1194J139D01*
G03X1171455Y1096435I-1202J0D01*
G03X1171598Y1096443I4J1202D01*
G01X1171645Y1096449D01*
X1171733Y1096417D01*
X1172020Y1096117D01*
X1172048Y1096028D01*
X1172045Y1096009D01*
G03X1172022Y1095767I1280J-244D01*
G01Y1095490D01*
G02X1171956Y1095341I-200J0D01*
G01X1171735Y1095142D01*
G02X1171581Y1095092I-134J149D01*
G01X1171580D01*
G03X1171455Y1095099I-130J-1195D01*
G03X1170253Y1093897I0J-1202D01*
G03X1170274Y1093677I1202J4D01*
G01Y1093675D01*
G02X1170219Y1093498I-197J-36D01*
G01X1169951Y1093229D01*
X1169856Y1093200D01*
X1169807Y1093209D01*
G03X1169577Y1093229I-219J-1182D01*
G03X1169494Y1093225I16J-1202D01*
G01X1169492D01*
G03X1169364Y1093209I85J-1199D01*
G01X1169316Y1093200D01*
X1169221Y1093229D01*
X1168952Y1093498D01*
G02X1168897Y1093675I142J141D01*
G01Y1093677D01*
G03X1168918Y1093897I-1181J224D01*
G03X1167716Y1095099I-1202J0D01*
G03X1167592Y1095092I6J-1202D01*
G01X1167590D01*
G02X1167436Y1095142I-20J199D01*
G01X1167215Y1095341D01*
G02X1167149Y1095490I134J149D01*
G01Y1095667D01*
G03X1167148Y1095689I-1302J-48D01*
G01Y1095767D01*
G03X1167124Y1096013I-1303J-3D01*
G01Y1096017D01*
X1167122Y1096027D01*
X1167150Y1096117D01*
X1167404Y1096384D01*
G02X1167572Y1096444I144J-139D01*
G01X1167573D01*
G03X1167716Y1096435I147J1193D01*
G03Y1098839I0J1202D01*
G03X1166514Y1097638I0J-1202D01*
G01Y1097636D01*
G03X1166523Y1097496I1202J7D01*
G01Y1097495D01*
G02X1166463Y1097327I-199J-24D01*
G01X1166230Y1097105D01*
G02X1166060Y1097052I-138J144D01*
G01X1166059D01*
G03X1165845Y1097070I-216J-1285D01*
G03X1165606Y1097048I-1J-1303D01*
G02X1165600Y1097047I-36J196D01*
G01X1165584Y1097044D01*
X1165495Y1097072D01*
X1165195Y1097359D01*
X1165163Y1097447D01*
X1165169Y1097494D01*
G03X1165177Y1097637I-1194J139D01*
G03X1163975Y1096435I-1202J0D01*
G03X1164118Y1096443I4J1202D01*
G01X1164165Y1096449D01*
X1164253Y1096417D01*
X1164540Y1096117D01*
X1164568Y1096028D01*
X1164565Y1096009D01*
G03X1164542Y1095767I1280J-244D01*
G01Y1095490D01*
G02X1164476Y1095341I-200J0D01*
G01X1164255Y1095142D01*
G02X1164101Y1095092I-134J149D01*
G01X1164100D01*
G03X1163975Y1095099I-130J-1195D01*
G03X1162773Y1093897I0J-1202D01*
G03X1162794Y1093677I1202J4D01*
G01Y1093675D01*
G02X1162739Y1093498I-197J-36D01*
G01X1162471Y1093229D01*
X1162376Y1093200D01*
X1162327Y1093209D01*
G03X1162106Y1093229I-218J-1182D01*
G01X1162105D01*
G03X1161885Y1093208I4J-1202D01*
G01X1161883D01*
G02X1161706Y1093263I-36J197D01*
G01X1161471Y1093497D01*
G02X1161416Y1093674I142J141D01*
G01Y1093675D01*
G03X1161437Y1093897I-1181J224D01*
G03X1160235Y1095099I-1202J0D01*
G03X1160109Y1095093I-6J-1202D01*
G01X1160067Y1095089D01*
X1159987Y1095115D01*
X1159735Y1095342D01*
G02X1159669Y1095491I134J149D01*
G01Y1095667D01*
G03X1159668Y1095689I-1302J-48D01*
G01Y1095767D01*
G03X1159646Y1096006I-1303J1D01*
G02X1159645Y1096012I196J36D01*
G01X1159642Y1096028D01*
X1159670Y1096117D01*
X1159957Y1096417D01*
X1160045Y1096449D01*
X1160092Y1096443D01*
G03X1160235Y1096435I139J1194D01*
G03X1159033Y1097637I0J1202D01*
G03X1159041Y1097494I1202J-4D01*
G01X1159047Y1097447D01*
X1159015Y1097359D01*
X1158715Y1097072D01*
X1158626Y1097044D01*
X1158607Y1097047D01*
G03X1158365Y1097070I-244J-1280D01*
G03X1158152Y1097052I3J-1303D01*
G01X1158150D01*
G02X1157980Y1097105I-32J197D01*
G01X1157747Y1097327D01*
G02X1157687Y1097495I139J144D01*
G01Y1097496D01*
G03X1157696Y1097636I-1193J147D01*
G01Y1097638D01*
G03X1156494Y1098839I-1202J-1D01*
G03Y1096435I0J-1202D01*
G03X1156637Y1096444I-4J1202D01*
G01X1156638D01*
G02X1156806Y1096384I24J-199D01*
G01X1157060Y1096117D01*
X1157088Y1096027D01*
X1157086Y1096015D01*
G03X1157062Y1095767I1279J-249D01*
G01Y1095490D01*
G02X1156996Y1095341I-200J0D01*
G01X1156775Y1095142D01*
G02X1156621Y1095092I-134J149D01*
G01X1156620D01*
G03X1156494Y1095099I-130J-1195D01*
G03X1155292Y1093897I0J-1202D01*
G03X1155313Y1093677I1202J4D01*
G01Y1093675D01*
G02X1155258Y1093498I-197J-36D01*
G01X1154990Y1093229D01*
X1154895Y1093200D01*
X1154846Y1093209D01*
G03X1154616Y1093229I-219J-1182D01*
G03X1154533Y1093225I16J-1202D01*
G01X1154531D01*
G03X1154403Y1093209I85J-1199D01*
G01X1154355Y1093200D01*
X1154260Y1093229D01*
X1153991Y1093498D01*
G02X1153936Y1093675I142J141D01*
G01Y1093677D01*
G03X1153957Y1093897I-1181J224D01*
G03X1152755Y1095099I-1202J0D01*
G03X1152631Y1095092I6J-1202D01*
G01X1152629D01*
G02X1152475Y1095142I-20J199D01*
G01X1152254Y1095341D01*
G02X1152188Y1095490I134J149D01*
G01Y1095731D01*
G03X1152187Y1095758I-1303J-35D01*
G01X1152186Y1095763D01*
Y1095781D01*
G03X1152174Y1095944I-1302J-14D01*
G01Y1095946D01*
G03X1152169Y1095981I-1292J-167D01*
G01X1152161Y1096028D01*
X1152189Y1096118D01*
X1152443Y1096384D01*
G02X1152611Y1096444I144J-139D01*
G01X1152612D01*
G03X1152755Y1096435I147J1193D01*
G03Y1098839I0J1202D01*
G03X1151553Y1097638I0J-1202D01*
G01Y1097636D01*
G03X1151562Y1097496I1202J7D01*
G01Y1097495D01*
G02X1151502Y1097327I-199J-24D01*
G01X1151235Y1097073D01*
X1151145Y1097045D01*
X1151099Y1097053D01*
G03X1150885Y1097070I-210J-1285D01*
G01X1150883D01*
G03X1150644Y1097048I-1J-1302D01*
G01X1150641D01*
X1150623Y1097045D01*
X1150534Y1097072D01*
X1150234Y1097359D01*
X1150202Y1097447D01*
X1150208Y1097494D01*
G03X1150216Y1097637I-1194J139D01*
G03X1149014Y1096435I-1202J0D01*
G03X1149156Y1096444I-5J1202D01*
G01X1149159D01*
G02X1149325Y1096384I22J-199D01*
G01X1149579Y1096118D01*
X1149607Y1096028D01*
X1149599Y1095982D01*
G03X1149582Y1095769I1285J-210D01*
G01Y1095490D01*
G02X1149516Y1095341I-200J0D01*
G01X1149295Y1095142D01*
G02X1149141Y1095092I-134J149D01*
G01X1149140D01*
G03X1149014Y1095099I-130J-1195D01*
G03Y1092695I0J-1202D01*
G03X1149139Y1092702I-5J1202D01*
G01X1149141D01*
G02X1149295Y1092652I20J-199D01*
G01X1149516Y1092453D01*
G02X1149582Y1092304I-134J-149D01*
G01Y1091925D01*
G03X1149589Y1091791I1303J1D01*
G01X1149594Y1091746D01*
X1149564Y1091661D01*
X1149311Y1091409D01*
G02X1149147Y1091352I-141J142D01*
G03X1149015Y1091359I-130J-1195D01*
G03X1148079Y1090911I0J-1202D01*
G02X1147924Y1090837I-155J126D01*
G01X1146366D01*
G02X1146211Y1090911I0J200D01*
G03X1145275Y1091359I-936J-754D01*
G03X1145055Y1091338I4J-1202D01*
G01X1145053D01*
G02X1144876Y1091393I-36J197D01*
G01X1144642Y1091627D01*
G02X1144587Y1091804I142J141D01*
G01Y1091805D01*
G03X1144607Y1091994I-1182J221D01*
G01Y1092041D01*
G03X1144583Y1092263I-1202J-18D01*
G01Y1092267D01*
X1144577Y1092298D01*
X1144606Y1092391D01*
X1144876Y1092661D01*
G02X1145053Y1092716I141J-142D01*
G01X1145054D01*
G03X1145275Y1092695I224J1181D01*
G03X1144073Y1093897I0J1202D01*
G03X1144094Y1093677I1202J4D01*
G01Y1093675D01*
G02X1144039Y1093498I-197J-36D01*
G01X1143769Y1093228D01*
X1143676Y1093199D01*
X1143644Y1093205D01*
G03X1143167I-239J-1178D01*
G01X1143164D01*
X1143134Y1093199D01*
X1143041Y1093228D01*
X1142771Y1093498D01*
G02X1142716Y1093675I142J141D01*
G01Y1093677D01*
G03X1142737Y1093897I-1181J224D01*
G03X1141535Y1095099I-1202J0D01*
G03X1141410Y1095092I5J-1202D01*
G01X1141408D01*
G02X1141254Y1095142I-20J199D01*
G01X1141033Y1095341D01*
G02X1140967Y1095490I134J149D01*
G01Y1095667D01*
G03X1140966Y1095689I-1301J-48D01*
G01Y1095767D01*
G03X1140942Y1096013I-1303J-3D01*
G01Y1096017D01*
X1140940Y1096027D01*
X1140968Y1096117D01*
X1141222Y1096384D01*
G02X1141390Y1096444I144J-139D01*
G01X1141391D01*
G03X1141535Y1096435I147J1193D01*
G03Y1098839I0J1202D01*
G03X1140333Y1097638I0J-1202D01*
G01Y1097636D01*
G03X1140342Y1097496I1202J7D01*
G01Y1097495D01*
G02X1140282Y1097327I-199J-24D01*
G01X1140049Y1097105D01*
G02X1139879Y1097052I-138J144D01*
G01X1139878D01*
G03X1139664Y1097070I-216J-1285D01*
G01X1139663D01*
G03X1139451Y1097053I-2J-1303D01*
G01X1139404Y1097045D01*
X1139314Y1097073D01*
X1139049Y1097326D01*
G02X1138989Y1097494I139J144D01*
G01Y1097495D01*
G03X1138997Y1097637I-1194J139D01*
G03X1137795Y1096435I-1202J0D01*
G03X1137936Y1096443I3J1202D01*
G01X1137983Y1096449D01*
X1138071Y1096417D01*
X1138358Y1096117D01*
X1138386Y1096028D01*
X1138383Y1096009D01*
G03X1138360Y1095767I1280J-244D01*
G01Y1095490D01*
G02X1138294Y1095341I-200J0D01*
G01X1138042Y1095115D01*
X1137962Y1095089D01*
X1137920Y1095093D01*
G03X1137795Y1095099I-120J-1196D01*
G03X1136593Y1093897I0J-1202D01*
G03X1136614Y1093676I1202J3D01*
G01Y1093674D01*
G02X1136559Y1093497I-197J-36D01*
G01X1136324Y1093263D01*
G02X1136147Y1093208I-141J142D01*
G01X1136146D01*
G03X1135703I-221J-1181D01*
G01X1135702D01*
G02X1135525Y1093263I-36J197D01*
G01X1135290Y1093498D01*
G02X1135235Y1093675I142J141D01*
G01Y1093677D01*
G03X1135256Y1093897I-1181J224D01*
G03X1134054Y1095099I-1202J0D01*
G03X1133929Y1095092I5J-1202D01*
G01X1133927D01*
G02X1133773Y1095142I-20J199D01*
G01X1133552Y1095341D01*
G02X1133486Y1095490I134J149D01*
G01Y1095731D01*
G03X1133485Y1095758I-1303J-35D01*
G01X1133484Y1095763D01*
Y1095781D01*
G03X1133472Y1095944I-1302J-14D01*
G01Y1095946D01*
G03X1133467Y1095981I-1292J-167D01*
G01X1133459Y1096028D01*
X1133487Y1096118D01*
X1133741Y1096384D01*
G02X1133909Y1096444I144J-139D01*
G01X1133910D01*
G03X1134054Y1096435I147J1193D01*
G03Y1098839I0J1202D01*
G03X1132852Y1097638I0J-1202D01*
G01Y1097636D01*
G03X1132861Y1097496I1202J7D01*
G01Y1097495D01*
G02X1132801Y1097327I-199J-24D01*
G01X1132534Y1097072D01*
X1132445Y1097044D01*
X1132409Y1097050D01*
G03X1132182Y1097070I-227J-1282D01*
G03X1131970Y1097053I-2J-1302D01*
G01X1131923Y1097045D01*
X1131833Y1097073D01*
X1131568Y1097326D01*
G02X1131508Y1097494I139J144D01*
G01Y1097495D01*
G03X1131516Y1097637I-1194J139D01*
G03X1130314Y1096435I-1202J0D01*
G03X1130456Y1096443I3J1202D01*
G01X1130503Y1096449D01*
X1130591Y1096417D01*
X1130877Y1096117D01*
X1130905Y1096027D01*
X1130897Y1095981D01*
G03X1130880Y1095769I1285J-210D01*
G01Y1095490D01*
G02X1130814Y1095341I-200J0D01*
G01X1130562Y1095115D01*
X1130482Y1095089D01*
X1130440Y1095093D01*
G03X1130314Y1095099I-120J-1196D01*
G03X1129112Y1093897I0J-1202D01*
G03X1129133Y1093677I1202J4D01*
G01Y1093675D01*
G02X1129078Y1093498I-197J-36D01*
G01X1128808Y1093228D01*
X1128715Y1093199D01*
X1128683Y1093205D01*
G03X1128206I-239J-1178D01*
G01X1128203D01*
X1128173Y1093199D01*
X1128080Y1093228D01*
X1127810Y1093498D01*
G02X1127755Y1093675I142J141D01*
G01Y1093677D01*
G03X1127776Y1093897I-1181J224D01*
G03X1126574Y1095099I-1202J0D01*
G03X1126448Y1095092I4J-1202D01*
G01X1126446D01*
G02X1126292Y1095142I-20J199D01*
G01X1126071Y1095341D01*
G02X1126005Y1095490I134J149D01*
G01Y1095667D01*
G03X1126004Y1095689I-1302J-48D01*
G01Y1095767D01*
G03X1125980Y1096013I-1303J-3D01*
G01Y1096017D01*
X1125978Y1096027D01*
X1126006Y1096117D01*
X1126261Y1096384D01*
G02X1126429Y1096444I144J-139D01*
G01X1126430D01*
G03X1126574Y1096435I147J1193D01*
G03Y1098839I0J1202D01*
G03X1125372Y1097638I0J-1202D01*
G01Y1097636D01*
G03X1125381Y1097496I1202J7D01*
G01Y1097495D01*
G02X1125321Y1097327I-199J-24D01*
G01X1125054Y1097072D01*
X1124964Y1097044D01*
X1124930Y1097050D01*
G03X1124701Y1097070I-227J-1283D01*
G01X1124700D01*
G03X1124490Y1097053I0J-1303D01*
G01X1124489D01*
G02X1124319Y1097106I-32J197D01*
G01X1124054Y1097360D01*
X1124022Y1097448D01*
X1124028Y1097495D01*
G03X1124036Y1097637I-1194J139D01*
G03X1122834Y1096435I-1202J0D01*
G01X1122837D01*
G03X1122974Y1096443I-1J1202D01*
G02X1123143Y1096382I24J-198D01*
G01X1123396Y1096117D01*
X1123424Y1096028D01*
X1123419Y1095999D01*
G03X1123398Y1095767I1282J-233D01*
G01Y1095491D01*
G02X1123332Y1095342I-200J0D01*
G01X1123112Y1095144D01*
G02X1122958Y1095093I-134J148D01*
G01X1122957D01*
G03X1122834Y1095099I-120J-1196D01*
G03X1121632Y1093897I0J-1202D01*
G03X1121653Y1093677I1202J4D01*
G01Y1093675D01*
G02X1121598Y1093498I-197J-36D01*
G01X1121328Y1093228D01*
X1121235Y1093199D01*
X1121203Y1093205D01*
G03X1120726I-239J-1178D01*
G01X1120723D01*
X1120693Y1093199D01*
X1120600Y1093228D01*
X1120330Y1093498D01*
G02X1120275Y1093675I142J141D01*
G01Y1093677D01*
G03X1120296Y1093897I-1181J224D01*
G03X1119094Y1095099I-1202J0D01*
G03X1118968Y1095092I4J-1202D01*
G01X1118966D01*
G02X1118812Y1095142I-20J199D01*
G01X1118591Y1095341D01*
G02X1118525Y1095490I134J149D01*
G01Y1095667D01*
G03X1118524Y1095689I-1302J-48D01*
G01Y1095767D01*
G03X1118500Y1096013I-1303J-3D01*
G01Y1096017D01*
X1118498Y1096027D01*
X1118526Y1096117D01*
X1118781Y1096384D01*
G02X1118949Y1096444I144J-139D01*
G01X1118950D01*
G03X1119094Y1096435I147J1193D01*
G03Y1098839I0J1202D01*
G03X1117892Y1097638I0J-1202D01*
G01Y1097636D01*
G03X1117901Y1097496I1202J7D01*
G01Y1097495D01*
G02X1117841Y1097327I-199J-24D01*
G01X1117574Y1097072D01*
X1117484Y1097044D01*
X1117450Y1097050D01*
G03X1117221Y1097070I-227J-1283D01*
G01X1117220D01*
G03X1117010Y1097053I0J-1303D01*
G01X1117009D01*
G02X1116839Y1097106I-32J197D01*
G01X1116574Y1097360D01*
X1116542Y1097448D01*
X1116548Y1097495D01*
G03X1116556Y1097637I-1194J139D01*
G03X1115354Y1096435I-1202J0D01*
G01X1115357D01*
G03X1115494Y1096443I-1J1202D01*
G02X1115663Y1096382I24J-198D01*
G01X1115916Y1096117D01*
X1115944Y1096028D01*
X1115939Y1095999D01*
G03X1115918Y1095767I1282J-233D01*
G01Y1095491D01*
G02X1115852Y1095342I-200J0D01*
G01X1115632Y1095144D01*
G02X1115478Y1095093I-134J148D01*
G01X1115477D01*
G03X1115354Y1095099I-120J-1196D01*
G03X1114152Y1093897I0J-1202D01*
G03X1114173Y1093677I1202J4D01*
G01Y1093675D01*
G02X1114118Y1093498I-197J-36D01*
G01X1113883Y1093263D01*
G02X1113706Y1093208I-141J142D01*
G01X1113705D01*
G03X1113262I-222J-1181D01*
G01X1113261D01*
G02X1113084Y1093263I-36J197D01*
G01X1112849Y1093497D01*
G02X1112794Y1093674I142J141D01*
G01Y1093675D01*
G03X1112815Y1093897I-1181J224D01*
G03X1111613Y1095099I-1202J0D01*
G03X1111488Y1095092I5J-1202D01*
G01X1111486D01*
G02X1111332Y1095142I-20J199D01*
G01X1111111Y1095341D01*
G02X1111045Y1095490I134J149D01*
G01Y1095667D01*
G03X1111044Y1095689I-1301J-48D01*
G01Y1095767D01*
G03X1111020Y1096013I-1303J-3D01*
G01Y1096017D01*
X1111018Y1096027D01*
X1111046Y1096117D01*
X1111300Y1096384D01*
G02X1111468Y1096444I144J-139D01*
G01X1111469D01*
G03X1111613Y1096435I147J1193D01*
G03Y1098839I0J1202D01*
G03X1110411Y1097638I0J-1202D01*
G01Y1097636D01*
G03X1110420Y1097496I1202J7D01*
G01Y1097495D01*
G02X1110360Y1097327I-199J-24D01*
G01X1110127Y1097105D01*
G02X1109957Y1097052I-138J144D01*
G01X1109956D01*
G03X1109742Y1097070I-216J-1285D01*
G01X1109741D01*
G03X1109529Y1097053I-2J-1303D01*
G01X1109482Y1097045D01*
X1109392Y1097073D01*
X1109127Y1097326D01*
G02X1109067Y1097494I139J144D01*
G01Y1097495D01*
G03X1109075Y1097637I-1194J139D01*
G03X1107873Y1096435I-1202J0D01*
G03X1108014Y1096443I3J1202D01*
G01X1108061Y1096449D01*
X1108149Y1096417D01*
X1108436Y1096117D01*
X1108464Y1096028D01*
X1108461Y1096009D01*
G03X1108438Y1095767I1280J-244D01*
G01Y1095490D01*
G02X1108372Y1095341I-200J0D01*
G01X1108120Y1095115D01*
X1108040Y1095089D01*
X1107998Y1095093D01*
G03X1107873Y1095099I-120J-1196D01*
G03X1106671Y1093897I0J-1202D01*
G03X1106692Y1093677I1202J4D01*
G01Y1093675D01*
G02X1106637Y1093498I-197J-36D01*
G01X1106367Y1093228D01*
X1106274Y1093199D01*
X1106242Y1093205D01*
G03X1105765I-238J-1178D01*
G01X1105762D01*
X1105732Y1093199D01*
X1105639Y1093228D01*
X1105369Y1093498D01*
G02X1105314Y1093675I142J141D01*
G01Y1093677D01*
G03X1105335Y1093897I-1181J224D01*
G03X1104133Y1095099I-1202J0D01*
G03X1104008Y1095092I5J-1202D01*
G01X1104006D01*
G02X1103852Y1095142I-21J199D01*
G01X1103630Y1095341D01*
G02X1103564Y1095490I134J149D01*
G01Y1095731D01*
G03X1103563Y1095758I-1303J-35D01*
G01X1103562Y1095763D01*
Y1095781D01*
G03X1103550Y1095944I-1302J-14D01*
G01Y1095946D01*
G03X1103545Y1095981I-1292J-167D01*
G01X1103537Y1096027D01*
X1103565Y1096117D01*
X1103819Y1096384D01*
G02X1103987Y1096444I144J-139D01*
G01X1103988D01*
G03X1104133Y1096435I147J1193D01*
G03Y1098839I0J1202D01*
G03X1102931Y1097638I0J-1202D01*
G01Y1097636D01*
G03X1102940Y1097496I1202J7D01*
G01Y1097495D01*
G02X1102880Y1097327I-199J-24D01*
G01X1102613Y1097072D01*
X1102523Y1097044D01*
X1102476Y1097052D01*
G03X1102260Y1097070I-216J-1284D01*
G01X1102259D01*
G03X1102049Y1097053I0J-1302D01*
G01X1102048D01*
G02X1101878Y1097106I-32J197D01*
G01X1101613Y1097360D01*
X1101581Y1097448D01*
X1101587Y1097495D01*
G03X1101595Y1097637I-1194J139D01*
G03X1100393Y1096435I-1202J0D01*
G03X1100534Y1096443I3J1202D01*
G01X1100581Y1096449D01*
X1100669Y1096417D01*
X1100955Y1096118D01*
X1100983Y1096029D01*
X1100975Y1095982D01*
G03X1100958Y1095769I1285J-210D01*
G01Y1095490D01*
G02X1100892Y1095341I-200J0D01*
G01X1100640Y1095115D01*
X1100560Y1095089D01*
X1100518Y1095093D01*
G03X1100393Y1095099I-120J-1196D01*
G03X1099191Y1093897I0J-1202D01*
G03X1099212Y1093677I1202J4D01*
G01Y1093675D01*
G02X1099157Y1093498I-197J-36D01*
G01X1098887Y1093228D01*
X1098794Y1093199D01*
X1098762Y1093205D01*
G03X1098285I-239J-1178D01*
G01X1098282D01*
X1098252Y1093199D01*
X1098159Y1093228D01*
X1097889Y1093498D01*
G02X1097834Y1093675I142J141D01*
G01Y1093677D01*
G03X1097855Y1093897I-1181J224D01*
G03X1096653Y1095099I-1202J0D01*
G03X1096528Y1095092I5J-1202D01*
G01X1096526D01*
G02X1096372Y1095142I-21J199D01*
G01X1096150Y1095341D01*
G02X1096084Y1095490I134J149D01*
G01Y1095731D01*
G03X1096083Y1095758I-1303J-35D01*
G01X1096082Y1095763D01*
Y1095781D01*
G03X1096070Y1095944I-1302J-14D01*
G01Y1095946D01*
G03X1096065Y1095981I-1292J-167D01*
G01X1096057Y1096027D01*
X1096085Y1096117D01*
X1096339Y1096384D01*
G02X1096507Y1096444I144J-139D01*
G01X1096508D01*
G03X1096653Y1096435I147J1193D01*
G03Y1098839I0J1202D01*
G03X1095451Y1097638I0J-1202D01*
G01Y1097636D01*
G03X1095460Y1097496I1202J7D01*
G01Y1097495D01*
G02X1095400Y1097327I-199J-24D01*
G01X1095133Y1097072D01*
X1095043Y1097044D01*
X1094996Y1097052D01*
G03X1094780Y1097070I-216J-1284D01*
G01X1094779D01*
G03X1094569Y1097053I0J-1302D01*
G01X1094568D01*
G02X1094398Y1097106I-32J197D01*
G01X1094133Y1097360D01*
X1094101Y1097448D01*
X1094107Y1097495D01*
G03X1094115Y1097637I-1194J139D01*
G03X1092913Y1096435I-1202J0D01*
G03X1093054Y1096443I3J1202D01*
G01X1093101Y1096449D01*
X1093189Y1096417D01*
X1093475Y1096118D01*
X1093503Y1096029D01*
X1093495Y1095982D01*
G03X1093478Y1095769I1285J-210D01*
G01Y1095490D01*
G02X1093412Y1095341I-200J0D01*
G01X1093160Y1095115D01*
X1093080Y1095089D01*
X1093038Y1095093D01*
G03X1092913Y1095099I-120J-1196D01*
G03X1091711Y1093897I0J-1202D01*
G03X1091732Y1093677I1202J4D01*
G01Y1093675D01*
G02X1091677Y1093498I-197J-36D01*
G01X1091442Y1093263D01*
G02X1091265Y1093208I-141J142D01*
G01X1091264D01*
G03X1090821I-221J-1181D01*
G01X1090820D01*
G02X1090643Y1093263I-36J197D01*
G01X1090408Y1093497D01*
G02X1090353Y1093674I142J141D01*
G01Y1093675D01*
G03X1090374Y1093897I-1181J224D01*
G03X1089172Y1095099I-1202J0D01*
G03X1089047Y1095092I5J-1202D01*
G01X1089045D01*
G02X1088891Y1095142I-20J199D01*
G01X1088670Y1095341D01*
G02X1088604Y1095490I134J149D01*
G01Y1095731D01*
G03X1088603Y1095758I-1303J-35D01*
G01X1088602Y1095763D01*
Y1095781D01*
G03X1088590Y1095944I-1302J-14D01*
G01Y1095946D01*
G03X1088585Y1095981I-1292J-167D01*
G01X1088577Y1096028D01*
X1088605Y1096118D01*
X1088859Y1096384D01*
G02X1089027Y1096444I144J-139D01*
G01X1089028D01*
G03X1089172Y1096435I147J1193D01*
G03Y1098839I0J1202D01*
G03X1087970Y1097638I0J-1202D01*
G01Y1097636D01*
G03X1087979Y1097496I1202J7D01*
G01Y1097495D01*
G02X1087919Y1097327I-199J-24D01*
G01X1087652Y1097072D01*
X1087563Y1097044D01*
X1087527Y1097050D01*
G03X1087300Y1097070I-227J-1282D01*
G03X1085998Y1095769I0J-1302D01*
G01Y1091927D01*
G03X1086148Y1091323I1302J3D01*
G01X1086155Y1091310D01*
X1086164Y1091293D01*
X1086178Y1091267D01*
X1086189Y1091222D01*
Y1091192D01*
G02X1086167Y1091103I-200J2D01*
G01X1086063Y1090922D01*
G02X1085900Y1090837I-164J115D01*
G01X1084955D01*
G02X1084793Y1090921I1J200D01*
G01X1084631Y1091198D01*
X1084609Y1091235D01*
G02X1084581Y1091335I172J102D01*
G01Y1091339D01*
G02X1084595Y1091411I200J-2D01*
G01X1084608Y1091434D01*
G03X1084764Y1091994I-1046J593D01*
G01Y1092041D01*
G03X1082360I-1202J-14D01*
G01Y1092024D01*
G03X1082505Y1091454I1202J2D01*
G01X1082506Y1091451D01*
X1082510Y1091443D01*
X1082512Y1091440D01*
X1082526Y1091413D01*
G02X1082542Y1091333I-184J-78D01*
G01X1082541Y1091280D01*
X1082493Y1091198D01*
X1082331Y1090921D01*
G02X1082169Y1090837I-163J116D01*
G01X1081215D01*
G02X1081053Y1090921I1J200D01*
G01X1080891Y1091198D01*
X1080869Y1091235D01*
G02X1080841Y1091335I172J102D01*
G01Y1091339D01*
G02X1080855Y1091411I200J-2D01*
G01X1080868Y1091434D01*
G03X1081024Y1091994I-1046J593D01*
G01Y1092041D01*
G03X1078620I-1202J-14D01*
G01Y1092024D01*
G03X1078765Y1091454I1202J2D01*
G01X1078766Y1091451D01*
X1078770Y1091443D01*
X1078772Y1091440D01*
X1078786Y1091413D01*
G02X1078802Y1091333I-184J-78D01*
G01X1078801Y1091280D01*
X1078753Y1091198D01*
X1078591Y1090921D01*
G02X1078429Y1090837I-163J116D01*
G01X1077475D01*
G02X1077313Y1090921I1J200D01*
G01X1077151Y1091198D01*
X1077129Y1091235D01*
G02X1077101Y1091335I172J102D01*
G01Y1091339D01*
G02X1077115Y1091411I200J-2D01*
G01X1077128Y1091434D01*
G03X1077284Y1091994I-1046J593D01*
G01Y1092041D01*
G03X1074880I-1202J-14D01*
G01Y1092024D01*
G03X1075025Y1091454I1202J2D01*
G01X1075026Y1091451D01*
X1075030Y1091443D01*
X1075032Y1091440D01*
X1075046Y1091413D01*
G02X1075062Y1091333I-184J-78D01*
G01X1075061Y1091280D01*
X1075013Y1091198D01*
X1074851Y1090921D01*
G02X1074689Y1090837I-163J116D01*
G01X1073735D01*
G02X1073573Y1090921I1J200D01*
G01X1073411Y1091198D01*
X1073389Y1091235D01*
G02X1073361Y1091335I172J102D01*
G01Y1091339D01*
G02X1073375Y1091411I200J-2D01*
G01X1073388Y1091434D01*
G03X1073544Y1091994I-1046J593D01*
G01Y1092041D01*
G03X1071140I-1202J-14D01*
G01Y1092024D01*
G03X1071285Y1091454I1202J2D01*
G01X1071286Y1091451D01*
X1071290Y1091443D01*
X1071292Y1091440D01*
X1071306Y1091413D01*
G02X1071322Y1091333I-184J-78D01*
G01X1071321Y1091280D01*
X1071273Y1091198D01*
X1071111Y1090921D01*
G02X1070949Y1090837I-163J116D01*
G01X1069995D01*
G02X1069833Y1090921I1J200D01*
G01X1069671Y1091198D01*
X1069649Y1091235D01*
G02X1069621Y1091335I172J102D01*
G01Y1091339D01*
G02X1069635Y1091411I200J-2D01*
G01X1069648Y1091434D01*
G03X1069804Y1091994I-1046J593D01*
G01Y1092041D01*
G03X1067400I-1202J-14D01*
G01Y1092024D01*
G03X1067545Y1091454I1202J2D01*
G01X1067546Y1091451D01*
X1067550Y1091443D01*
X1067552Y1091440D01*
X1067566Y1091413D01*
G02X1067582Y1091333I-184J-78D01*
G01X1067581Y1091280D01*
X1067533Y1091198D01*
X1067371Y1090921D01*
G02X1067209Y1090837I-163J116D01*
G01X1066255D01*
G02X1066093Y1090921I1J200D01*
G01X1065931Y1091198D01*
X1065909Y1091235D01*
G02X1065881Y1091335I172J102D01*
G01Y1091339D01*
G02X1065895Y1091411I200J-2D01*
G01X1065908Y1091434D01*
G03X1066064Y1091994I-1046J593D01*
G01Y1092041D01*
G03X1063660I-1202J-14D01*
G01Y1092024D01*
G03X1063805Y1091454I1202J2D01*
G01X1063806Y1091451D01*
X1063810Y1091443D01*
X1063812Y1091440D01*
X1063826Y1091413D01*
G02X1063842Y1091333I-184J-78D01*
G01X1063841Y1091280D01*
X1063793Y1091198D01*
X1063631Y1090921D01*
G02X1063469Y1090837I-163J116D01*
G01X1062629D01*
G02X1062572Y1090846I2J200D01*
G01X1062570D01*
G02X1062483Y1090900I58J191D01*
G02X1062458Y1090933I146J137D01*
G01X1062281Y1091225D01*
X1062264Y1091259D01*
G02X1062266Y1091406I187J71D01*
G01X1062275Y1091423D01*
G03X1062423Y1092025I-1154J603D01*
G01Y1092027D01*
G03X1059819I-1302J0D01*
G01Y1092025D01*
G03X1059961Y1091433I1302J-1D01*
G01X1059973Y1091410D01*
X1059991Y1091330D01*
G02X1059978Y1091259I-200J0D01*
G01X1059961Y1091225D01*
X1059867Y1091070D01*
X1059866Y1091069D01*
X1059823Y1090998D01*
X1059784Y1090933D01*
G02X1059759Y1090900I-171J104D01*
G02X1059672Y1090846I-145J137D01*
G01X1059670D01*
G02X1059613Y1090837I-59J191D01*
G01X1058929D01*
G02X1058905Y1090839I5J200D01*
G01X1058903D01*
G02X1058820Y1090869I25J198D01*
G01X1058795Y1090893D01*
X1058794Y1090894D01*
X1058782Y1090905D01*
X1058781Y1090906D01*
G03X1058770Y1090916I-139J-142D01*
G01X1058760Y1090923D01*
X1058543Y1091140D01*
G02X1058486Y1091256I141J142D01*
G01Y1091257D01*
G02X1058487Y1091314I198J25D01*
G01X1058489Y1091325D01*
G02X1058503Y1091366I195J-44D01*
G01X1058511Y1091380D01*
G03X1058683Y1092027I-1131J647D01*
G03X1057381Y1093329I-1302J0D01*
G03X1056777Y1093180I1J-1303D01*
G02X1056684Y1093157I-93J177D01*
G01X1056536D01*
X1056517Y1093166D01*
X1049627Y1100056D01*
G02X1049591Y1100106I142J140D01*
G02X1049569Y1100197I178J91D01*
G01Y1178868D01*
G02X1049591Y1178959I200J0D01*
G02X1049627Y1179009I178J-90D01*
G01X1049788Y1179170D01*
G02X1049838Y1179206I140J-142D01*
G02X1049929Y1179228I91J-178D01*
G01X1052440D01*
G03X1052539Y1179229I10J3892D01*
G01X1052557Y1179230D01*
X1053614D01*
G03X1053653I19J3891D01*
G01X1053696D01*
X1053707Y1179231D01*
X1053736D01*
X1053753Y1179232D01*
X1053766D01*
G02X1053918Y1179154I-7J-200D01*
G01X1053992Y1179051D01*
G02X1054028Y1178958I-163J-116D01*
G01X1054034Y1178910D01*
X1053965Y1178829D01*
G03X1053679Y1178050I918J-779D01*
G03X1054881Y1176848I1202J0D01*
G03X1055766Y1177237I0J1201D01*
G01X1055770Y1177241D01*
G02X1055911Y1177305I147J-136D01*
G01X1056074Y1177301D01*
X1056225Y1177297D01*
G02X1056307Y1177277I-5J-200D01*
G01X1056344Y1177259D01*
X1056373Y1177224D01*
G03X1057379Y1176748I1007J827D01*
G01X1061120D01*
G03X1062239Y1177383I0J1303D01*
G01X1062251Y1177404D01*
X1062252Y1177406D01*
X1062258Y1177416D01*
G03X1062369Y1177677I-1136J637D01*
G01X1062371Y1177685D01*
G03X1062377Y1177705I-1245J384D01*
G01X1062380Y1177716D01*
X1062381Y1177719D01*
G03X1062384Y1177729I-1244J379D01*
G01X1062385Y1177734D01*
X1062390Y1177755D01*
G03X1062422Y1178003I-1270J290D01*
G01Y1178028D01*
G03Y1178043I-1302J7D01*
G01Y1178047D01*
G03Y1178051I-1302J2D01*
G03X1062400Y1178293I-1302J4D01*
G01X1062394Y1178327D01*
G03X1062371Y1178414I-1270J-289D01*
G01Y1178416D01*
G03X1062356Y1178460I-1240J-398D01*
G02X1062354Y1178468I193J53D01*
G03X1062352Y1178474I-1236J-409D01*
G01X1062349Y1178484D01*
X1062347Y1178490D01*
G03X1062323Y1178550I-1221J-454D01*
G01Y1178552D01*
G03X1062216Y1178756I-1203J-501D01*
G03X1062214Y1178758I-139J-137D01*
G03X1062179Y1178809I-1091J-711D01*
G02X1062174Y1178817I167J110D01*
G03X1062170Y1178822I-1015J-808D01*
G01X1062168Y1178825D01*
X1062167Y1178826D01*
X1062163Y1178832D01*
X1062152Y1178848D01*
G02X1062141Y1179018I176J97D01*
G01X1062230Y1179193D01*
Y1179195D01*
X1062253Y1179239D01*
Y1179241D01*
X1062310Y1179354D01*
G02X1062488Y1179464I179J-90D01*
G01X1063597D01*
G02X1063647Y1179457I-3J-200D01*
G01X1063724Y1179434D01*
G02X1063764Y1179402I-104J-171D01*
G02X1063802Y1179347I-143J-140D01*
G01X1063845Y1179254D01*
X1063963Y1179000D01*
G02X1063974Y1178938I-189J-65D01*
G01X1063931Y1178814D01*
X1063911Y1178788D01*
G03X1063659Y1178058I950J-736D01*
G01Y1178021D01*
G03X1066063I1202J30D01*
G01Y1178058D01*
G03X1065811Y1178788I-1202J-6D01*
G01X1065791Y1178814D01*
X1065748Y1178938D01*
G02X1065759Y1179000I200J-3D01*
G01X1065877Y1179254D01*
X1065922Y1179351D01*
G02X1065936Y1179375I179J-88D01*
G02X1065989Y1179429I167J-111D01*
G01X1066011Y1179442D01*
G02X1066049Y1179457I92J-178D01*
G02X1066100Y1179464I52J-193D01*
G01X1066170D01*
G03X1067427Y1179679I-2J3796D01*
G03X1067740Y1179805I-1260J3582D01*
G01X1067741D01*
G03X1067783Y1179825I-1611J3438D01*
G01X1067813Y1179838D01*
X1067841Y1179852D01*
X1067863Y1179864D01*
X1067877Y1179871D01*
X1067878D01*
G03X1067887Y1179876I-1838J3318D01*
G01X1067897Y1179881D01*
X1067900Y1179883D01*
X1067931Y1179899D01*
X1067932D01*
X1067933Y1179900D01*
X1067934D01*
G03X1067941Y1179904I-1872J3283D01*
G01X1067942D01*
G03X1067945Y1179906I-109J166D01*
G01X1067946D01*
G03X1067948Y1179907I-1692J3386D01*
G01X1067964Y1179916D01*
X1067966Y1179917D01*
G03X1068302Y1180121I-1800J3343D01*
G01X1068315Y1180130D01*
G03X1068843Y1180568I-2150J3129D01*
G03X1068858Y1180583I-2677J2692D01*
G01X1068867Y1180592D01*
G02X1068939Y1180637I140J-143D01*
G01X1068949Y1180640D01*
G03X1069753Y1181444I-347J1151D01*
G01X1069756Y1181454D01*
G02X1069805Y1181530I188J-68D01*
G01X1069817Y1181542D01*
G03X1070145Y1181915I-2681J2689D01*
G02X1070193Y1181960I159J-121D01*
G03X1070549Y1182226I-2109J3193D01*
G01X1070626Y1182290D01*
X1070643Y1182295D01*
G02X1070734Y1182273I0J-200D01*
G01X1070852Y1182200D01*
X1070854D01*
X1071050Y1182077D01*
X1071058Y1182072D01*
G02X1071078Y1182057I-110J-167D01*
G02X1071144Y1181892I-134J-149D01*
G01X1071143Y1181882D01*
G03X1071140Y1181797I1199J-85D01*
G01Y1181787D01*
G03X1072342Y1180589I1202J4D01*
G03X1073544Y1181791I0J1202D01*
G01Y1181794D01*
G03X1073524Y1182013I-1202J1D01*
G01X1073515Y1182061D01*
X1073544Y1182156D01*
X1073813Y1182425D01*
G02X1073990Y1182480I141J-142D01*
G01X1073991D01*
G03X1074211Y1182459I224J1181D01*
G01X1074213D01*
G03X1074432Y1182480I-5J1202D01*
G01X1074434D01*
G02X1074611Y1182425I36J-197D01*
G01X1074846Y1182190D01*
G02X1074901Y1182013I-142J-141D01*
G01Y1182011D01*
G03X1074880Y1181791I1181J-224D01*
G03X1077284I1202J0D01*
G03X1077263Y1182011I-1202J-4D01*
G01Y1182013D01*
G02X1077318Y1182190I197J36D01*
G01X1077553Y1182425D01*
G02X1077730Y1182480I141J-142D01*
G01X1077731D01*
G03X1077952Y1182459I224J1181D01*
G03X1079154Y1183660I0J1202D01*
G01Y1183662D01*
G03X1079148Y1183775I-1202J-7D01*
G01X1079147Y1183785D01*
Y1183787D01*
G02X1079197Y1183941I199J20D01*
G01X1079396Y1184162D01*
G02X1079545Y1184228I149J-134D01*
G01X1079822D01*
G03X1080061Y1184250I1J1303D01*
G02X1080067Y1184251I36J-196D01*
G01X1080083Y1184254D01*
X1080172Y1184226D01*
X1080472Y1183939D01*
X1080504Y1183851D01*
X1080498Y1183804D01*
G03X1080490Y1183661I1194J-139D01*
G03X1081692Y1182459I1202J0D01*
G03X1081912Y1182480I-4J1202D01*
G01X1081914D01*
G02X1082091Y1182425I36J-197D01*
G01X1082326Y1182190D01*
G02X1082381Y1182013I-142J-141D01*
G01Y1182011D01*
G03X1082360Y1181792I1181J-224D01*
G01Y1181790D01*
G03X1082381Y1181571I1202J5D01*
G01Y1181569D01*
G02X1082326Y1181392I-197J-36D01*
G01X1082091Y1181157D01*
G02X1081914Y1181102I-141J142D01*
G01X1081913D01*
G03X1081692Y1181123I-224J-1181D01*
G03X1080490Y1179921I0J-1202D01*
G03X1080511Y1179700I1202J3D01*
G01Y1179698D01*
G02X1080456Y1179521I-197J-36D01*
G01X1080222Y1179286D01*
G02X1080045Y1179231I-141J142D01*
G01X1080044D01*
G03X1079822Y1179252I-224J-1181D01*
G03X1081024Y1178050I0J-1202D01*
G03X1081003Y1178271I-1202J-3D01*
G01Y1178273D01*
G02X1081058Y1178450I197J36D01*
G01X1081292Y1178685D01*
G02X1081469Y1178740I141J-142D01*
G01X1081470D01*
G03X1081692Y1178719I224J1181D01*
G03X1082894Y1179921I0J1202D01*
G03X1082873Y1180141I-1202J-4D01*
G01Y1180143D01*
G02X1082928Y1180320I197J36D01*
G01X1083163Y1180555D01*
G02X1083340Y1180610I141J-142D01*
G01X1083341D01*
G03X1083562Y1180589I224J1181D01*
G03X1084764Y1181791I0J1202D01*
G03X1084743Y1182011I-1202J-4D01*
G01Y1182013D01*
G02X1084798Y1182190I197J36D01*
G01X1085033Y1182425D01*
G02X1085210Y1182480I141J-142D01*
G01X1085211D01*
G03X1085431Y1182459I224J1181D01*
G01X1085433D01*
G03X1085652Y1182480I-5J1202D01*
G01X1085654D01*
G02X1085831Y1182425I36J-197D01*
G01X1086066Y1182190D01*
G02X1086121Y1182013I-142J-141D01*
G01Y1182011D01*
G03X1086100Y1181791I1181J-224D01*
G03X1087302Y1182993I1202J0D01*
G03X1087082Y1182972I4J-1202D01*
G01X1087080D01*
G02X1086903Y1183027I-36J197D01*
G01X1086668Y1183262D01*
G02X1086613Y1183439I142J141D01*
G01Y1183441D01*
G03X1086634Y1183661I-1181J224D01*
G03X1084230I-1202J0D01*
G03X1084251Y1183441I1202J4D01*
G01Y1183439D01*
G02X1084196Y1183262I-197J-36D01*
G01X1083961Y1183027D01*
G02X1083784Y1182972I-141J142D01*
G01X1083783D01*
G03X1083563Y1182993I-224J-1181D01*
G01X1083561D01*
G03X1083342Y1182972I5J-1202D01*
G01X1083340D01*
G02X1083163Y1183027I-36J197D01*
G01X1082928Y1183262D01*
G02X1082873Y1183439I142J141D01*
G01Y1183441D01*
G03X1082894Y1183661I-1181J224D01*
G03X1081692Y1184863I-1202J0D01*
G03X1081549Y1184855I-4J-1202D01*
G01X1081502Y1184849D01*
X1081414Y1184881D01*
X1081127Y1185181D01*
X1081099Y1185270D01*
X1081102Y1185289D01*
G03X1081125Y1185531I-1280J244D01*
G03X1081103Y1185770I-1303J1D01*
G02X1081102Y1185776I196J36D01*
G01X1081099Y1185792D01*
X1081127Y1185881D01*
X1081414Y1186181D01*
X1081502Y1186213D01*
X1081549Y1186207D01*
G03X1081692Y1186199I139J1194D01*
G03X1080490Y1187401I0J1202D01*
G03X1080498Y1187258I1202J-4D01*
G01X1080504Y1187211D01*
X1080472Y1187123D01*
X1080172Y1186836D01*
X1080083Y1186808D01*
X1080064Y1186811D01*
G03X1079822Y1186834I-244J-1280D01*
G01X1079545D01*
G02X1079396Y1186900I0J200D01*
G01X1079168Y1187154D01*
X1079142Y1187232D01*
X1079146Y1187271D01*
X1079147Y1187273D01*
Y1187279D01*
G03X1079154Y1187400I-1195J130D01*
G01Y1187402D01*
G03X1077952Y1188603I-1202J-1D01*
G03X1077809Y1188594I4J-1202D01*
G02X1077640Y1188655I-24J198D01*
G01X1077386Y1188921D01*
X1077359Y1189010D01*
X1077362Y1189030D01*
G03X1077384Y1189271I-1280J238D01*
G03X1077360Y1189517I-1301J-3D01*
G01Y1189521D01*
X1077358Y1189530D01*
X1077386Y1189620D01*
X1077640Y1189887D01*
G02X1077809Y1189948I145J-137D01*
G03X1077952Y1189939I147J1193D01*
G03X1079154Y1191140I0J1202D01*
G01Y1191142D01*
G03X1079148Y1191255I-1202J-7D01*
G01X1079147Y1191265D01*
Y1191267D01*
G02X1079197Y1191421I199J20D01*
G01X1079396Y1191642D01*
G02X1079545Y1191708I149J-134D01*
G01X1079822D01*
G03X1080061Y1191730I1J1303D01*
G02X1080067Y1191731I36J-196D01*
G01X1080083Y1191734D01*
X1080172Y1191706D01*
X1080472Y1191419D01*
X1080504Y1191331D01*
X1080498Y1191284D01*
G03X1080490Y1191141I1194J-139D01*
G03X1081692Y1192343I1202J0D01*
G03X1081549Y1192335I-4J-1202D01*
G01X1081502Y1192329D01*
X1081414Y1192361D01*
X1081127Y1192661D01*
X1081099Y1192750D01*
X1081102Y1192769D01*
G03X1081125Y1193011I-1280J244D01*
G03X1081103Y1193250I-1303J1D01*
G02X1081102Y1193256I196J36D01*
G01X1081099Y1193272D01*
X1081127Y1193361D01*
X1081414Y1193661D01*
X1081502Y1193693D01*
X1081549Y1193687D01*
G03X1081692Y1193679I139J1194D01*
G03X1080490Y1194881I0J1202D01*
G03X1080498Y1194738I1202J-4D01*
G01X1080504Y1194691D01*
X1080472Y1194603D01*
X1080172Y1194316D01*
X1080083Y1194288D01*
X1080064Y1194291D01*
G03X1079822Y1194314I-244J-1280D01*
G01X1079545D01*
G02X1079396Y1194380I0J200D01*
G01X1079168Y1194634D01*
X1079142Y1194712D01*
X1079146Y1194751D01*
X1079147Y1194753D01*
Y1194759D01*
G03X1079154Y1194880I-1195J130D01*
G01Y1194882D01*
G03X1077952Y1196083I-1202J-1D01*
G03X1077808Y1196074I3J-1202D01*
G01X1077807D01*
G02X1077639Y1196134I-24J199D01*
G01X1077385Y1196400D01*
X1077357Y1196490D01*
X1077365Y1196537D01*
G03Y1196965I-1282J214D01*
G01X1077357Y1197012D01*
X1077385Y1197102D01*
X1077639Y1197368D01*
G02X1077807Y1197428I144J-139D01*
G01X1077808D01*
G03X1077952Y1197419I147J1193D01*
G03X1079154Y1198621I0J1202D01*
G03X1079147Y1198746I-1202J-5D01*
G01Y1198748D01*
G02X1079197Y1198902I199J21D01*
G01X1079396Y1199124D01*
G02X1079545Y1199190I149J-134D01*
G01X1079778D01*
X1079786Y1199189D01*
X1079822D01*
G03X1080060Y1199211I0J1303D01*
G01X1080064D01*
X1080084Y1199215D01*
X1080173Y1199187D01*
X1080439Y1198933D01*
G02X1080499Y1198765I-139J-144D01*
G01Y1198764D01*
G03X1080490Y1198621I1193J-147D01*
G03X1081692Y1199823I1202J0D01*
G01X1081691D01*
G03X1081302Y1199758I1J-1201D01*
G01X1081287Y1199753D01*
X1081259Y1199748D01*
G02X1081082Y1199805I-34J197D01*
G01X1081048Y1199840D01*
X1081019Y1199933D01*
X1081035Y1200014D01*
X1081041Y1200030D01*
G03X1081043Y1200036I-1235J415D01*
G02X1081045Y1200042I191J-60D01*
G03X1081067Y1200107I-1223J450D01*
G01Y1200109D01*
G03X1081073Y1200127I-1233J421D01*
G01Y1200128D01*
X1081082Y1200157D01*
G03X1081086Y1200170I-1241J389D01*
G01X1081088Y1200179D01*
X1081093Y1200201D01*
G03X1081096Y1200215I-1272J280D01*
G01Y1200216D01*
X1081100Y1200236D01*
G03X1081119Y1200364I-1278J255D01*
G01Y1200366D01*
G03X1081120Y1200375I-1294J148D01*
G01Y1200380D01*
X1081121Y1200387D01*
G03X1081122Y1200404I-1300J85D01*
G01Y1200419D01*
X1081123Y1200426D01*
Y1200434D01*
X1081124Y1200438D01*
Y1200471D01*
G03Y1200485I-1302J7D01*
G01Y1200493D01*
G03X1081102Y1200732I-1302J1D01*
G01Y1200735D01*
X1081099Y1200753D01*
X1081126Y1200842D01*
X1081380Y1201108D01*
G02X1081549Y1201169I145J-137D01*
G03X1081692Y1201160I147J1193D01*
G03X1080490Y1202362I0J1202D01*
G03X1080499Y1202219I1202J4D01*
G02X1080438Y1202050I-198J-24D01*
G01X1080172Y1201796D01*
X1080083Y1201769D01*
X1080063Y1201772D01*
G03X1079822Y1201794I-238J-1280D01*
G01X1079545D01*
G02X1079396Y1201860I0J200D01*
G01X1079168Y1202114D01*
X1079142Y1202192D01*
X1079146Y1202231D01*
X1079147Y1202233D01*
Y1202239D01*
G03X1079154Y1202361I-1195J130D01*
G01Y1202363D01*
G03X1077952Y1203564I-1202J-1D01*
G03X1077808Y1203555I3J-1202D01*
G01X1077807D01*
G02X1077639Y1203615I-24J199D01*
G01X1077385Y1203881D01*
X1077357Y1203971D01*
X1077365Y1204018D01*
G03Y1204446I-1282J214D01*
G01X1077357Y1204493D01*
X1077385Y1204583D01*
X1077639Y1204849D01*
G02X1077807Y1204909I144J-139D01*
G01X1077808D01*
G03X1077952Y1204900I147J1193D01*
G03X1079154Y1206101I0J1202D01*
G01Y1206103D01*
G03X1079148Y1206217I-1202J-6D01*
G01X1079147Y1206227D01*
Y1206229D01*
G02X1079197Y1206383I199J20D01*
G01X1079396Y1206604D01*
G02X1079545Y1206670I149J-134D01*
G01X1079822D01*
G03X1080062Y1206692I2J1302D01*
G01X1080065D01*
X1080083Y1206695D01*
X1080172Y1206668D01*
X1080438Y1206414D01*
G02X1080499Y1206245I-137J-145D01*
G03X1080490Y1206102I1193J-147D01*
G03X1081692Y1207304I1202J0D01*
G03X1081549Y1207295I4J-1202D01*
G02X1081380Y1207356I-24J198D01*
G01X1081126Y1207622D01*
X1081099Y1207711D01*
X1081102Y1207731D01*
G03X1081124Y1207972I-1280J238D01*
G03X1081102Y1208212I-1302J2D01*
G01Y1208215D01*
X1081099Y1208233D01*
X1081126Y1208322D01*
X1081380Y1208588D01*
G02X1081549Y1208649I145J-137D01*
G03X1081692Y1208640I147J1193D01*
G03X1080490Y1209842I0J1202D01*
G03X1080499Y1209699I1202J4D01*
G02X1080438Y1209530I-198J-24D01*
G01X1080172Y1209276D01*
X1080083Y1209249D01*
X1080063Y1209252D01*
G03X1079822Y1209274I-238J-1280D01*
G01X1079545D01*
G02X1079396Y1209340I0J200D01*
G01X1079168Y1209594D01*
X1079142Y1209672D01*
X1079146Y1209711D01*
X1079147Y1209713D01*
Y1209719D01*
G03X1079154Y1209841I-1195J130D01*
G01Y1209843D01*
G03X1077952Y1211044I-1202J-1D01*
G03X1077808Y1211035I3J-1202D01*
G01X1077807D01*
G02X1077639Y1211095I-24J199D01*
G01X1077385Y1211361D01*
X1077357Y1211451D01*
X1077365Y1211498D01*
G03Y1211926I-1282J214D01*
G01X1077357Y1211973D01*
X1077385Y1212063D01*
X1077639Y1212329D01*
G02X1077807Y1212389I144J-139D01*
G01X1077808D01*
G03X1077952Y1212380I147J1193D01*
G03X1079154Y1213581I0J1202D01*
G01Y1213583D01*
G03X1079148Y1213697I-1202J-6D01*
G01X1079147Y1213707D01*
Y1213709D01*
G02X1079197Y1213863I199J20D01*
G01X1079396Y1214084D01*
G02X1079545Y1214150I149J-134D01*
G01X1079822D01*
G03X1080062Y1214172I2J1302D01*
G01X1080065D01*
X1080083Y1214175D01*
X1080172Y1214148D01*
X1080438Y1213894D01*
G02X1080499Y1213725I-137J-145D01*
G03X1080490Y1213582I1193J-147D01*
G03X1081692Y1214784I1202J0D01*
G03X1081549Y1214775I4J-1202D01*
G02X1081380Y1214836I-24J198D01*
G01X1081126Y1215102D01*
X1081099Y1215191D01*
X1081102Y1215211D01*
G03X1081124Y1215452I-1280J238D01*
G03X1081102Y1215692I-1302J2D01*
G01Y1215695D01*
X1081099Y1215713D01*
X1081126Y1215802D01*
X1081380Y1216068D01*
G02X1081549Y1216129I145J-137D01*
G03X1081692Y1216120I147J1193D01*
G03X1080490Y1217322I0J1202D01*
G03X1080499Y1217179I1202J4D01*
G02X1080438Y1217010I-198J-24D01*
G01X1080172Y1216756D01*
X1080083Y1216729D01*
X1080063Y1216732D01*
G03X1079822Y1216754I-238J-1280D01*
G01X1079545D01*
G02X1079396Y1216820I0J200D01*
G01X1079168Y1217074D01*
X1079142Y1217152D01*
X1079146Y1217191D01*
X1079147Y1217193D01*
Y1217199D01*
G03X1079154Y1217321I-1195J130D01*
G01Y1217323D01*
G03X1077952Y1218524I-1202J-1D01*
G03X1077808Y1218515I3J-1202D01*
G01X1077807D01*
G02X1077639Y1218575I-24J199D01*
G01X1077385Y1218841D01*
X1077357Y1218931D01*
X1077365Y1218978D01*
G03Y1219406I-1282J214D01*
G01X1077357Y1219453D01*
X1077385Y1219543D01*
X1077639Y1219809D01*
G02X1077807Y1219869I144J-139D01*
G01X1077808D01*
G03X1077952Y1219860I147J1193D01*
G03Y1222264I0J1202D01*
G01X1077950D01*
G03X1077561Y1222199I1J-1202D01*
G02X1077531Y1222191I-66J189D01*
G01X1077517Y1222189D01*
G02X1077341Y1222246I-33J197D01*
G01X1077305Y1222282D01*
X1077278Y1222375D01*
X1077293Y1222453D01*
X1077299Y1222469D01*
G03X1077327Y1222551I-1218J462D01*
G01Y1222553D01*
G03X1077341Y1222601I-1243J389D01*
G01X1077346Y1222622D01*
Y1222623D01*
G03X1077384Y1222931I-1264J312D01*
G01Y1223210D01*
G02X1077450Y1223359I200J0D01*
G01X1077671Y1223558D01*
G02X1077825Y1223608I134J-149D01*
G01X1077826D01*
G03X1077952Y1223601I130J1195D01*
G03Y1226005I0J1202D01*
G03X1077827Y1225998I5J-1202D01*
G01X1077825D01*
G02X1077671Y1226048I-20J199D01*
G01X1077450Y1226247D01*
G02X1077384Y1226396I134J149D01*
G01Y1226673D01*
G03X1077363Y1226905I-1303J-1D01*
G01Y1226908D01*
X1077358Y1226934D01*
X1077386Y1227023D01*
X1077640Y1227289D01*
G02X1077809Y1227350I145J-137D01*
G03X1077952Y1227341I147J1193D01*
G03Y1229745I0J1202D01*
G03X1077732Y1229724I4J-1202D01*
G01X1077730D01*
G02X1077553Y1229779I-36J197D01*
G01X1077283Y1230049D01*
X1077254Y1230142D01*
X1077257Y1230160D01*
G03X1077262Y1230644I-1176J254D01*
G02X1077258Y1230682I196J40D01*
G01Y1230709D01*
X1077288Y1230782D01*
X1077553Y1231047D01*
G02X1077730Y1231102I141J-142D01*
G01X1077731D01*
G03X1077952Y1231081I224J1181D01*
G03X1079154Y1232283I0J1202D01*
G03X1079146Y1232426I-1202J4D01*
G01X1079140Y1232473D01*
X1079172Y1232561D01*
X1079471Y1232848D01*
X1079560Y1232876D01*
X1079607Y1232868D01*
G03X1079820Y1232850I216J1285D01*
G01X1079821D01*
G03X1080034Y1232868I-3J1303D01*
G01X1080036D01*
G02X1080206Y1232815I32J-197D01*
G01X1080439Y1232593D01*
G02X1080499Y1232425I-139J-144D01*
G01Y1232424D01*
G03X1080490Y1232284I1193J-147D01*
G01Y1232282D01*
G03X1081692Y1231081I1202J1D01*
G03Y1233485I0J1202D01*
G03X1081549Y1233476I4J-1202D01*
G01X1081548D01*
G02X1081380Y1233536I-24J199D01*
G01X1081126Y1233803D01*
X1081098Y1233893D01*
X1081100Y1233905D01*
G03X1081124Y1234153I-1279J249D01*
G01Y1234430D01*
G02X1081190Y1234579I200J0D01*
G01X1081411Y1234778D01*
G02X1081565Y1234828I134J-149D01*
G01X1081566D01*
G03X1081692Y1234821I130J1195D01*
G03X1082894Y1236023I0J1202D01*
G03X1082873Y1236243I-1202J-4D01*
G01Y1236245D01*
G02X1082928Y1236422I197J36D01*
G01X1083198Y1236692D01*
X1083291Y1236721D01*
X1083323Y1236715D01*
G03X1083800I239J1178D01*
G01X1083803D01*
X1083833Y1236721D01*
X1083926Y1236692D01*
X1084196Y1236422D01*
G02X1084251Y1236245I-142J-141D01*
G01Y1236243D01*
G03X1084230Y1236023I1181J-224D01*
G03X1085432Y1234821I1202J0D01*
G03X1085557Y1234828I-5J1202D01*
G01X1085559D01*
G02X1085713Y1234778I20J-199D01*
G01X1085934Y1234579D01*
G02X1086000Y1234430I-134J-149D01*
G01Y1234153D01*
G03X1086022Y1233913I1302J-2D01*
G01Y1233910D01*
X1086025Y1233892D01*
X1085998Y1233803D01*
X1085744Y1233537D01*
G02X1085575Y1233476I-145J137D01*
G03X1085432Y1233485I-147J-1193D01*
G03X1086634Y1232283I0J-1202D01*
G03X1086625Y1232426I-1202J-4D01*
G02X1086686Y1232595I198J24D01*
G01X1086952Y1232849D01*
X1087041Y1232876D01*
X1087061Y1232873D01*
G03X1087302Y1232851I238J1280D01*
G03X1087542Y1232873I2J1302D01*
G01X1087545D01*
X1087563Y1232876D01*
X1087652Y1232849D01*
X1087918Y1232595D01*
G02X1087979Y1232426I-137J-145D01*
G03X1087970Y1232283I1193J-147D01*
G03X1089172Y1233485I1202J0D01*
G03X1089029Y1233476I4J-1202D01*
G02X1088860Y1233537I-24J198D01*
G01X1088606Y1233803D01*
X1088579Y1233892D01*
X1088582Y1233912D01*
G03X1088604Y1234153I-1280J238D01*
G01Y1234430D01*
G02X1088670Y1234579I200J0D01*
G01X1088891Y1234778D01*
G02X1089045Y1234828I134J-149D01*
G01X1089046D01*
G03X1089172Y1234821I130J1195D01*
G03X1090374Y1236023I0J1202D01*
G03X1090353Y1236244I-1202J-3D01*
G01Y1236246D01*
G02X1090408Y1236423I197J36D01*
G01X1090643Y1236657D01*
G02X1090820Y1236712I141J-142D01*
G01X1090821D01*
G03X1091042Y1236691I224J1181D01*
G01X1091044D01*
G03X1091265Y1236711I3J1202D01*
G01X1091313Y1236720D01*
X1091408Y1236691D01*
X1091677Y1236422D01*
G02X1091732Y1236245I-142J-141D01*
G01Y1236243D01*
G03X1091711Y1236023I1181J-224D01*
G03X1092913Y1234821I1202J0D01*
G03X1093037Y1234828I-6J1202D01*
G01X1093039D01*
G02X1093193Y1234778I20J-199D01*
G01X1093414Y1234579D01*
G02X1093480Y1234430I-134J-149D01*
G01Y1234153D01*
G03X1093502Y1233913I1302J-2D01*
G01Y1233910D01*
X1093505Y1233892D01*
X1093478Y1233803D01*
X1093191Y1233503D01*
X1093103Y1233471D01*
X1093056Y1233477D01*
G03X1092913Y1233485I-139J-1194D01*
G03Y1231081I0J-1202D01*
G03X1094115Y1232282I0J1202D01*
G01Y1232284D01*
G03X1094107Y1232414I-1202J-9D01*
G01X1094106Y1232425D01*
Y1232428D01*
G02X1094166Y1232594I199J22D01*
G01X1094432Y1232848D01*
X1094522Y1232876D01*
X1094568Y1232868D01*
G03X1094780Y1232851I210J1285D01*
G01X1094782D01*
G03X1094995Y1232869I-3J1303D01*
G01X1094997D01*
G02X1095167Y1232817I33J-197D01*
G01X1095399Y1232595D01*
G02X1095460Y1232426I-137J-145D01*
G03X1095451Y1232283I1193J-147D01*
G03X1096653Y1233485I1202J0D01*
G03X1096509Y1233476I3J-1202D01*
G01X1096508D01*
G02X1096340Y1233536I-24J199D01*
G01X1096087Y1233802D01*
X1096059Y1233892D01*
X1096067Y1233938D01*
G03X1096084Y1234153I-1285J210D01*
G01Y1234430D01*
G02X1096150Y1234579I200J0D01*
G01X1096372Y1234778D01*
G02X1096526Y1234828I133J-149D01*
G01X1096527D01*
G03X1096653Y1234821I130J1195D01*
G03X1097855Y1236023I0J1202D01*
G03X1097834Y1236243I-1202J-4D01*
G01Y1236245D01*
G02X1097889Y1236422I197J36D01*
G01X1098158Y1236691D01*
X1098253Y1236720D01*
X1098301Y1236711D01*
G03X1098522Y1236691I218J1182D01*
G01X1098524D01*
G03X1098745Y1236711I3J1202D01*
G01X1098793Y1236720D01*
X1098888Y1236691D01*
X1099157Y1236422D01*
G02X1099212Y1236245I-142J-141D01*
G01Y1236243D01*
G03X1099191Y1236023I1181J-224D01*
G03X1100393Y1234821I1202J0D01*
G03X1100517Y1234828I-6J1202D01*
G01X1100519D01*
G02X1100673Y1234778I20J-199D01*
G01X1100894Y1234579D01*
G02X1100960Y1234430I-134J-149D01*
G01Y1234153D01*
G03X1100982Y1233913I1302J-2D01*
G01Y1233910D01*
X1100985Y1233892D01*
X1100958Y1233803D01*
X1100671Y1233503D01*
X1100583Y1233471D01*
X1100536Y1233477D01*
G03X1100393Y1233485I-139J-1194D01*
G03Y1231081I0J-1202D01*
G03X1101595Y1232282I0J1202D01*
G01Y1232284D01*
G03X1101587Y1232414I-1202J-9D01*
G01X1101586Y1232425D01*
Y1232428D01*
G02X1101646Y1232594I199J22D01*
G01X1101912Y1232848D01*
X1102002Y1232876D01*
X1102048Y1232868D01*
G03X1102260Y1232851I210J1285D01*
G01X1102262D01*
G03X1102475Y1232869I-3J1303D01*
G01X1102477D01*
G02X1102647Y1232817I33J-197D01*
G01X1102879Y1232595D01*
G02X1102940Y1232426I-137J-145D01*
G03X1102931Y1232283I1193J-147D01*
G03X1104133Y1233485I1202J0D01*
G03X1103989Y1233476I3J-1202D01*
G01X1103988D01*
G02X1103820Y1233536I-24J199D01*
G01X1103567Y1233802D01*
X1103539Y1233892D01*
X1103547Y1233938D01*
G03X1103564Y1234153I-1285J210D01*
G01Y1234430D01*
G02X1103630Y1234579I200J0D01*
G01X1103852Y1234778D01*
G02X1104006Y1234828I133J-149D01*
G01X1104007D01*
G03X1104133Y1234821I130J1195D01*
G03X1105335Y1236023I0J1202D01*
G03X1105314Y1236243I-1202J-4D01*
G01Y1236245D01*
G02X1105369Y1236422I197J36D01*
G01X1105639Y1236692D01*
X1105732Y1236721D01*
X1105764Y1236715D01*
G03X1106241I239J1178D01*
G01X1106244D01*
X1106274Y1236721D01*
X1106367Y1236692D01*
X1106637Y1236422D01*
G02X1106692Y1236245I-142J-141D01*
G01Y1236243D01*
G03X1106671Y1236023I1181J-224D01*
G03X1107873Y1234821I1202J0D01*
G03X1107997Y1234828I-6J1202D01*
G01X1107999D01*
G02X1108153Y1234778I20J-199D01*
G01X1108374Y1234579D01*
G02X1108440Y1234430I-134J-149D01*
G01Y1234153D01*
G03X1108462Y1233914I1303J-1D01*
G02X1108463Y1233908I-196J-36D01*
G01X1108466Y1233892D01*
X1108438Y1233803D01*
X1108151Y1233503D01*
X1108063Y1233471D01*
X1108016Y1233477D01*
G03X1107873Y1233485I-139J-1194D01*
G03X1109075Y1232283I0J-1202D01*
G03X1109067Y1232426I-1202J4D01*
G01X1109061Y1232473D01*
X1109093Y1232561D01*
X1109393Y1232848D01*
X1109482Y1232876D01*
X1109501Y1232873D01*
G03X1109743Y1232850I244J1280D01*
G03X1109982Y1232872I1J1303D01*
G02X1109988Y1232873I36J-196D01*
G01X1110004Y1232876D01*
X1110093Y1232848D01*
X1110393Y1232561D01*
X1110425Y1232473D01*
X1110419Y1232426D01*
G03X1110411Y1232283I1194J-139D01*
G03X1111613Y1233485I1202J0D01*
G03X1111470Y1233477I-4J-1202D01*
G01X1111423Y1233471D01*
X1111335Y1233503D01*
X1111048Y1233803D01*
X1111020Y1233892D01*
X1111023Y1233911D01*
G03X1111046Y1234153I-1280J244D01*
G01Y1234430D01*
G02X1111112Y1234579I200J0D01*
G01X1111333Y1234778D01*
G02X1111487Y1234828I134J-149D01*
G01X1111488D01*
G03X1111613Y1234821I130J1195D01*
G03Y1237225I0J1202D01*
G03X1111489Y1237218I6J-1202D01*
G01X1111487D01*
G02X1111333Y1237268I-20J199D01*
G01X1111112Y1237467D01*
G02X1111046Y1237616I134J149D01*
G01Y1237893D01*
G03X1111024Y1238132I-1303J1D01*
G02X1111023Y1238138I196J36D01*
G01X1111020Y1238154D01*
X1111048Y1238243D01*
X1111335Y1238543D01*
X1111423Y1238575D01*
X1111470Y1238569D01*
G03X1111613Y1238561I139J1194D01*
G03X1112815Y1239763I0J1202D01*
G03X1112812Y1239846I-1202J-2D01*
G02X1112865Y1239997I200J15D01*
G01X1113065Y1240210D01*
G02X1113211Y1240274I147J-136D01*
G01X1113756D01*
G02X1113902Y1240210I-1J-200D01*
G01X1114102Y1239997D01*
G02X1114155Y1239846I-147J-136D01*
G03X1114152Y1239763I1199J-85D01*
G03X1116556I1202J0D01*
G01Y1239764D01*
G03X1116527Y1240026I-1202J0D01*
G01X1116524Y1240037D01*
X1116521Y1240063D01*
G02X1116674Y1240279I199J21D01*
G03X1116770Y1240333I-46J195D01*
G01X1116832Y1240395D01*
G02X1116854Y1240414I141J-141D01*
G02X1116913Y1240444I119J-161D01*
G01X1116958Y1240458D01*
X1117007Y1240449D01*
G03X1117629Y1240501I214J1182D01*
G02X1117839Y1240454I68J-188D01*
G01X1117957Y1240335D01*
X1117982Y1240223D01*
X1117962Y1240168D01*
G03X1117892Y1239765I1132J-404D01*
G01Y1239763D01*
G03X1120296I1202J0D01*
G03X1120189Y1240258I-1201J-1D01*
G01X1120181Y1240276D01*
X1120173Y1240313D01*
G02X1120226Y1240499I195J45D01*
G01X1120263Y1240536D01*
X1120361Y1240564D01*
X1120444Y1240545D01*
X1120462Y1240537D01*
G03X1120520Y1240513I489J1099D01*
G01X1120522D01*
G03X1120772Y1240446I434J1121D01*
G01X1120773D01*
X1120788Y1240444D01*
G03X1120963Y1240431I176J1189D01*
G01X1120989D01*
G03X1121269Y1240470I-25J1202D01*
G03X1121465Y1240540I-305J1163D01*
G01X1121483Y1240548D01*
X1121518Y1240556D01*
G02X1121703Y1240504I45J-195D01*
G01X1121740Y1240467D01*
X1121769Y1240368D01*
X1121750Y1240283D01*
X1121741Y1240263D01*
Y1240262D01*
G03X1121632Y1239763I1093J-500D01*
G03X1124036I1202J0D01*
G03X1123918Y1240281I-1202J-1D01*
G02X1124185Y1240548I180J87D01*
G01X1124186D01*
G03X1124209Y1240537I530J1079D01*
G03X1125109Y1240501I495J1095D01*
G02X1125319Y1240454I68J-188D01*
G01X1125437Y1240335D01*
X1125462Y1240223D01*
X1125442Y1240168D01*
G03X1125372Y1239765I1132J-404D01*
G01Y1239763D01*
G03X1127776I1202J0D01*
G03X1127669Y1240258I-1201J-1D01*
G01X1127661Y1240276D01*
X1127653Y1240313D01*
G02X1127706Y1240499I195J45D01*
G01X1127743Y1240536D01*
X1127841Y1240564D01*
X1127924Y1240545D01*
X1127942Y1240537D01*
G03X1128000Y1240513I489J1099D01*
G01X1128002D01*
G03X1128252Y1240446I434J1121D01*
G01X1128253D01*
X1128268Y1240444D01*
G03X1128443Y1240431I176J1189D01*
G01X1128469D01*
G03X1128749Y1240470I-25J1202D01*
G03X1128945Y1240540I-305J1163D01*
G01X1128963Y1240548D01*
X1128998Y1240556D01*
G02X1129183Y1240504I45J-195D01*
G01X1129220Y1240467D01*
X1129249Y1240368D01*
X1129230Y1240283D01*
X1129221Y1240263D01*
Y1240262D01*
G03X1129112Y1239763I1093J-500D01*
G03X1131516I1202J0D01*
G03X1131398Y1240282I-1202J0D01*
G02X1131663Y1240549I181J86D01*
G03X1131689Y1240538I481J1102D01*
G02X1131691Y1240536I-131J-133D01*
G03X1132677I493J1096D01*
G02X1132679Y1240538I133J-131D01*
G03X1132705Y1240549I-455J1113D01*
G02X1132970Y1240282I84J-181D01*
G03X1132852Y1239763I1084J-519D01*
G03X1135256I1202J0D01*
G03X1135238Y1239967I-1202J-3D01*
G01X1135235Y1239984D01*
Y1239985D01*
G02X1135290Y1240162I197J36D01*
G01X1135522Y1240396D01*
G02X1135699Y1240452I142J-141D01*
G03X1135741Y1240445I219J1183D01*
G01X1135755Y1240443D01*
G03X1135924Y1240431I169J1190D01*
G01X1135925D01*
G03X1136160Y1240454I1J1200D01*
G01X1136162D01*
X1136195Y1240460D01*
X1136290Y1240431D01*
X1136559Y1240162D01*
G02X1136614Y1239985I-142J-141D01*
G01Y1239983D01*
G03X1136593Y1239763I1181J-224D01*
G03X1137795Y1238561I1202J0D01*
G03X1137938Y1238569I4J1202D01*
G01X1137985Y1238575D01*
X1138073Y1238543D01*
X1138360Y1238243D01*
X1138388Y1238154D01*
X1138385Y1238135D01*
G03X1138362Y1237893I1280J-244D01*
G01Y1237616D01*
G02X1138296Y1237467I-200J0D01*
G01X1138075Y1237268D01*
G02X1137921Y1237218I-134J149D01*
G01X1137920D01*
G03X1137795Y1237225I-130J-1195D01*
G03Y1234821I0J-1202D01*
G03X1137919Y1234828I-6J1202D01*
G01X1137921D01*
G02X1138075Y1234778I20J-199D01*
G01X1138296Y1234579D01*
G02X1138362Y1234430I-134J-149D01*
G01Y1234153D01*
G03X1138384Y1233914I1303J-1D01*
G02X1138385Y1233908I-196J-36D01*
G01X1138388Y1233892D01*
X1138360Y1233803D01*
X1138073Y1233503D01*
X1137985Y1233471D01*
X1137938Y1233477D01*
G03X1137795Y1233485I-139J-1194D01*
G03X1138997Y1232283I0J-1202D01*
G03X1138989Y1232426I-1202J4D01*
G01X1138983Y1232473D01*
X1139015Y1232561D01*
X1139315Y1232848D01*
X1139404Y1232876D01*
X1139423Y1232873D01*
G03X1139665Y1232850I244J1280D01*
G03X1139904Y1232872I1J1303D01*
G02X1139910Y1232873I36J-196D01*
G01X1139926Y1232876D01*
X1140015Y1232848D01*
X1140315Y1232561D01*
X1140347Y1232473D01*
X1140341Y1232426D01*
G03X1140333Y1232283I1194J-139D01*
G03X1141535Y1233485I1202J0D01*
G03X1141392Y1233477I-4J-1202D01*
G01X1141345Y1233471D01*
X1141257Y1233503D01*
X1140970Y1233803D01*
X1140942Y1233892D01*
X1140945Y1233911D01*
G03X1140968Y1234153I-1280J244D01*
G01Y1234430D01*
G02X1141034Y1234579I200J0D01*
G01X1141255Y1234778D01*
G02X1141409Y1234828I134J-149D01*
G01X1141410D01*
G03X1141535Y1234821I130J1195D01*
G03X1142737Y1236023I0J1202D01*
G03X1142716Y1236243I-1202J-4D01*
G01Y1236245D01*
G02X1142771Y1236422I197J36D01*
G01X1143040Y1236692D01*
X1143133Y1236721D01*
X1143166Y1236715D01*
G03X1143405Y1236691I239J1178D01*
G01X1143417D01*
G03X1143616Y1236710I-14J1202D01*
G01X1143618D01*
G03X1143655Y1236717I-205J1185D01*
G01X1143675Y1236721D01*
X1143770Y1236692D01*
X1144074Y1236388D01*
X1144103Y1236295D01*
X1144096Y1236254D01*
X1144095Y1236252D01*
X1144094Y1236242D01*
G03X1144073Y1236023I1181J-224D01*
G03X1145275Y1237225I1202J0D01*
G03X1144757Y1237107I1J-1202D01*
G02X1144490Y1237374I-87J180D01*
G03X1144548Y1237518I-1084J520D01*
G03X1144558Y1237550I-1143J375D01*
G01X1144565Y1237575D01*
G03X1144607Y1237833I-1159J321D01*
G01Y1237835D01*
X1144609Y1237867D01*
G02X1144628Y1237918I195J-44D01*
G01X1144674Y1237985D01*
X1144678Y1237991D01*
X1144713Y1238041D01*
G02X1144744Y1238071I154J-128D01*
G01X1144761Y1238085D01*
X1144794Y1238098D01*
G03X1145771Y1238662I-1389J3535D01*
G02X1145807Y1238685I125J-156D01*
G03X1146353Y1239231I-532J1078D01*
G02X1146376Y1239267I179J-89D01*
G03X1146582Y1239552I-2972J2365D01*
G03X1147115Y1240824I-3178J2079D01*
G01X1147116Y1240827D01*
X1147117Y1240831D01*
X1147124Y1240857D01*
G02X1147184Y1240941I187J-70D01*
G01X1147210Y1240962D01*
X1147241Y1240973D01*
G02X1147309Y1240985I68J-188D01*
G01X1147640D01*
G02X1147814Y1240884I0J-200D01*
G01X1148012Y1240534D01*
X1148011Y1240427D01*
X1147983Y1240380D01*
G03X1147813Y1239764I1032J-616D01*
G01Y1239763D01*
G03X1149015Y1238561I1202J0D01*
G03X1149157Y1238569I3J1202D01*
G01X1149158D01*
G02X1149326Y1238509I24J-199D01*
G01X1149580Y1238244D01*
X1149608Y1238155D01*
X1149603Y1238127D01*
G03X1149582Y1237895I1283J-233D01*
G01Y1237616D01*
G02X1149516Y1237467I-200J0D01*
G01X1149295Y1237268D01*
G02X1149141Y1237218I-134J149D01*
G01X1149140D01*
G03X1149015Y1237225I-130J-1195D01*
G03Y1234821I0J-1202D01*
G03X1149139Y1234828I-6J1202D01*
G01X1149141D01*
G02X1149295Y1234778I20J-199D01*
G01X1149516Y1234579D01*
G02X1149582Y1234430I-134J-149D01*
G01Y1234153D01*
G03X1149603Y1233921I1303J1D01*
G01Y1233918D01*
X1149608Y1233892D01*
X1149580Y1233803D01*
X1149293Y1233503D01*
X1149205Y1233471D01*
X1149158Y1233477D01*
G03X1149015Y1233485I-139J-1194D01*
G03X1150217Y1232283I0J-1202D01*
G03X1150209Y1232425I-1202J3D01*
G01X1150203Y1232472D01*
X1150235Y1232560D01*
X1150535Y1232847D01*
X1150624Y1232874D01*
X1150645Y1232871D01*
G03X1150886Y1232849I239J1282D01*
G03X1151100Y1232866I4J1304D01*
G01X1151147Y1232874D01*
X1151236Y1232846D01*
X1151535Y1232560D01*
X1151567Y1232472D01*
X1151561Y1232425D01*
G03X1151553Y1232283I1194J-139D01*
G03X1152755Y1233485I1202J0D01*
G03X1152614Y1233477I-3J-1202D01*
G01X1152567Y1233471D01*
X1152479Y1233503D01*
X1152192Y1233803D01*
X1152164Y1233892D01*
X1152169Y1233920D01*
G03X1152190Y1234153I-1282J233D01*
G01Y1234430D01*
G02X1152256Y1234579I200J0D01*
G01X1152508Y1234805D01*
X1152588Y1234831D01*
X1152630Y1234827D01*
G03X1152755Y1234821I120J1196D01*
G03X1153957Y1236023I0J1202D01*
G03X1153937Y1236243I-1202J2D01*
G01X1153928Y1236292D01*
X1153957Y1236387D01*
X1154261Y1236690D01*
X1154354Y1236719D01*
X1154384Y1236714D01*
G03X1154834Y1236708I241J1177D01*
G01X1154838D01*
G03X1154846Y1236710I-287J1166D01*
G01X1154847D01*
G02X1155024Y1236655I36J-197D01*
G01X1155293Y1236387D01*
X1155322Y1236292D01*
X1155313Y1236243D01*
G03X1155293Y1236023I1182J-218D01*
G03X1156495Y1234821I1202J0D01*
G03X1156620Y1234828I-5J1202D01*
G01X1156622D01*
G02X1156776Y1234778I21J-199D01*
G01X1156998Y1234579D01*
G02X1157064Y1234430I-134J-149D01*
G01Y1234153D01*
G03X1157081Y1233938I1302J-5D01*
G01X1157089Y1233892D01*
X1157061Y1233802D01*
X1156808Y1233536D01*
G02X1156640Y1233476I-144J139D01*
G01X1156639D01*
G03X1156495Y1233485I-147J-1193D01*
G03X1157697Y1232283I0J-1202D01*
G03X1157688Y1232426I-1202J-4D01*
G02X1157749Y1232595I198J24D01*
G01X1157981Y1232817D01*
G02X1158151Y1232869I137J-145D01*
G01X1158152D01*
G03X1158366Y1232851I216J1285D01*
G01X1158368D01*
G03X1158580Y1232868I2J1302D01*
G01X1158626Y1232876D01*
X1158716Y1232848D01*
X1158982Y1232594D01*
G02X1159042Y1232428I-139J-144D01*
G01Y1232425D01*
X1159041Y1232414D01*
G03X1159033Y1232284I1194J-139D01*
G01Y1232282D01*
G03X1160235Y1231081I1202J1D01*
G03X1160760Y1231203I-3J1202D01*
G01X1160762D01*
G02X1160954Y1231193I87J-180D01*
G01X1161243Y1231013D01*
G02X1161337Y1230843I-106J-170D01*
G01Y1229983D01*
G02X1161243Y1229813I-200J0D01*
G01X1160954Y1229633D01*
G02X1160762Y1229623I-105J170D01*
G01X1160761D01*
G03X1160235Y1229745I-528J-1080D01*
G03Y1227341I0J-1202D01*
G03X1160760Y1227463I-3J1202D01*
G01X1160762D01*
G02X1160954Y1227453I87J-180D01*
G01X1161243Y1227273D01*
G02X1161337Y1227103I-106J-170D01*
G01Y1226243D01*
G02X1161243Y1226073I-200J0D01*
G01X1160954Y1225893D01*
G02X1160762Y1225883I-105J170D01*
G01X1160761D01*
G03X1160235Y1226005I-528J-1080D01*
G03Y1223601I0J-1202D01*
G03X1160760Y1223723I-3J1202D01*
G01X1160762D01*
G02X1160954Y1223713I87J-180D01*
G01X1161243Y1223533D01*
G02X1161337Y1223363I-106J-170D01*
G01Y1222502D01*
G02X1161243Y1222332I-200J0D01*
G01X1160954Y1222152D01*
G02X1160762Y1222142I-105J170D01*
G01X1160761D01*
G03X1160235Y1222264I-528J-1080D01*
G03Y1219860I0J-1202D01*
G03X1160760Y1219982I-3J1202D01*
G01X1160762D01*
G02X1160954Y1219972I87J-180D01*
G01X1161243Y1219792D01*
G02X1161337Y1219622I-106J-170D01*
G01Y1216466D01*
G02X1161275Y1216321I-200J0D01*
G03Y1214581I831J-870D01*
G01X1161305Y1214552D01*
X1161337Y1214478D01*
Y1214288D01*
G02X1161278Y1214146I-200J0D01*
G01X1160474Y1213342D01*
G03X1159969Y1212582I1631J-1631D01*
G02X1159814Y1212460I-185J76D01*
G01X1159422Y1212400D01*
X1159325Y1212437D01*
X1159291Y1212478D01*
G03X1158365Y1212914I-926J-765D01*
G03Y1210510I0J-1202D01*
G03X1159291Y1210945I0J1203D01*
G01X1159325Y1210986D01*
X1159422Y1211023D01*
X1159867Y1210954D01*
X1159949Y1210890D01*
X1159969Y1210841D01*
G03X1161234Y1209575I2136J870D01*
G02X1161356Y1209420I-76J-185D01*
G01X1161417Y1209029D01*
X1161379Y1208930D01*
X1161338Y1208897D01*
G03X1160904Y1207972I769J-925D01*
G03X1163308I1202J0D01*
G03X1162873Y1208897I-1201J0D01*
G01X1162872Y1208898D01*
G02X1162803Y1209081I129J153D01*
G01X1162864Y1209474D01*
X1162928Y1209556D01*
X1162977Y1209576D01*
G03X1163313Y1209746I-870J2136D01*
G02X1163560Y1209717I105J-170D01*
G01X1164025Y1209252D01*
G03X1164167Y1209193I142J141D01*
G01X1164875D01*
G02X1165017Y1209134I0J-200D01*
G01X1165022Y1209129D01*
G02Y1208847I-142J-141D01*
G01X1165016Y1208841D01*
X1165014Y1208840D01*
G03X1164644Y1207974I831J-867D01*
G01Y1207972D01*
G03X1165846Y1206770I1202J0D01*
G03X1166935Y1207462I0J1203D01*
G02X1167152Y1207574I181J-85D01*
G03X1167571Y1207536I417J2268D01*
G01X1168336D01*
G02X1168515Y1207427I1J-200D01*
G01Y1207426D01*
G03X1170657I1071J546D01*
G01Y1207427D01*
G02X1170836Y1207536I178J-91D01*
G01X1172076D01*
G02X1172255Y1207427I1J-200D01*
G01Y1207426D01*
G03X1174397I1071J546D01*
G01Y1207427D01*
G02X1174576Y1207536I178J-91D01*
G01X1175816D01*
G02X1175995Y1207427I1J-200D01*
G01Y1207426D01*
G03X1178137I1071J546D01*
G01Y1207427D01*
G02X1178316Y1207536I178J-91D01*
G01X1179556D01*
G02X1179735Y1207427I1J-200D01*
G01Y1207426D01*
G03X1181877I1071J546D01*
G01Y1207427D01*
G02X1182056Y1207536I178J-91D01*
G01X1183296D01*
G02X1183475Y1207427I1J-200D01*
G01Y1207426D01*
G03X1185617I1071J546D01*
G01Y1207427D01*
G02X1185796Y1207536I178J-91D01*
G01X1187037D01*
G02X1187216Y1207427I1J-200D01*
G01Y1207426D01*
G03X1189358I1071J546D01*
G01Y1207427D01*
G02X1189537Y1207536I178J-91D01*
G01X1190777D01*
G02X1190956Y1207427I1J-200D01*
G01Y1207426D01*
G03X1193098I1071J546D01*
G01Y1207427D01*
G02X1193277Y1207536I178J-91D01*
G01X1194517D01*
G02X1194696Y1207427I1J-200D01*
G01Y1207426D01*
G03X1195212Y1206906I1071J546D01*
G02X1195319Y1206746I-92J-177D01*
G03X1195553Y1205907I2298J189D01*
G01X1195572Y1205868D01*
X1195576Y1205786D01*
X1195453Y1205469D01*
G02X1195338Y1205355I-186J73D01*
G03X1194565Y1204232I429J-1123D01*
G03X1195000Y1203306I1202J-1D01*
G01X1195002D01*
Y1203305D01*
G02X1195071Y1203122I-129J-153D01*
G01X1195010Y1202729D01*
X1194946Y1202647D01*
X1194897Y1202627D01*
G03X1193631Y1201362I870J-2136D01*
G02X1193476Y1201240I-185J76D01*
G01X1193137Y1201187D01*
G02X1192954Y1201256I-30J198D01*
G01X1192953Y1201257D01*
G03X1192027Y1201693I-927J-767D01*
G03Y1199289I0J-1202D01*
G03X1192953Y1199725I-1J1203D01*
G01Y1199726D01*
X1192954D01*
G02X1193137Y1199795I153J-129D01*
G01X1193476Y1199742D01*
G02X1193631Y1199620I-30J-198D01*
G03X1194136Y1198860I2136J871D01*
G01X1194874Y1198122D01*
G02X1194933Y1197985I-141J-142D01*
G01X1194938Y1197707D01*
G02X1194886Y1197568I-200J-4D01*
G01X1194885Y1197567D01*
G03X1194565Y1196751I882J-817D01*
G03X1195767Y1195549I1202J0D01*
G03X1196836Y1196200I0J1203D01*
G01Y1196202D01*
G02X1196926Y1196289I177J-93D01*
G01X1197033Y1196340D01*
G02X1197161Y1196356I87J-180D01*
G03X1197644Y1196304I487J2254D01*
G01X1198263D01*
G02X1198441Y1196196I0J-200D01*
G03X1198895Y1195716I1067J554D01*
G02X1198994Y1195543I-101J-173D01*
G01Y1194219D01*
G02X1198895Y1194046I-200J0D01*
G03Y1191976I613J-1035D01*
G02X1198994Y1191803I-101J-173D01*
G01Y1190479D01*
G02X1198895Y1190306I-200J0D01*
G03Y1188236I613J-1035D01*
G02X1198994Y1188063I-101J-173D01*
G01Y1186739D01*
G02X1198895Y1186566I-200J0D01*
G03Y1184496I613J-1035D01*
G02X1198994Y1184323I-101J-173D01*
G01Y1182999D01*
G02X1198895Y1182826I-200J0D01*
G03Y1180756I613J-1035D01*
G02X1198994Y1180583I-101J-173D01*
G01Y1179259D01*
G02X1198895Y1179086I-200J0D01*
G03Y1177016I613J-1035D01*
G02X1198994Y1176843I-101J-173D01*
G01Y1175518D01*
G02X1198895Y1175345I-200J0D01*
G03X1198305Y1174310I613J-1035D01*
G03X1199073Y1173189I1202J0D01*
G02X1199184Y1173082I-73J-186D01*
G03X1199669Y1172369I2116J918D01*
G01X1199959Y1172079D01*
G02Y1171796I-141J-142D01*
G01X1199877Y1171714D01*
G03X1199509Y1171772I-369J-1145D01*
G01X1199507D01*
G03X1200709Y1170570I0J-1202D01*
G03X1200679Y1170836I-1203J-1D01*
G01Y1170837D01*
G02X1200732Y1171022I195J44D01*
G01X1200733D01*
G02X1201016I142J-141D01*
G01X1201229Y1170809D01*
G03X1201996Y1170302I1630J1632D01*
G02X1202110Y1170181I-76J-185D01*
G03X1203247Y1169368I1137J389D01*
G03X1204318Y1170024I0J1202D01*
G01Y1170025D01*
G02X1204497Y1170134I178J-91D01*
G01X1205738D01*
G02X1205917Y1170025I1J-200D01*
G01Y1170024D01*
G03X1208059I1071J546D01*
G01Y1170025D01*
G02X1208238Y1170134I178J-91D01*
G01X1209478D01*
G02X1209657Y1170025I1J-200D01*
G01Y1170024D01*
G03X1211799I1071J546D01*
G01Y1170025D01*
G02X1211978Y1170134I178J-91D01*
G01X1213218D01*
G02X1213397Y1170025I1J-200D01*
G01Y1170024D01*
G03X1215539I1071J546D01*
G01Y1170025D01*
G02X1215718Y1170134I178J-91D01*
G01X1216958D01*
G02X1217137Y1170025I1J-200D01*
G01Y1170024D01*
G03X1219279I1071J546D01*
G01Y1170025D01*
G02X1219458Y1170134I178J-91D01*
G01X1220698D01*
G02X1220877Y1170025I1J-200D01*
G01Y1170024D01*
G03X1223019I1071J546D01*
G01Y1170025D01*
G02X1223198Y1170134I178J-91D01*
G01X1224438D01*
G02X1224617Y1170025I1J-200D01*
G01Y1170024D01*
G03X1226759I1071J546D01*
G01Y1170025D01*
G02X1226938Y1170134I178J-91D01*
G01X1228178D01*
G02X1228357Y1170025I1J-200D01*
G01Y1170024D01*
G03X1230499I1071J546D01*
G01Y1170025D01*
G02X1230678Y1170134I178J-91D01*
G01X1231919D01*
G02X1232098Y1170025I1J-200D01*
G01Y1170024D01*
G03X1234240I1071J546D01*
G01Y1170025D01*
G02X1234419Y1170134I178J-91D01*
G01X1235659D01*
G02X1235838Y1170025I1J-200D01*
G01Y1170024D01*
G03X1237980I1071J546D01*
G01Y1170025D01*
G02X1238159Y1170134I178J-91D01*
G01X1239399D01*
G02X1239578Y1170025I1J-200D01*
G01Y1170024D01*
G03X1240649Y1169368I1071J546D01*
G01X1240650D01*
G03X1240912Y1169397I0J1202D01*
G01X1240913D01*
G02X1241098Y1169343I43J-195D01*
G01X1241623Y1168818D01*
G02X1241682Y1168676I-141J-142D01*
G01Y1168302D01*
G02X1241592Y1168135I-200J0D01*
G01X1241311Y1167951D01*
G02X1241124Y1167934I-109J167D01*
G01X1241123D01*
G03X1240649Y1168032I-475J-1104D01*
G03Y1165628I0J-1202D01*
G03X1241123Y1165726I-1J1202D01*
G01X1241124D01*
G02X1241311Y1165709I78J-184D01*
G01X1241592Y1165525D01*
G02X1241682Y1165358I-110J-167D01*
G01Y1160822D01*
G02X1241592Y1160655I-200J0D01*
G01X1241311Y1160471D01*
G02X1241124Y1160454I-109J167D01*
G01X1241123D01*
G03X1240649Y1160552I-475J-1104D01*
G03Y1158148I0J-1202D01*
G03X1241123Y1158246I-1J1202D01*
G01X1241124D01*
G02X1241311Y1158229I78J-184D01*
G01X1241592Y1158045D01*
G02X1241682Y1157878I-110J-167D01*
G01Y1157082D01*
G02X1241592Y1156915I-200J0D01*
G01X1241311Y1156731D01*
G02X1241124Y1156714I-109J167D01*
G01X1241123D01*
G03X1240649Y1156812I-475J-1104D01*
G03Y1154408I0J-1202D01*
G03X1241123Y1154506I-1J1202D01*
G01X1241124D01*
G02X1241311Y1154489I78J-184D01*
G01X1241592Y1154305D01*
G02X1241682Y1154138I-110J-167D01*
G01Y1153342D01*
G02X1241592Y1153175I-200J0D01*
G01X1241311Y1152991D01*
G02X1241124Y1152974I-109J167D01*
G01X1241123D01*
G03X1240649Y1153072I-475J-1104D01*
G03Y1150668I0J-1202D01*
G03X1241123Y1150766I-1J1202D01*
G01X1241124D01*
G02X1241311Y1150749I78J-184D01*
G01X1241592Y1150565D01*
G02X1241682Y1150398I-110J-167D01*
G01Y1149601D01*
G02X1241592Y1149434I-200J0D01*
G01X1241311Y1149250D01*
G02X1241124Y1149233I-109J167D01*
G01X1241123D01*
G03X1240649Y1149331I-475J-1104D01*
G03Y1146927I0J-1202D01*
G03X1241123Y1147025I-1J1202D01*
G01X1241124D01*
G02X1241311Y1147008I78J-184D01*
G01X1241592Y1146824D01*
G02X1241682Y1146657I-110J-167D01*
G01Y1145861D01*
G02X1241592Y1145694I-200J0D01*
G01X1241311Y1145510D01*
G02X1241124Y1145493I-109J167D01*
G01X1241123D01*
G03X1240649Y1145591I-475J-1104D01*
G03Y1143187I0J-1202D01*
G03X1241123Y1143285I-1J1202D01*
G01X1241124D01*
G02X1241311Y1143268I78J-184D01*
G01X1241592Y1143084D01*
G02X1241682Y1142917I-110J-167D01*
G01Y1142121D01*
G02X1241592Y1141954I-200J0D01*
G01X1241311Y1141770D01*
G02X1241124Y1141753I-109J167D01*
G01X1241123D01*
G03X1240649Y1141851I-475J-1104D01*
G03Y1139447I0J-1202D01*
G03X1241123Y1139545I-1J1202D01*
G01X1241124D01*
G02X1241311Y1139528I78J-184D01*
G01X1241592Y1139344D01*
G02X1241682Y1139177I-110J-167D01*
G01Y1139019D01*
X1241629Y1138927D01*
X1241592Y1138906D01*
G02X1241587Y1138903I-105J170D01*
G03X1241540Y1138868I95J-176D01*
G01X1240837Y1138165D01*
G02X1240801Y1138137I-140J143D01*
G02X1240787Y1138130I-97J176D01*
G01X1240737Y1138110D01*
X1240688D01*
G03X1240650Y1138111I-51J-1200D01*
G01X1240648D01*
G03X1239589Y1137476I1J-1202D01*
G01Y1137475D01*
G02X1239412Y1137370I-176J95D01*
G01X1238146D01*
G02X1237969Y1137475I-1J200D01*
G01Y1137476D01*
G03X1235849I-1060J-567D01*
G01Y1137475D01*
G02X1235672Y1137370I-176J95D01*
G01X1234430D01*
G02X1234273Y1137445I-1J200D01*
G03X1234197Y1137538I-3001J-2375D01*
G02X1234181Y1137559I151J131D01*
G03X1233950Y1137823I-1011J-651D01*
G03X1233819Y1137921I-784J-912D01*
G02X1233796Y1137937I102J172D01*
G03X1231298Y1138866I-2499J-2898D01*
G01X1230253D01*
G03X1229469Y1138785I-1J-3826D01*
G02X1229387I-41J196D01*
G03X1228603Y1138866I-783J-3745D01*
G01X1227558D01*
G03X1225058Y1137935I2J-3826D01*
G02X1225036Y1137919I-128J154D01*
G03X1224678Y1137561I652J-1010D01*
G02X1224662Y1137539I-170J106D01*
G03X1224094Y1136667I2893J-2505D01*
G02X1224002Y1136573I-181J85D01*
G03X1223850Y1136494I1675J-3409D01*
G01X1223847Y1136492D01*
X1223837Y1136487D01*
X1223787Y1136465D01*
X1223769Y1136461D01*
X1223735Y1136462D01*
G02X1223670Y1136477I12J200D01*
G01X1223563Y1136541D01*
X1223561D01*
X1223328Y1136686D01*
G02X1223280Y1136739I122J158D01*
G01X1223273Y1136752D01*
X1223267Y1136764D01*
G02X1223249Y1136854I182J83D01*
G01X1223250Y1136866D01*
X1223251Y1136902D01*
Y1136909D01*
G03X1221949Y1138212I-1303J0D01*
G01X1218208D01*
G03X1216905Y1136909I0J-1303D01*
G03X1216927Y1136670I1303J-1D01*
G02X1216928Y1136664I-196J-36D01*
G01X1216931Y1136648D01*
X1216903Y1136559D01*
X1216616Y1136259D01*
X1216528Y1136227D01*
X1216481Y1136233D01*
G03X1216338Y1136241I-139J-1194D01*
G03X1217540Y1135039I0J-1202D01*
G03X1217532Y1135182I-1202J4D01*
G01X1217526Y1135229D01*
X1217558Y1135317D01*
X1217858Y1135604D01*
X1217947Y1135632D01*
X1217966Y1135629D01*
G03X1218208Y1135606I244J1280D01*
G01X1218485D01*
G02X1218634Y1135540I0J-200D01*
G01X1218862Y1135286D01*
X1218888Y1135208D01*
X1218884Y1135169D01*
X1218883Y1135167D01*
Y1135161D01*
G03X1218876Y1135040I1195J-130D01*
G01Y1135038D01*
G03X1220078Y1133837I1202J1D01*
G03X1220298Y1133858I-4J1202D01*
G01X1220300D01*
G02X1220477Y1133803I36J-197D01*
G01X1220711Y1133569D01*
G02X1220766Y1133394I-142J-141D01*
G01Y1133393D01*
G03X1220758Y1133341I1184J-209D01*
G01Y1133340D01*
X1220751Y1133289D01*
G03X1220745Y1133169I1197J-120D01*
G01Y1133167D01*
G03X1220765Y1132947I1203J-2D01*
G01X1220774Y1132899D01*
X1220745Y1132804D01*
X1220443Y1132501D01*
X1220348Y1132472D01*
X1220299Y1132481D01*
G03X1220078Y1132501I-218J-1182D01*
G03X1218876Y1131299I0J-1202D01*
G03X1218883Y1131174I1202J5D01*
G01Y1131172D01*
G02X1218833Y1131018I-199J-21D01*
G01X1218634Y1130796D01*
G02X1218485Y1130730I-149J134D01*
G01X1218208D01*
G03X1217993Y1130713I-5J-1302D01*
G01X1217947Y1130705D01*
X1217857Y1130733D01*
X1217591Y1130986D01*
G02X1217531Y1131154I139J144D01*
G01Y1131155D01*
G03X1217540Y1131299I-1193J147D01*
G03X1216338Y1130097I-1202J0D01*
G03X1216481Y1130106I-4J1202D01*
G02X1216650Y1130045I24J-198D01*
G01X1216872Y1129813D01*
G02X1216924Y1129643I-145J-137D01*
G01Y1129642D01*
G03X1216906Y1129428I1285J-216D01*
G01Y1129426D01*
G03X1216923Y1129214I1302J-2D01*
G01X1216931Y1129168D01*
X1216903Y1129078D01*
X1216649Y1128812D01*
G02X1216483Y1128752I-144J139D01*
G01X1216481D01*
G03X1216338Y1128761I-147J-1193D01*
G03X1217540Y1127559I0J-1202D01*
G03X1217532Y1127702I-1202J4D01*
G01X1217526Y1127749D01*
X1217558Y1127837D01*
X1217858Y1128124D01*
X1217947Y1128151D01*
X1217967Y1128148D01*
G03X1218208Y1128126I238J1280D01*
G01X1218485D01*
G02X1218634Y1128060I0J-200D01*
G01X1218862Y1127806D01*
X1218888Y1127728D01*
X1218884Y1127689D01*
X1218883Y1127687D01*
Y1127681D01*
G03X1218876Y1127560I1195J-130D01*
G01Y1127558D01*
G03X1220078Y1126357I1202J1D01*
G03X1220299Y1126378I-3J1202D01*
G01X1220301D01*
G02X1220478Y1126323I36J-197D01*
G01X1220712Y1126088D01*
G02X1220767Y1125911I-142J-141D01*
G01Y1125910D01*
G03Y1125467I1181J-221D01*
G01Y1125466D01*
G02X1220712Y1125289I-197J-36D01*
G01X1220477Y1125054D01*
G02X1220300Y1124999I-141J142D01*
G01X1220299D01*
G03X1220078Y1125020I-224J-1181D01*
G03X1218876Y1123819I0J-1202D01*
G01Y1123817D01*
G03X1218882Y1123703I1202J6D01*
G01X1218883Y1123693D01*
Y1123691D01*
G02X1218833Y1123537I-199J-20D01*
G01X1218634Y1123316D01*
G02X1218485Y1123250I-149J134D01*
G01X1218208D01*
G03X1217968Y1123228I-2J-1302D01*
G01X1217965D01*
X1217947Y1123225D01*
X1217858Y1123252D01*
X1217592Y1123506D01*
G02X1217531Y1123675I137J145D01*
G03X1217540Y1123818I-1193J147D01*
G03X1216338Y1122616I-1202J0D01*
G03X1216481Y1122625I-4J1202D01*
G02X1216650Y1122564I24J-198D01*
G01X1216904Y1122298D01*
X1216931Y1122209D01*
X1216928Y1122189D01*
G03X1216906Y1121948I1280J-238D01*
G03X1216928Y1121708I1302J-2D01*
G01Y1121705D01*
X1216931Y1121687D01*
X1216904Y1121598D01*
X1216650Y1121332D01*
G02X1216481Y1121271I-145J137D01*
G03X1216338Y1121280I-147J-1193D01*
G03X1217540Y1120078I0J-1202D01*
G03X1217531Y1120221I-1202J-4D01*
G02X1217592Y1120390I198J24D01*
G01X1217858Y1120644D01*
X1217947Y1120671D01*
X1217967Y1120668D01*
G03X1218208Y1120646I238J1280D01*
G01X1218485D01*
G02X1218634Y1120580I0J-200D01*
G01X1218862Y1120326D01*
X1218888Y1120248D01*
X1218884Y1120209D01*
X1218883Y1120207D01*
Y1120201D01*
G03X1218876Y1120079I1195J-130D01*
G01Y1120077D01*
G03X1220078Y1118876I1202J1D01*
G03X1220298Y1118897I-4J1202D01*
G01X1220300D01*
G02X1220477Y1118842I36J-197D01*
G01X1220747Y1118572D01*
X1220776Y1118479D01*
X1220770Y1118447D01*
G03Y1117970I1178J-239D01*
G01Y1117967D01*
X1220776Y1117937D01*
X1220747Y1117844D01*
X1220477Y1117574D01*
G02X1220300Y1117519I-141J142D01*
G01X1220299D01*
G03X1220078Y1117540I-224J-1181D01*
G03X1218876Y1116339I0J-1202D01*
G01Y1116337D01*
G03X1218882Y1116223I1202J6D01*
G01X1218883Y1116213D01*
Y1116211D01*
G02X1218833Y1116057I-199J-20D01*
G01X1218634Y1115836D01*
G02X1218485Y1115770I-149J134D01*
G01X1218208D01*
G03X1217968Y1115748I-2J-1302D01*
G01X1217965D01*
X1217947Y1115745D01*
X1217858Y1115772D01*
X1217592Y1116026D01*
G02X1217531Y1116195I137J145D01*
G03X1217540Y1116338I-1193J147D01*
G03X1216338Y1115136I-1202J0D01*
G03X1216481Y1115145I-4J1202D01*
G02X1216650Y1115084I24J-198D01*
G01X1216904Y1114818D01*
X1216931Y1114729D01*
X1216928Y1114709D01*
G03X1216906Y1114468I1280J-238D01*
G03X1216928Y1114228I1302J-2D01*
G01Y1114225D01*
X1216931Y1114207D01*
X1216904Y1114118D01*
X1216650Y1113852D01*
G02X1216481Y1113791I-145J137D01*
G03X1216338Y1113800I-147J-1193D01*
G03X1217540Y1112598I0J-1202D01*
G03X1217531Y1112741I-1202J-4D01*
G02X1217592Y1112910I198J24D01*
G01X1217858Y1113164D01*
X1217947Y1113191D01*
X1217967Y1113188D01*
G03X1218208Y1113166I238J1280D01*
G01X1218485D01*
G02X1218634Y1113100I0J-200D01*
G01X1218862Y1112846D01*
X1218888Y1112768D01*
X1218884Y1112729D01*
X1218883Y1112727D01*
Y1112721D01*
G03X1218876Y1112599I1195J-130D01*
G01Y1112597D01*
G03X1220078Y1111396I1202J1D01*
G03X1220298Y1111417I-4J1202D01*
G01X1220300D01*
G02X1220477Y1111362I36J-197D01*
G01X1220712Y1111127D01*
G02X1220767Y1110950I-142J-141D01*
G01Y1110949D01*
G03Y1110506I1181J-221D01*
G01Y1110505D01*
G02X1220712Y1110328I-197J-36D01*
G01X1220477Y1110093D01*
G02X1220300Y1110038I-141J142D01*
G01X1220299D01*
G03X1220077Y1110059I-224J-1181D01*
G03Y1107655I0J-1202D01*
G01X1220079D01*
G03X1220291Y1107674I-1J1202D01*
G01X1220340Y1107683D01*
X1220433Y1107654D01*
X1220735Y1107350D01*
X1220764Y1107257D01*
X1220755Y1107208D01*
G03X1220739Y1106891I1183J-219D01*
G01Y1106889D01*
G03X1220756Y1106769I1198J109D01*
G01Y1106767D01*
G02X1220701Y1106590I-197J-36D01*
G01X1220434Y1106321D01*
X1220340Y1106291D01*
X1220292Y1106300D01*
G03X1220080Y1106319I-213J-1183D01*
G01X1220078D01*
G03Y1103915I0J-1202D01*
G03X1220291Y1103934I0J1202D01*
G02X1220469Y1103878I36J-197D01*
G01X1220701Y1103645D01*
G02X1220756Y1103470I-142J-141D01*
G01Y1103469D01*
G03X1220736Y1103251I1183J-218D01*
G01Y1103250D01*
G03X1220757Y1103026I1203J0D01*
G01X1220766Y1102978D01*
X1220738Y1102883D01*
X1220435Y1102579D01*
X1220342Y1102550D01*
X1220293Y1102559D01*
G03X1220078Y1102578I-213J-1183D01*
G03Y1100174I0J-1202D01*
G03X1220298Y1100195I-4J1202D01*
G01X1220300D01*
G02X1220477Y1100140I36J-197D01*
G01X1220746Y1099872D01*
X1220775Y1099777D01*
X1220766Y1099728D01*
G03X1220746Y1099514I1182J-218D01*
G03X1220751Y1099400I1202J-4D01*
G01Y1099398D01*
G03X1220766Y1099285I1198J102D01*
G01X1220775Y1099237D01*
X1220746Y1099142D01*
X1220477Y1098873D01*
G02X1220300Y1098818I-141J142D01*
G01X1220299D01*
G03X1220078Y1098839I-224J-1181D01*
G03X1218876Y1097638I0J-1202D01*
G01Y1097636D01*
G03X1218885Y1097496I1202J7D01*
G01Y1097495D01*
G02X1218825Y1097327I-199J-24D01*
G01X1218592Y1097105D01*
G02X1218422Y1097052I-138J144D01*
G01X1218421D01*
G03X1218207Y1097070I-216J-1285D01*
G03X1217968Y1097048I-1J-1303D01*
G02X1217962Y1097047I-36J196D01*
G01X1217946Y1097044D01*
X1217857Y1097072D01*
X1217557Y1097359D01*
X1217525Y1097447D01*
X1217531Y1097494D01*
G03X1217539Y1097637I-1194J139D01*
G03X1216337Y1096435I-1202J0D01*
G03X1216480Y1096443I4J1202D01*
G01X1216527Y1096449D01*
X1216615Y1096417D01*
X1216902Y1096117D01*
X1216930Y1096028D01*
X1216927Y1096009D01*
G03X1216904Y1095767I1280J-244D01*
G01Y1095490D01*
G02X1216838Y1095341I-200J0D01*
G01X1216617Y1095142D01*
G02X1216463Y1095092I-134J149D01*
G01X1216462D01*
G03X1216337Y1095099I-130J-1195D01*
G03X1215135Y1093897I0J-1202D01*
G03X1215156Y1093677I1202J4D01*
G01Y1093675D01*
G02X1215101Y1093498I-197J-36D01*
G01X1214833Y1093229D01*
X1214738Y1093200D01*
X1214689Y1093209D01*
G03X1214459Y1093229I-219J-1182D01*
G03X1214376Y1093225I16J-1202D01*
G01X1214374D01*
G03X1214246Y1093209I85J-1199D01*
G01X1214198Y1093200D01*
X1214103Y1093229D01*
X1213834Y1093498D01*
G02X1213779Y1093675I142J141D01*
G01Y1093677D01*
G03X1213800Y1093897I-1181J224D01*
G03X1212598Y1095099I-1202J0D01*
G03X1212474Y1095092I6J-1202D01*
G01X1212472D01*
G02X1212318Y1095142I-20J199D01*
G01X1212097Y1095341D01*
G02X1212031Y1095490I134J149D01*
G01Y1095667D01*
G03X1212030Y1095689I-1302J-48D01*
G01Y1095767D01*
G03X1212006Y1096013I-1303J-3D01*
G01Y1096017D01*
X1212004Y1096027D01*
X1212032Y1096117D01*
X1212286Y1096384D01*
G02X1212454Y1096444I144J-139D01*
G01X1212455D01*
G03X1212598Y1096435I147J1193D01*
G03Y1098839I0J1202D01*
G03X1211396Y1097638I0J-1202D01*
G01Y1097636D01*
G03X1211405Y1097496I1202J7D01*
G01Y1097495D01*
G02X1211345Y1097327I-199J-24D01*
G01X1211112Y1097105D01*
G02X1210942Y1097052I-138J144D01*
G01X1210941D01*
G03X1210727Y1097070I-216J-1285D01*
G03X1210488Y1097048I-1J-1303D01*
G02X1210482Y1097047I-36J196D01*
G01X1210466Y1097044D01*
X1210377Y1097072D01*
X1210077Y1097359D01*
X1210045Y1097447D01*
X1210051Y1097494D01*
G03X1210059Y1097637I-1194J139D01*
G03X1208857Y1096435I-1202J0D01*
G03X1209000Y1096443I4J1202D01*
G01X1209047Y1096449D01*
X1209135Y1096417D01*
X1209422Y1096117D01*
X1209450Y1096028D01*
X1209447Y1096009D01*
G03X1209424Y1095767I1280J-244D01*
G01Y1095490D01*
G02X1209358Y1095341I-200J0D01*
G01X1209137Y1095142D01*
G02X1208983Y1095092I-134J149D01*
G01X1208982D01*
G03X1208857Y1095099I-130J-1195D01*
G03X1207655Y1093897I0J-1202D01*
G03X1207676Y1093677I1202J4D01*
G01Y1093675D01*
G02X1207621Y1093498I-197J-36D01*
G01X1207351Y1093228D01*
X1207258Y1093199D01*
X1207226Y1093205D01*
G03X1206749I-239J-1178D01*
G01X1206746D01*
X1206716Y1093199D01*
X1206623Y1093228D01*
X1206353Y1093498D01*
G02X1206298Y1093675I142J141D01*
G01Y1093677D01*
G03X1206319Y1093897I-1181J224D01*
G03X1205117Y1095099I-1202J0D01*
G03X1204991Y1095093I-6J-1202D01*
G01X1204949Y1095089D01*
X1204869Y1095115D01*
X1204617Y1095342D01*
G02X1204551Y1095491I134J149D01*
G01Y1095667D01*
G03X1204550Y1095689I-1302J-48D01*
G01Y1095767D01*
G03X1204528Y1096006I-1303J1D01*
G02X1204527Y1096012I196J36D01*
G01X1204524Y1096028D01*
X1204552Y1096117D01*
X1204839Y1096417D01*
X1204927Y1096449D01*
X1204974Y1096443D01*
G03X1205117Y1096435I139J1194D01*
G03X1203915Y1097637I0J1202D01*
G03X1203923Y1097494I1202J-4D01*
G01X1203929Y1097447D01*
X1203897Y1097359D01*
X1203597Y1097072D01*
X1203508Y1097044D01*
X1203489Y1097047D01*
G03X1203247Y1097070I-244J-1280D01*
G03X1203034Y1097052I3J-1303D01*
G01X1203032D01*
G02X1202862Y1097105I-32J197D01*
G01X1202629Y1097327D01*
G02X1202569Y1097495I139J144D01*
G01Y1097496D01*
G03X1202578Y1097636I-1193J147D01*
G01Y1097638D01*
G03X1201376Y1098839I-1202J-1D01*
G03Y1096435I0J-1202D01*
G03X1201519Y1096444I-4J1202D01*
G01X1201520D01*
G02X1201688Y1096384I24J-199D01*
G01X1201942Y1096117D01*
X1201970Y1096027D01*
X1201968Y1096015D01*
G03X1201944Y1095767I1279J-249D01*
G01Y1095490D01*
G02X1201878Y1095341I-200J0D01*
G01X1201657Y1095142D01*
G02X1201503Y1095092I-134J149D01*
G01X1201502D01*
G03X1201376Y1095099I-130J-1195D01*
G03X1200174Y1093897I0J-1202D01*
G03X1200195Y1093677I1202J4D01*
G01Y1093675D01*
G02X1200140Y1093498I-197J-36D01*
G01X1199872Y1093229D01*
X1199777Y1093200D01*
X1199728Y1093209D01*
G03X1199498Y1093229I-219J-1182D01*
G03X1199415Y1093225I16J-1202D01*
G01X1199413D01*
G03X1199285Y1093209I85J-1199D01*
G01X1199237Y1093200D01*
X1199142Y1093229D01*
X1198873Y1093498D01*
G02X1198818Y1093675I142J141D01*
G01Y1093677D01*
G03X1198839Y1093897I-1181J224D01*
G03X1197637Y1095099I-1202J0D01*
G03X1197513Y1095092I6J-1202D01*
G01X1197511D01*
G02X1197357Y1095142I-20J199D01*
G01X1197136Y1095341D01*
G02X1197070Y1095490I134J149D01*
G01Y1095731D01*
G03X1197069Y1095758I-1303J-35D01*
G37*
G36*
G01X1154193Y54588D02*
X1182695D01*
X1183133Y54150D01*
Y53029D01*
X1182695Y52591D01*
X1154193D01*
G03X1148256Y46654I0J-5937D01*
G01Y7874D01*
G02X1142382Y2000I-5874J0D01*
G01X1095138D01*
G02X1089264Y7874I0J5874D01*
G01Y46558D01*
X1091262D01*
Y7874D01*
G03X1095138Y3998I3876J0D01*
G01X1142382D01*
G03X1146258Y7874I0J3876D01*
G01Y46654D01*
G02X1154193Y54588I7935J-1D01*
G37*
G36*
G01X1302571Y1288699D02*
G03X1302398Y1288000I1329J-700D01*
G03X1303900Y1286498I1502J0D01*
G01X1303902D01*
G03X1304510Y1286627I-1J1502D01*
G01X1304557Y1286648D01*
X1304657Y1286640D01*
X1304981Y1286429D01*
G02X1305072Y1286261I-109J-168D01*
G01Y1106888D01*
G02X1304872Y1106688I-200J0D01*
G01X1295960D01*
G02X1295818Y1106747I0J200D01*
G01X1277133Y1125433D01*
G03X1275788Y1125990I-1345J-1345D01*
G03X1275143Y1125877I1J-1902D01*
G01X1275142D01*
G02X1274933Y1125924I-67J188D01*
G01X1274852Y1126005D01*
G03X1274710Y1126064I-142J-141D01*
G01X1270098D01*
G02X1269959Y1126120I0J200D01*
G01X1262311Y1133505D01*
G03X1261945Y1133817I-2725J-2826D01*
G02X1261886Y1134065I121J160D01*
G03X1262031Y1134559I-1347J664D01*
G02X1262033Y1134570I197J-30D01*
G02X1262428Y1134568I197J-34D01*
G02X1262429Y1134559I-198J-27D01*
G03X1263921Y1133227I1492J170D01*
G03Y1136231I0J1502D01*
G03X1262586Y1135417I0J-1502D01*
G02X1262408Y1135308I-178J91D01*
G01X1262052D01*
G02X1261874Y1135417I0J200D01*
G03X1260539Y1136231I-1335J-688D01*
G03X1259367Y1135669I0J-1503D01*
G01X1259320Y1135610D01*
X1259170Y1135584D01*
X1256854Y1137045D01*
G03X1255270Y1137617I-2095J-3321D01*
G01X1255232Y1137622D01*
X1255167Y1137658D01*
X1254968Y1137898D01*
G02X1254923Y1138038I155J127D01*
G03X1254926Y1138130I-1499J95D01*
G03X1251922I-1502J0D01*
G03X1251923Y1138067I1502J-8D01*
G01X1251925Y1138026D01*
X1251897Y1137950D01*
X1251668Y1137712D01*
G02X1251524Y1137650I-145J138D01*
G01X1244582D01*
G03X1244338Y1137642I7J-3926D01*
G02X1244169Y1137718I-12J200D01*
G03X1243149Y1138211I-1020J-809D01*
G01X1243147D01*
G03X1242908Y1138188I5J-1302D01*
G02X1242887Y1138185I-39J196D01*
G02X1242670Y1138375I-17J200D01*
G01Y1138582D01*
X1242684Y1138595D01*
Y1155495D01*
G02X1242743Y1155637I200J0D01*
G01X1252577Y1165472D01*
X1262412Y1175307D01*
G02X1262554Y1175366I142J-141D01*
G01X1262907D01*
G03X1263288Y1175397I4J2306D01*
G01X1263305Y1175400D01*
X1278749D01*
G03X1278891Y1175459I0J200D01*
G01X1282435Y1179003D01*
G03X1282494Y1179145I-141J142D01*
G01Y1183858D01*
G02X1282527Y1183968I200J0D01*
G03X1282908Y1185237I-1925J1270D01*
G01Y1185238D01*
G03X1281701Y1187266I-2307J0D01*
G02X1281655Y1187300I95J176D01*
G01X1278433Y1190522D01*
G03X1278291Y1190581I-142J-141D01*
G01X1262698D01*
G02X1262553Y1190644I1J200D01*
G01X1262353Y1190856D01*
G02X1262299Y1191005I146J137D01*
G03X1262302Y1191096I-1499J95D01*
G03X1259298I-1502J0D01*
G03X1259301Y1191005I1502J4D01*
G01Y1191004D01*
X1259303Y1190963D01*
X1259276Y1190887D01*
X1259047Y1190644D01*
G02X1258902Y1190581I-146J137D01*
G01X1247480D01*
G02X1247338Y1190640I0J200D01*
G01X1243336Y1194642D01*
G03X1243194Y1194701I-142J-141D01*
G01X1229906D01*
G02X1229706Y1194901I0J200D01*
G01Y1195001D01*
G03X1229031Y1196631I-2306J0D01*
G01X1228355Y1197307D01*
G02X1228362Y1197598I141J142D01*
G02X1228371Y1197605I127J-154D01*
G03X1228860Y1198621I-812J1017D01*
G03X1228206Y1199750I-1301J0D01*
G02X1228106Y1199923I100J173D01*
G01Y1201176D01*
G02X1228199Y1201345I200J0D01*
G03Y1203379I-641J1017D01*
G02X1228106Y1203548I107J169D01*
G01Y1204800D01*
G02X1228206Y1204973I200J0D01*
G03Y1207231I-648J1129D01*
G02X1228106Y1207404I100J173D01*
G01Y1208656D01*
G02X1228199Y1208825I200J0D01*
G03Y1210859I-641J1017D01*
G02X1228106Y1211028I107J169D01*
G01Y1212280D01*
G02X1228206Y1212453I200J0D01*
G03X1228860Y1213582I-647J1129D01*
G03X1228125Y1214754I-1302J0D01*
G02X1228020Y1214879I87J180D01*
G03X1227698Y1215563I-2220J-627D01*
G01X1227671Y1215602D01*
X1227658Y1215697D01*
X1227780Y1216048D01*
G02X1227910Y1216173I189J-66D01*
G03X1228760Y1217322I-352J1149D01*
G03X1227558Y1218524I-1202J0D01*
G03X1226405Y1217661I0J-1202D01*
G01Y1217660D01*
G02X1226282Y1217529I-192J57D01*
G01X1225937Y1217401D01*
X1225844Y1217411D01*
X1225804Y1217437D01*
G03X1225144Y1217730I-1254J-1936D01*
G02X1225012Y1217843I51J193D01*
G03X1223818Y1218624I-1194J-522D01*
G03X1222911Y1218256I0J-1302D01*
G02X1222771Y1218199I-140J143D01*
G01X1220976D01*
G02X1220848Y1218245I0J200D01*
G03X1219308I-770J-923D01*
G02X1219180Y1218199I-128J154D01*
G01X1217236D01*
G02X1217108Y1218245I0J200D01*
G03X1215568I-770J-923D01*
G02X1215440Y1218199I-128J154D01*
G01X1213645D01*
G02X1213505Y1218256I0J200D01*
G03X1211691I-907J-933D01*
G02X1211551Y1218199I-140J143D01*
G01X1209905D01*
G02X1209765Y1218256I0J200D01*
G03X1207951I-907J-933D01*
G02X1207811Y1218199I-140J143D01*
G01X1206164D01*
G02X1206024Y1218256I0J200D01*
G03X1204210I-907J-933D01*
G02X1204070Y1218199I-140J143D01*
G01X1204063D01*
X1203309Y1218953D01*
G03X1201679Y1219628I-1630J-1631D01*
G01X1190825D01*
G03X1189195Y1218953I0J-2306D01*
G01X1188500Y1218258D01*
G02X1188358Y1218199I-142J141D01*
G01X1165619D01*
G02X1165477Y1218258I0J200D01*
G01X1164833Y1218902D01*
G02X1164774Y1219044I141J142D01*
G01Y1219939D01*
G02X1164841Y1220089I200J1D01*
G03Y1222035I-865J973D01*
G02X1164774Y1222185I133J149D01*
G01Y1223680D01*
G02X1164841Y1223830I200J1D01*
G03Y1225776I-865J973D01*
G02X1164774Y1225926I133J149D01*
G01Y1227420D01*
G02X1164841Y1227570I200J1D01*
G03Y1229516I-865J973D01*
G02X1164774Y1229666I133J149D01*
G01Y1231298D01*
G02X1164832Y1231439I200J0D01*
G03Y1233127I-856J844D01*
G02X1164774Y1233268I142J141D01*
G01Y1235038D01*
G02X1164832Y1235179I200J0D01*
G03Y1236867I-856J844D01*
G02X1164774Y1237008I142J141D01*
G01Y1238640D01*
G02X1164841Y1238790I200J1D01*
G03Y1240736I-865J973D01*
G02X1164774Y1240886I133J149D01*
G01Y1242376D01*
G02X1164833Y1242518I200J0D01*
G01X1166087Y1243772D01*
G02X1166229Y1243831I142J-141D01*
G01X1166320D01*
G02X1166520Y1243631I0J-200D01*
G01Y1243622D01*
X1166519Y1243613D01*
G03X1166514Y1243504I1197J-110D01*
G01Y1243503D01*
G03X1167716Y1242301I1202J0D01*
G03X1168917Y1243449I0J1202D01*
G01X1168918Y1243487D01*
X1168950Y1243558D01*
X1169178Y1243776D01*
G02X1169316Y1243831I138J-145D01*
G01X1169616D01*
G02X1169782Y1243744I1J-200D01*
G01Y1243743D01*
G03X1170142Y1243288I3172J2140D01*
G02X1170190Y1243199I-146J-136D01*
G03X1171152Y1242237I1266J304D01*
G02X1171241Y1242189I-47J-194D01*
G03X1171740Y1241799I2598J2810D01*
G02X1171808Y1241725I-109J-168D01*
G03X1173769Y1239952I3388J1777D01*
G02X1173894Y1239767I-75J-185D01*
G01Y1239763D01*
G03X1176498I1302J0D01*
G01Y1239767D01*
G02X1176623Y1239952I200J0D01*
G03X1178573Y1241703I-1427J3551D01*
G01X1178593Y1241741D01*
X1178660Y1241793D01*
X1179034Y1241884D01*
X1179117Y1241869D01*
X1179152Y1241845D01*
G03X1179220Y1241799I2178J3146D01*
G02X1179288Y1241725I-109J-168D01*
G03X1181249Y1239952I3388J1777D01*
G02X1181374Y1239767I-75J-185D01*
G01Y1239763D01*
G03X1183978I1302J0D01*
G01Y1239767D01*
G02X1184103Y1239952I200J0D01*
G03X1186053Y1241704I-1427J3550D01*
G01X1186073Y1241742D01*
X1186140Y1241794D01*
X1186472Y1241875D01*
G02X1186633Y1241845I47J-194D01*
G03X1186701Y1241799I2178J3146D01*
G02X1186769Y1241725I-109J-168D01*
G03X1188730Y1239952I3388J1777D01*
G02X1188855Y1239767I-75J-185D01*
G01Y1239763D01*
G03X1191459I1302J0D01*
G01Y1239767D01*
G02X1191584Y1239952I200J0D01*
G03X1193534Y1241703I-1427J3551D01*
G01X1193554Y1241741D01*
X1193621Y1241793D01*
X1193995Y1241884D01*
X1194078Y1241869D01*
X1194113Y1241845D01*
G03X1194181Y1241799I2178J3146D01*
G02X1194249Y1241725I-109J-168D01*
G03X1196210Y1239952I3388J1777D01*
G02X1196335Y1239767I-75J-185D01*
G01Y1239763D01*
G03X1198939I1302J0D01*
G01Y1239767D01*
G02X1199064Y1239952I200J0D01*
G03X1201188Y1242076I-1427J3551D01*
G02X1201373Y1242201I185J-75D01*
G01X1201377D01*
G03X1202679Y1243503I0J1302D01*
G03X1202579Y1244003I-1302J0D01*
G02X1202622Y1244222I184J78D01*
G01X1204518Y1246118D01*
X1204632Y1246142D01*
X1204688Y1246120D01*
G03X1205116Y1246041I429J1123D01*
G01X1205117D01*
G03X1206319Y1247243I0J1202D01*
G01Y1247244D01*
G03X1206240Y1247672I-1202J-1D01*
G01X1206218Y1247728D01*
X1206242Y1247842D01*
X1207512Y1249112D01*
G03X1207571Y1249254I-141J142D01*
G01Y1249650D01*
G02X1207677Y1249827I200J0D01*
G01X1208037Y1250019D01*
X1208146Y1250013D01*
X1208192Y1249983D01*
G03X1208857Y1249782I665J1001D01*
G01X1208858D01*
G03Y1252186I0J1202D01*
G01X1208857D01*
G03X1208192Y1251985I0J-1202D01*
G01X1208146Y1251955D01*
X1208037Y1251949D01*
X1207677Y1252141D01*
G02X1207571Y1252318I94J177D01*
G01Y1253390D01*
G02X1207677Y1253567I200J0D01*
G01X1208037Y1253759D01*
X1208146Y1253753D01*
X1208192Y1253723D01*
G03X1208857Y1253522I665J1001D01*
G01X1208858D01*
G03Y1255926I0J1202D01*
G01X1208857D01*
G03X1208192Y1255725I0J-1202D01*
G01X1208146Y1255695D01*
X1208037Y1255689D01*
X1207677Y1255881D01*
G02X1207571Y1256058I94J177D01*
G01Y1258524D01*
G02X1207672Y1258698I200J0D01*
G03X1208821Y1259684I-1934J3417D01*
G02X1208895Y1259742I157J-124D01*
G01X1304267Y1303654D01*
G02X1304493Y1303613I84J-182D01*
G01X1305013Y1303093D01*
G02X1305072Y1302951I-141J-142D01*
G01Y1298903D01*
G02X1305013Y1298761I-200J0D01*
G01X1302976Y1296724D01*
G03X1302594Y1295802I924J-923D01*
G01Y1288792D01*
G02X1302571Y1288699I-200J0D01*
G37*
G36*
G01X1256555Y54588D02*
X1285191D01*
X1285226D01*
X1285275Y54539D01*
Y52675D01*
X1285191Y52591D01*
X1256555D01*
G03X1250618Y46654I0J-5937D01*
G01Y7874D01*
G02X1244744Y2000I-5874J0D01*
G01X1197500D01*
G02X1191626Y7874I0J5874D01*
G01Y46654D01*
G03X1190170Y50549I-5938J0D01*
G01Y50728D01*
X1190174Y50732D01*
X1192419D01*
X1192602Y50549D01*
G02X1193624Y46654I-6911J-3895D01*
G01Y7874D01*
G03X1197500Y3998I3876J0D01*
G01X1244744D01*
G03X1248620Y7874I0J3876D01*
G01Y46654D01*
G02X1256555Y54588I7935J-1D01*
G37*
G36*
G01X1632190Y1640016D02*
X1738420D01*
G02X1738562Y1639957I0J-200D01*
G01X1742680Y1635839D01*
G02X1742682Y1635837I-140J-142D01*
G02X1742739Y1635697I-143J-140D01*
G01Y1612726D01*
G03X1742798Y1612584I200J0D01*
G01X1745914Y1609468D01*
G02X1745973Y1609326I-141J-142D01*
G01Y1593758D01*
G03X1746032Y1593616I200J0D01*
G01X1763758Y1575890D01*
G02X1763817Y1575748I-141J-142D01*
G01Y1575709D01*
X1763814Y1575692D01*
G03X1763792Y1575436I1480J-256D01*
G01Y1575434D01*
G03X1765126Y1573942I1501J0D01*
G01X1765162Y1573938D01*
X1765226Y1573906D01*
X1765326Y1573796D01*
G03X1765330Y1573792I143J139D01*
G01X1765355Y1573767D01*
X1765384Y1573695D01*
Y1404937D01*
G02X1765261Y1404753I-200J1D01*
G01X1765204Y1404729D01*
X1765086Y1404753D01*
X1761615Y1408224D01*
G02X1761557Y1408360I142J141D01*
G01X1761446Y1412413D01*
Y1413156D01*
G03X1761148Y1414654I-3927J-2D01*
G01X1755771Y1427635D01*
G03X1754580Y1429211I-3628J-1503D01*
G01X1737185Y1442982D01*
G03X1736886Y1443196I-2432J-3082D01*
G01X1724724Y1451094D01*
G02X1724633Y1451261I109J168D01*
G01Y1601183D01*
G03X1724574Y1601325I-200J0D01*
G01X1723100Y1602799D01*
G03X1723003Y1602853I-142J-141D01*
G01X1722959Y1602863D01*
X1722924Y1602890D01*
G02X1722869Y1602956I122J158D01*
G01X1722863Y1602967D01*
Y1602968D01*
G03X1718789Y1602967I-2037J-1037D01*
G02X1718611Y1602858I-178J91D01*
G01X1716066D01*
X1716034Y1602869D01*
G03X1715718Y1602962I-1266J-3717D01*
G02X1715592Y1603058I48J194D01*
G03X1712165Y1605068I-3427J-1916D01*
G01X1712164D01*
G03X1710522Y1604708I0J-3926D01*
G02X1710499Y1604714I39J196D01*
G03X1709953Y1604817I-547J-1399D01*
G01X1709952D01*
G03X1708450Y1603315I0J-1502D01*
G01Y1603313D01*
G03X1708466Y1603098I1502J4D01*
G01X1708467Y1603090D01*
X1708468Y1603072D01*
Y1603071D01*
G02X1708415Y1602921I-200J-14D01*
G01X1708387Y1602891D01*
X1708311Y1602858D01*
X1705718D01*
G02X1705540Y1602967I0J200D01*
G03X1701466I-2037J-1037D01*
G02X1701288Y1602858I-178J91D01*
G01X1698743D01*
X1698711Y1602869D01*
G03X1698395Y1602962I-1266J-3717D01*
G02X1698269Y1603058I48J194D01*
G03X1694842Y1605068I-3427J-1916D01*
G01X1694841D01*
G03X1693199Y1604708I0J-3926D01*
G02X1693176Y1604714I39J196D01*
G03X1692630Y1604817I-547J-1399D01*
G01X1692629D01*
G03X1691127Y1603315I0J-1502D01*
G01Y1603313D01*
G03X1691143Y1603098I1502J4D01*
G01X1691144Y1603090D01*
X1691145Y1603072D01*
Y1603071D01*
G02X1691092Y1602921I-200J-14D01*
G01X1691064Y1602891D01*
X1690988Y1602858D01*
X1688396D01*
G02X1688218Y1602967I0J200D01*
G03X1684144I-2037J-1037D01*
G02X1683966Y1602858I-178J91D01*
G01X1681420D01*
X1681388Y1602869D01*
G03X1681072Y1602962I-1266J-3717D01*
G02X1680946Y1603058I48J194D01*
G03X1677519Y1605068I-3427J-1916D01*
G01X1677518D01*
G03X1675876Y1604708I0J-3926D01*
G02X1675853Y1604714I39J196D01*
G03X1675307Y1604817I-547J-1399D01*
G01X1675306D01*
G03X1673804Y1603315I0J-1502D01*
G01Y1603313D01*
G03X1673820Y1603098I1502J4D01*
G01X1673821Y1603090D01*
X1673822Y1603072D01*
Y1603071D01*
G02X1673769Y1602921I-200J-14D01*
G01X1673741Y1602891D01*
X1673665Y1602858D01*
X1671073D01*
G02X1670895Y1602967I0J200D01*
G03X1666821I-2037J-1037D01*
G02X1666643Y1602858I-178J91D01*
G01X1664097D01*
X1664065Y1602869D01*
G03X1663749Y1602962I-1266J-3717D01*
G02X1663623Y1603058I48J194D01*
G03X1660196Y1605068I-3427J-1916D01*
G01X1660195D01*
G03X1658553Y1604708I0J-3926D01*
G02X1658530Y1604714I39J196D01*
G03X1657984Y1604817I-547J-1399D01*
G01X1657983D01*
G03X1656481Y1603315I0J-1502D01*
G01Y1603313D01*
G03X1656497Y1603098I1502J4D01*
G01X1656498Y1603090D01*
X1656499Y1603072D01*
Y1603071D01*
G02X1656446Y1602921I-200J-14D01*
G01X1656418Y1602891D01*
X1656342Y1602858D01*
X1653750D01*
G02X1653572Y1602967I0J200D01*
G03X1649498I-2037J-1037D01*
G02X1649320Y1602858I-178J91D01*
G01X1648921D01*
G03X1648779Y1602799I0J-200D01*
G01X1646138Y1600158D01*
G03X1646079Y1600016I141J-142D01*
G01Y1560314D01*
G02X1646020Y1560172I-200J0D01*
G01X1628635Y1542787D01*
X1628607Y1542758D01*
X1628533Y1542728D01*
X1600460D01*
G02X1600310Y1542796I0J200D01*
G01X1600111Y1543023D01*
G02X1600063Y1543178I151J132D01*
G01Y1543181D01*
G03X1600076Y1543373I-1489J197D01*
G03X1597072I-1502J0D01*
G03X1597085Y1543181I1502J5D01*
G01Y1543178D01*
G02X1597037Y1543023I-199J-23D01*
G01X1596838Y1542796D01*
G02X1596688Y1542728I-150J132D01*
G01X1578374D01*
G02X1578232Y1542787I0J200D01*
G01X1557617Y1563402D01*
X1557588Y1563430D01*
X1557558Y1563504D01*
Y1563826D01*
G02X1557617Y1563968I200J0D01*
G03X1558172Y1565315I-1357J1347D01*
G03X1556260Y1567227I-1912J0D01*
G03X1554913Y1566672I0J-1912D01*
G02X1554771Y1566613I-142J141D01*
G01X1554489D01*
G02X1554347Y1566672I0J200D01*
G01X1549943Y1571076D01*
X1549914Y1571104D01*
X1549884Y1571178D01*
Y1571218D01*
G03X1547598Y1573507I-2286J3D01*
G03X1545833Y1572673I0J-2285D01*
G01X1545829Y1572668D01*
X1545820Y1572659D01*
G02X1545674Y1572595I-147J136D01*
G01X1542278D01*
X1542224Y1572623D01*
G02X1542187Y1572649I96J176D01*
G01X1542167Y1572666D01*
X1542153Y1572686D01*
G03X1538937Y1574360I-3216J-2252D01*
G01X1538936D01*
G03X1537292Y1573999I0J-3926D01*
G02X1537274Y1574004I45J195D01*
G03X1536726Y1574108I-549J-1398D01*
G01X1536724D01*
G03X1535231Y1572773I0J-1502D01*
G01Y1572772D01*
G02X1535033Y1572595I-199J23D01*
G01X1532199D01*
G02X1532053Y1572659I1J200D01*
G01X1532044Y1572668D01*
X1532040Y1572673D01*
G03X1528510I-1765J-1450D01*
G01X1528506Y1572668D01*
X1528497Y1572659D01*
G02X1528351Y1572595I-147J136D01*
G01X1524955D01*
X1524901Y1572623D01*
G02X1524864Y1572649I96J176D01*
G01X1524844Y1572666D01*
X1524830Y1572686D01*
G03X1521614Y1574360I-3216J-2252D01*
G01X1521613D01*
G03X1519969Y1573999I0J-3926D01*
G02X1519951Y1574004I45J195D01*
G03X1519403Y1574108I-549J-1398D01*
G01X1519401D01*
G03X1517908Y1572773I0J-1502D01*
G01Y1572772D01*
G02X1517710Y1572595I-199J23D01*
G01X1514877D01*
G02X1514731Y1572659I1J200D01*
G01X1514722Y1572668D01*
X1514718Y1572673D01*
G03X1511188I-1765J-1450D01*
G01X1511184Y1572668D01*
X1511175Y1572659D01*
G02X1511029Y1572595I-147J136D01*
G01X1507632D01*
X1507578Y1572623D01*
G02X1507541Y1572649I96J176D01*
G01X1507521Y1572666D01*
X1507507Y1572686D01*
G03X1504291Y1574360I-3216J-2252D01*
G01X1504290D01*
G03X1502646Y1573999I0J-3926D01*
G02X1502628Y1574004I45J195D01*
G03X1502080Y1574108I-549J-1398D01*
G01X1502078D01*
G03X1500585Y1572773I0J-1502D01*
G01Y1572772D01*
G02X1500387Y1572595I-199J23D01*
G01X1497554D01*
G02X1497408Y1572659I1J200D01*
G01X1497399Y1572668D01*
X1497395Y1572673D01*
G03X1493865I-1765J-1450D01*
G01X1493861Y1572668D01*
X1493852Y1572659D01*
G02X1493706Y1572595I-147J136D01*
G01X1490309D01*
X1490255Y1572623D01*
G02X1490218Y1572649I96J176D01*
G01X1490198Y1572666D01*
X1490184Y1572686D01*
G03X1486968Y1574360I-3216J-2252D01*
G01X1486967D01*
G03X1485323Y1573999I0J-3926D01*
G02X1485305Y1574004I45J195D01*
G03X1484757Y1574108I-549J-1398D01*
G01X1484755D01*
G03X1483262Y1572773I0J-1502D01*
G01Y1572772D01*
G02X1483064Y1572595I-199J23D01*
G01X1480231D01*
G02X1480085Y1572659I1J200D01*
G01X1480076Y1572668D01*
X1480072Y1572673D01*
G03X1478307Y1573507I-1765J-1451D01*
G03X1476021Y1571221I0J-2286D01*
G03X1476086Y1570682I2286J2D01*
G02X1476033Y1570493I-194J-47D01*
G01X1473502Y1567962D01*
G03X1473443Y1567820I141J-142D01*
G01Y1447865D01*
G02X1473406Y1447749I-200J0D01*
G01X1472441Y1446384D01*
G03X1471915Y1445338I3206J-2267D01*
G01X1471909Y1445319D01*
X1471801Y1445127D01*
X1471782Y1445138D01*
X1471595Y1444880D01*
X1471576Y1444864D01*
G03X1470907Y1444134I2537J-2997D01*
G01X1469681Y1442400D01*
G03X1469136Y1441298I3204J-2270D01*
G01X1469127Y1441267D01*
X1469051Y1441162D01*
X1469024Y1441143D01*
G03X1468086Y1440204I2269J-3204D01*
G01X1466902Y1438529D01*
G03X1466327Y1437322I3205J-2268D01*
G01X1466319Y1437290D01*
X1466245Y1437182D01*
X1466219Y1437163D01*
G03X1465380Y1436296I2369J-3132D01*
G01X1464142Y1434545D01*
G03X1463499Y1433054I3206J-2267D01*
G01X1463491Y1433012D01*
X1460949Y1429414D01*
G02X1460927Y1429388I-163J116D01*
G01X1435888Y1404349D01*
G03X1435829Y1404207I141J-142D01*
G01Y1344076D01*
X1435799Y1344002D01*
X1435770Y1343974D01*
X1433047Y1341251D01*
G03X1432988Y1341109I141J-142D01*
G01Y1337300D01*
X1432958Y1337226D01*
X1432929Y1337198D01*
X1430643Y1334912D01*
G02X1430501Y1334853I-142J141D01*
G01X1393584D01*
G02X1393399Y1334975I-1J200D01*
G01Y1334976D01*
G02X1393442Y1335195I184J78D01*
G01X1408749Y1350501D01*
G03X1409132Y1351425I-923J924D01*
G01Y1426207D01*
X1409143Y1426255D01*
X1409155Y1426278D01*
G03X1409327Y1426975I-1330J698D01*
G03X1406323I-1502J0D01*
G03X1406495Y1426278I1502J1D01*
G01X1406507Y1426255D01*
X1406518Y1426207D01*
Y1352049D01*
G02X1406459Y1351907I-200J0D01*
G01X1389464Y1334912D01*
X1389436Y1334883D01*
X1389362Y1334853D01*
X1384510D01*
X1384436Y1334883D01*
X1384408Y1334912D01*
X1382191Y1337129D01*
G02X1382132Y1337271I141J142D01*
G01Y1450460D01*
G02X1382207Y1450616I200J0D01*
G01X1382485Y1450839D01*
X1382573Y1450860D01*
X1382618Y1450850D01*
G03X1383029Y1450805I412J1867D01*
G01X1383032D01*
G03Y1454629I0J1912D01*
G01X1383029D01*
G03X1382618Y1454584I1J-1912D01*
G01X1382573Y1454574D01*
X1382485Y1454595D01*
X1382207Y1454818D01*
G02X1382132Y1454974I125J156D01*
G01Y1460696D01*
G02X1382207Y1460852I200J0D01*
G01X1382485Y1461075D01*
X1382573Y1461096D01*
X1382618Y1461086D01*
G03X1383029Y1461041I412J1867D01*
G01X1383032D01*
G03Y1464865I0J1912D01*
G01X1383029D01*
G03X1382618Y1464820I1J-1912D01*
G01X1382573Y1464810D01*
X1382485Y1464831D01*
X1382207Y1465054D01*
G02X1382132Y1465210I125J156D01*
G01Y1465814D01*
G02X1382207Y1465970I200J0D01*
G01X1382485Y1466193D01*
X1382573Y1466214D01*
X1382618Y1466204D01*
G03X1383029Y1466159I412J1867D01*
G01X1383032D01*
G03Y1469983I0J1912D01*
G01X1383029D01*
G03X1382618Y1469938I1J-1912D01*
G01X1382573Y1469928D01*
X1382485Y1469949D01*
X1382207Y1470172D01*
G02X1382132Y1470328I125J156D01*
G01Y1476051D01*
G02X1382207Y1476207I200J0D01*
G01X1382485Y1476430D01*
X1382573Y1476451D01*
X1382618Y1476441D01*
G03X1383029Y1476396I412J1867D01*
G01X1383032D01*
G03Y1480220I0J1912D01*
G01X1383029D01*
G03X1382618Y1480175I1J-1912D01*
G01X1382573Y1480165D01*
X1382485Y1480186D01*
X1382207Y1480409D01*
G02X1382132Y1480565I125J156D01*
G01Y1481169D01*
G02X1382207Y1481325I200J0D01*
G01X1382485Y1481548D01*
X1382573Y1481569D01*
X1382618Y1481559D01*
G03X1383029Y1481514I412J1867D01*
G01X1383032D01*
G03Y1485338I0J1912D01*
G01X1383029D01*
G03X1382618Y1485293I1J-1912D01*
G01X1382573Y1485283D01*
X1382485Y1485304D01*
X1382207Y1485527D01*
G02X1382132Y1485683I125J156D01*
G01Y1491405D01*
G02X1382207Y1491561I200J0D01*
G01X1382485Y1491784D01*
X1382573Y1491805D01*
X1382618Y1491795D01*
G03X1383029Y1491750I412J1867D01*
G01X1383032D01*
G03Y1495574I0J1912D01*
G01X1383029D01*
G03X1382618Y1495529I1J-1912D01*
G01X1382573Y1495519D01*
X1382485Y1495540D01*
X1382207Y1495763D01*
G02X1382132Y1495919I125J156D01*
G01Y1496523D01*
G02X1382207Y1496679I200J0D01*
G01X1382485Y1496902D01*
X1382573Y1496923D01*
X1382618Y1496913D01*
G03X1383029Y1496868I412J1867D01*
G01X1383032D01*
G03Y1500692I0J1912D01*
G01X1383029D01*
G03X1382618Y1500647I1J-1912D01*
G01X1382573Y1500637D01*
X1382485Y1500658D01*
X1382207Y1500881D01*
G02X1382132Y1501037I125J156D01*
G01Y1506759D01*
G02X1382207Y1506915I200J0D01*
G01X1382485Y1507138D01*
X1382573Y1507159D01*
X1382618Y1507149D01*
G03X1383029Y1507104I412J1867D01*
G01X1383032D01*
G03Y1510928I0J1912D01*
G01X1383029D01*
G03X1382618Y1510883I1J-1912D01*
G01X1382573Y1510873D01*
X1382485Y1510894D01*
X1382207Y1511117D01*
G02X1382132Y1511273I125J156D01*
G01Y1511877D01*
G02X1382207Y1512033I200J0D01*
G01X1382485Y1512256D01*
X1382573Y1512277D01*
X1382618Y1512267D01*
G03X1383029Y1512222I412J1867D01*
G01X1383032D01*
G03Y1516046I0J1912D01*
G01X1383029D01*
G03X1382618Y1516001I1J-1912D01*
G01X1382573Y1515991D01*
X1382485Y1516012D01*
X1382207Y1516235D01*
G02X1382132Y1516391I125J156D01*
G01Y1563058D01*
G02X1382207Y1563214I200J0D01*
G01X1382485Y1563437D01*
X1382573Y1563458D01*
X1382618Y1563448D01*
G03X1383029Y1563403I412J1867D01*
G01X1383032D01*
G03Y1567227I0J1912D01*
G01X1383029D01*
G03X1382618Y1567182I1J-1912D01*
G01X1382573Y1567172D01*
X1382485Y1567193D01*
X1382207Y1567416D01*
G02X1382132Y1567572I125J156D01*
G01Y1568177D01*
G02X1382207Y1568333I200J0D01*
G01X1382485Y1568556D01*
X1382573Y1568577D01*
X1382618Y1568567D01*
G03X1383029Y1568522I412J1867D01*
G01X1383032D01*
G03Y1572346I0J1912D01*
G01X1383029D01*
G03X1382618Y1572301I1J-1912D01*
G01X1382573Y1572291D01*
X1382485Y1572312D01*
X1382207Y1572535D01*
G02X1382132Y1572691I125J156D01*
G01Y1575042D01*
G03X1382073Y1575184I-200J0D01*
G01X1376312Y1580945D01*
X1376283Y1580973D01*
X1376253Y1581047D01*
Y1581121D01*
X1376256Y1581137D01*
G03X1376282Y1581451I-1886J314D01*
G01Y1581460D01*
G03X1374370Y1583369I-1912J-3D01*
G03X1374199Y1583361I4J-1912D01*
G02X1373989Y1583502I-19J199D01*
G03X1373019Y1585118I-3722J-1135D01*
G01X1371616Y1586521D01*
G03X1369270Y1587640I-2752J-2752D01*
G01X1369117Y1587739D01*
G03X1365710Y1589714I-3407J-1951D01*
G01X1365708D01*
G03X1364135Y1589385I0J-3926D01*
G02X1363989Y1589379I-81J183D01*
G03X1363509Y1589462I-493J-1419D01*
G01X1363488D01*
G03X1361994Y1587960I8J-1502D01*
G01Y1587958D01*
G03X1362102Y1587399I1502J0D01*
G01X1362110Y1587358D01*
G03X1361831Y1586406I3598J-1571D01*
G02X1361634Y1586238I-197J32D01*
G01X1354222D01*
G02X1354081Y1586296I0J200D01*
G01X1353816Y1586560D01*
G03X1351943Y1587605I-2777J-2776D01*
G01X1351902Y1587615D01*
X1351838Y1587661D01*
X1351814Y1587702D01*
X1351813Y1587705D01*
G03X1348386Y1589714I-3427J-1918D01*
G01X1348385D01*
G03X1346812Y1589385I0J-3926D01*
G02X1346666Y1589379I-81J183D01*
G03X1346186Y1589462I-493J-1419D01*
G01X1346165D01*
G03X1344671Y1587960I8J-1502D01*
G01Y1587958D01*
G03X1344779Y1587399I1502J0D01*
G01X1344787Y1587358D01*
G03X1344508Y1586406I3598J-1571D01*
G02X1344311Y1586238I-197J32D01*
G01X1336899D01*
G02X1336758Y1586296I0J200D01*
G01X1336493Y1586560D01*
G03X1334620Y1587605I-2777J-2776D01*
G01X1334579Y1587615D01*
X1334515Y1587661D01*
X1334491Y1587702D01*
X1334490Y1587705D01*
G03X1331063Y1589714I-3427J-1918D01*
G01X1331062D01*
G03X1329489Y1589385I0J-3926D01*
G02X1329343Y1589379I-81J183D01*
G03X1328863Y1589462I-493J-1419D01*
G01X1328842D01*
G03X1327348Y1587960I8J-1502D01*
G01Y1587958D01*
G03X1327456Y1587399I1502J0D01*
G01X1327464Y1587358D01*
G03X1327186Y1586407I3600J-1568D01*
G01Y1586406D01*
G02X1326989Y1586238I-197J32D01*
G01X1319621D01*
G02X1319488Y1586297I9J200D01*
G01X1319265Y1586521D01*
G03X1318058Y1587341I-2752J-2752D01*
G01X1318043Y1587347D01*
G03X1317224Y1587622I-1652J-3562D01*
G01X1317204Y1587636D01*
G03X1313740Y1589714I-3464J-1848D01*
G01X1313739D01*
G03X1312166Y1589385I0J-3926D01*
G02X1312020Y1589379I-81J183D01*
G03X1311540Y1589462I-493J-1419D01*
G01X1311519D01*
G03X1310025Y1587960I8J-1502D01*
G01Y1587958D01*
G03X1310133Y1587399I1502J0D01*
G01X1310141Y1587358D01*
G03X1309862Y1586406I3598J-1571D01*
G02X1309665Y1586238I-197J32D01*
G01X1307758D01*
G03X1307616Y1586179I0J-200D01*
G01X1306589Y1585152D01*
X1306476Y1585127D01*
X1306421Y1585147D01*
G03X1305079Y1585384I-1344J-3690D01*
G03X1303434Y1585022I2J-3927D01*
G02X1303413Y1585028I44J195D01*
G03X1302867Y1585131I-547J-1399D01*
G01X1302866D01*
G03X1301364Y1583629I0J-1502D01*
G01Y1583628D01*
G03X1301473Y1583067I1502J1D01*
G01X1301481Y1583028D01*
G03X1301152Y1581457I3598J-1573D01*
G01Y1579953D01*
G03X1301155Y1579809I3927J10D01*
G01X1301157Y1579766D01*
X1301127Y1579690D01*
X1299585Y1578148D01*
G03X1299526Y1578006I141J-142D01*
G01Y1560021D01*
G02X1299467Y1559879I-200J0D01*
G01X1289167Y1549579D01*
G03X1289108Y1549437I141J-142D01*
G01Y1549101D01*
X1289042Y1549002D01*
X1288985Y1548978D01*
X1287361Y1548297D01*
G03X1286101Y1547450I1519J-3621D01*
G01X1275480Y1536808D01*
G03X1274674Y1535635I2780J-2773D01*
G01X1272816Y1531474D01*
X1272814Y1531470D01*
X1270982Y1527706D01*
G03X1270762Y1527148I3499J-1702D01*
G01X1270491Y1526268D01*
X1270485Y1526255D01*
X1214946Y1401882D01*
G02X1214764Y1401764I-182J82D01*
G01X1194347D01*
G02X1194147Y1401967I0J200D01*
G01X1194410Y1418719D01*
Y1418732D01*
X1195294Y1426577D01*
X1195295Y1426587D01*
X1200754Y1452359D01*
Y1452360D01*
G03X1200775Y1452462I-3835J843D01*
G01Y1452465D01*
X1200844Y1452787D01*
G03X1200930Y1453596I-3806J814D01*
G01Y1456427D01*
G02X1200989Y1456569I200J0D01*
G01X1201101Y1456680D01*
X1201169Y1456710D01*
X1201208Y1456711D01*
G03Y1460533I-67J1911D01*
G01X1201169Y1460534D01*
X1201101Y1460564D01*
X1200989Y1460675D01*
G02X1200930Y1460817I141J142D01*
G01Y1461546D01*
G02X1200989Y1461688I200J0D01*
G01X1201101Y1461799D01*
X1201169Y1461829D01*
X1201208Y1461830D01*
G03Y1465652I-67J1911D01*
G01X1201169Y1465653D01*
X1201101Y1465683D01*
X1200989Y1465794D01*
G02X1200930Y1465936I141J142D01*
G01Y1471782D01*
G02X1200989Y1471924I200J0D01*
G01X1201101Y1472035D01*
X1201169Y1472065D01*
X1201208Y1472066D01*
G03Y1475888I-67J1911D01*
G01X1201169Y1475889D01*
X1201101Y1475919D01*
X1200989Y1476030D01*
G02X1200930Y1476172I141J142D01*
G01Y1476900D01*
G02X1200989Y1477042I200J0D01*
G01X1201101Y1477153D01*
X1201169Y1477183D01*
X1201208Y1477184D01*
G03Y1481006I-67J1911D01*
G01X1201169Y1481007D01*
X1201101Y1481037D01*
X1200989Y1481148D01*
G02X1200930Y1481290I141J142D01*
G01Y1487136D01*
G02X1200989Y1487278I200J0D01*
G01X1201101Y1487389D01*
X1201169Y1487419D01*
X1201208Y1487420D01*
G03Y1491242I-67J1911D01*
G01X1201169Y1491243D01*
X1201101Y1491273D01*
X1200989Y1491384D01*
G02X1200930Y1491526I141J142D01*
G01Y1492254D01*
G02X1200989Y1492396I200J0D01*
G01X1201101Y1492507D01*
X1201169Y1492537D01*
X1201208Y1492538D01*
G03Y1496360I-67J1911D01*
G01X1201169Y1496361D01*
X1201101Y1496391D01*
X1200989Y1496502D01*
G02X1200930Y1496644I141J142D01*
G01Y1502490D01*
G02X1200989Y1502632I200J0D01*
G01X1201101Y1502743D01*
X1201169Y1502773D01*
X1201208Y1502774D01*
G03Y1506596I-67J1911D01*
G01X1201169Y1506597D01*
X1201101Y1506627D01*
X1200989Y1506738D01*
G02X1200930Y1506880I141J142D01*
G01Y1507609D01*
G02X1200989Y1507751I200J0D01*
G01X1201101Y1507862D01*
X1201169Y1507892D01*
X1201208Y1507893D01*
G03X1203053Y1509804I-67J1911D01*
G03X1201141Y1511716I-1912J0D01*
G01X1201139D01*
G03X1200851Y1511694I1J-1912D01*
G01X1200836Y1511692D01*
X1200835D01*
G02X1200693Y1511722I-32J197D01*
G01X1200626Y1511765D01*
G03X1200624Y1511767I-139J-137D01*
G01X1200602Y1511780D01*
X1200566Y1511820D01*
X1200551Y1511851D01*
X1200550Y1511852D01*
G03X1200447Y1512053I-3514J-1674D01*
G01X1200423Y1512129D01*
G03X1199332Y1513424I-1495J-152D01*
G01X1199306Y1513431D01*
X1199263Y1513456D01*
X1198799Y1513920D01*
G03X1198749Y1513971I-2829J-2723D01*
G01X1197985Y1514734D01*
G03X1197897Y1514820I-2788J-2765D01*
G01X1197849Y1514868D01*
G03X1196026Y1515895I-2751J-2752D01*
G02X1195981Y1515912I48J194D01*
G03X1194512Y1517494I-3501J-1778D01*
G01X1194477Y1517516D01*
X1194430Y1517581D01*
X1194369Y1517854D01*
G02X1194395Y1518004I195J43D01*
G01X1194396Y1518006D01*
X1194397Y1518007D01*
G03X1194766Y1519252I-1917J1245D01*
G03X1194024Y1520937I-2284J0D01*
G01X1194019Y1520942D01*
X1194009Y1520953D01*
G02X1193954Y1521090I145J138D01*
G01Y1548218D01*
G02X1194011Y1548358I200J0D01*
G01X1198076Y1552424D01*
G03X1198301Y1552669I-2777J2776D01*
G02X1198305Y1552674I158J-123D01*
G03X1199007Y1553788I-2894J2602D01*
G01X1200633Y1557713D01*
G03X1200906Y1558777I-3595J1489D01*
G01X1200910Y1558813D01*
X1200973Y1558940D01*
X1201000Y1558965D01*
X1201087Y1559045D01*
X1201122Y1559059D01*
X1201156Y1559073D01*
X1201192Y1559074D01*
G03X1203053Y1560985I-51J1911D01*
G03X1201208Y1562896I-1912J0D01*
G01X1201169Y1562897D01*
X1201101Y1562927D01*
X1200989Y1563038D01*
G02X1200930Y1563180I141J142D01*
G01Y1563908D01*
G02X1200989Y1564050I200J0D01*
G01X1201101Y1564161D01*
X1201169Y1564191D01*
X1201208Y1564192D01*
G03Y1568014I-67J1911D01*
G01X1201169Y1568015D01*
X1201101Y1568045D01*
X1200989Y1568156D01*
G02X1200930Y1568298I141J142D01*
G01Y1574144D01*
G02X1200989Y1574286I200J0D01*
G01X1201101Y1574397D01*
X1201169Y1574427D01*
X1201208Y1574428D01*
G03Y1578250I-67J1911D01*
G01X1201169Y1578251D01*
X1201101Y1578281D01*
X1200989Y1578392D01*
G02X1200930Y1578534I141J142D01*
G01Y1579262D01*
G02X1200989Y1579404I200J0D01*
G01X1201101Y1579515D01*
X1201169Y1579545D01*
X1201208Y1579546D01*
G03Y1583368I-67J1911D01*
G01X1201169Y1583369D01*
X1201101Y1583399D01*
X1200989Y1583510D01*
G02X1200930Y1583652I141J142D01*
G01Y1589498D01*
G02X1200989Y1589640I200J0D01*
G01X1201101Y1589751D01*
X1201169Y1589781D01*
X1201208Y1589782D01*
G03Y1593604I-67J1911D01*
G01X1201169Y1593605D01*
X1201101Y1593635D01*
X1200989Y1593746D01*
G02X1200930Y1593888I141J142D01*
G01Y1594616D01*
G02X1200989Y1594758I200J0D01*
G01X1201101Y1594869D01*
X1201169Y1594899D01*
X1201208Y1594900D01*
G03Y1598722I-67J1911D01*
G01X1201169Y1598723D01*
X1201101Y1598753D01*
X1200989Y1598864D01*
G02X1200930Y1599006I141J142D01*
G01Y1604853D01*
G02X1200989Y1604995I200J0D01*
G01X1201101Y1605106D01*
X1201169Y1605136D01*
X1201208Y1605137D01*
G03Y1608959I-67J1911D01*
G01X1201169Y1608960D01*
X1201101Y1608990D01*
X1200989Y1609101D01*
G02X1200930Y1609243I141J142D01*
G01Y1609971D01*
G02X1200989Y1610113I200J0D01*
G01X1201101Y1610224D01*
X1201169Y1610254D01*
X1201208Y1610255D01*
G03X1203053Y1612166I-67J1911D01*
G03X1201141Y1614078I-1912J0D01*
G01X1201139D01*
G03X1200851Y1614056I1J-1912D01*
G01X1200836Y1614054D01*
X1200835D01*
G02X1200693Y1614084I-32J197D01*
G01X1200626Y1614127D01*
G03X1200624Y1614129I-139J-137D01*
G01X1200602Y1614142D01*
X1200566Y1614182D01*
X1200551Y1614213D01*
X1200550Y1614215D01*
G03X1200483Y1614349I-3514J-1673D01*
G01X1200478Y1614358D01*
X1200475Y1614365D01*
G03X1200448Y1614422I-3562J-1652D01*
G01X1200440Y1614438D01*
X1200421Y1614506D01*
X1200419Y1614522D01*
G03X1199462Y1615742I-1491J-184D01*
G01X1199422Y1615757D01*
X1197910Y1617268D01*
G03X1196037Y1618313I-2777J-2776D01*
G01X1195996Y1618323D01*
X1195932Y1618369D01*
X1195908Y1618410D01*
X1195907Y1618413D01*
G03X1194531Y1619843I-3425J-1919D01*
G01Y1619844D01*
X1194509Y1619857D01*
G02X1194453Y1619910I107J169D01*
G01X1194452Y1619912D01*
G02X1194419Y1619987I162J116D01*
G01X1194400Y1620073D01*
G02X1194396Y1620115I196J40D01*
G01Y1620310D01*
G02X1194425Y1620413I200J-1D01*
G01X1194426Y1620415D01*
X1194427Y1620416D01*
G03X1194766Y1621614I-1949J1198D01*
G01Y1621615D01*
G03X1194024Y1623300I-2284J0D01*
G01X1194019Y1623305D01*
X1194009Y1623316D01*
G02X1193954Y1623453I145J138D01*
G01Y1633015D01*
G02X1194011Y1633155I200J0D01*
G01X1200813Y1639957D01*
G02X1200815Y1639959I142J-140D01*
G02X1200955Y1640016I140J-143D01*
G01X1232376D01*
G02X1232574Y1639840I0J-199D01*
G01Y1552480D01*
Y1552280D01*
X1285356D01*
X1285376Y1552284D01*
G03X1285525Y1552420I-42J196D01*
G01X1285534Y1552448D01*
Y1639830D01*
G02X1285734Y1640016I200J-15D01*
G01X1578832D01*
G02X1579032Y1639830I0J-201D01*
G01Y1552280D01*
X1631790D01*
G03X1631990Y1552480I0J200D01*
G01Y1552571D01*
X1631992Y1552573D01*
Y1639844D01*
G02X1632190Y1640016I198J-28D01*
G37*
G36*
G01X1406555Y54588D02*
X1435515D01*
X1435890Y54213D01*
Y52966D01*
X1435515Y52591D01*
X1406555D01*
G03X1400618Y46654I0J-5937D01*
G01Y7874D01*
G02X1394744Y2000I-5874J0D01*
G01X1299862D01*
G02X1293988Y7874I0J5874D01*
G01Y46654D01*
G03X1292425Y50669I-5938J0D01*
G01Y50696D01*
X1292470Y50741D01*
X1294823D01*
X1294895Y50669D01*
G02X1295986Y46654I-6842J-4015D01*
G01Y7874D01*
G03X1299862Y3998I3876J0D01*
G01X1394744D01*
G03X1398620Y7874I0J3876D01*
G01Y46654D01*
G02X1406555Y54588I7935J-1D01*
G37*
G36*
G01X1304571Y813187D02*
X1306315D01*
G02X1306456Y813128I-1J-200D01*
G01X1307420Y812164D01*
G03X1308297Y811794I895J896D01*
G01X1308336Y811793D01*
X1308407Y811763D01*
X1309259Y810911D01*
G02X1309318Y810769I-141J-142D01*
G01Y810031D01*
G03X1309333Y809954I200J-1D01*
G01X1309362Y809886D01*
G02X1309377Y809809I-185J-76D01*
G01Y800272D01*
G02X1309318Y800130I-200J0D01*
G01X1306790Y797602D01*
X1306762Y797573D01*
X1306688Y797543D01*
X1300317D01*
G02X1300142Y797647I0J200D01*
G01X1299947Y798004D01*
X1299952Y798114D01*
X1299982Y798160D01*
G03X1300222Y798975I-1262J815D01*
G01Y799001D01*
G03X1298720Y800477I-1502J-26D01*
G03X1297407Y799705I0J-1503D01*
G01X1297382Y799659D01*
X1297294Y799605D01*
X1296850Y799584D01*
X1296758Y799630D01*
X1296728Y799673D01*
G03X1295491Y800323I-1237J-852D01*
G03X1294714Y800106I1J-1502D01*
G01X1294667Y800078D01*
X1294560Y800076D01*
X1294210Y800273D01*
G02X1294108Y800447I98J175D01*
G01Y810317D01*
G02X1294167Y810458I200J-1D01*
G01X1295175Y811465D01*
G02X1295316Y811524I142J-141D01*
G01X1301043D01*
G02X1301172Y811477I0J-200D01*
G03X1302140Y811123I968J1148D01*
G03X1303108Y811477I0J1502D01*
G02X1303237Y811524I129J-153D01*
G01X1303705D01*
G03X1303847Y811583I0J200D01*
G01X1303878Y811614D01*
G03X1303937Y811756I-141J142D01*
G01Y812553D01*
G02X1303996Y812695I200J0D01*
G01X1304429Y813128D01*
G02X1304571Y813187I142J-141D01*
G37*
G36*
G01X1389052Y1304640D02*
G03X1387990Y1304201I-1J-1501D01*
G01X1387193Y1303404D01*
G02X1386911I-141J141D01*
G01X1386114Y1304201D01*
G03X1385054Y1304640I-1061J-1062D01*
G01X1385052D01*
G03X1383550Y1303139I0J-1502D01*
G03X1383990Y1302077I1502J0D01*
G01X1384677Y1301390D01*
G02X1384736Y1301248I-141J-142D01*
G01Y1300856D01*
G02X1384536Y1300656I-200J0D01*
G01X1384191D01*
G03X1384049Y1300597I0J-200D01*
G01X1383706Y1300254D01*
G03X1383647Y1300112I141J-142D01*
G01Y1298146D01*
G02X1383588Y1298004I-200J0D01*
G01X1378458Y1292875D01*
G03X1378018Y1291813I1062J-1062D01*
G01Y1208067D01*
G03X1378458Y1207005I1502J0D01*
G01X1381763Y1203700D01*
G02X1381822Y1203558I-141J-142D01*
G01Y1198222D01*
G02X1381622Y1198022I-200J0D01*
G01X1381614D01*
G02X1381472Y1198081I0J200D01*
G01X1381021Y1198533D01*
G03X1379961Y1198972I-1061J-1062D01*
G01X1379959D01*
G03X1378458Y1197471I0J-1501D01*
G01Y1197469D01*
G03X1378897Y1196409I1501J1D01*
G01X1379694Y1195612D01*
G02Y1195330I-141J-141D01*
G01X1378897Y1194533D01*
G03X1378458Y1193473I1062J-1061D01*
G01Y1193471D01*
G03X1379959Y1191970I1501J0D01*
G01X1379961D01*
G03X1381021Y1192409I-1J1501D01*
G01X1381772Y1193161D01*
G02X1381914Y1193220I142J-141D01*
G01X1383248D01*
G03X1384308Y1193659I-1J1501D01*
G01X1385886Y1195237D01*
G03X1386326Y1196299I-1062J1062D01*
G01Y1204885D01*
G03X1385886Y1205947I-1502J0D01*
G01X1382581Y1209252D01*
G02X1382522Y1209394I141J142D01*
G01Y1290486D01*
G02X1382580Y1290628I200J1D01*
G01X1383306Y1291354D01*
G02X1383523Y1291397I141J-142D01*
G01X1383580Y1291374D01*
X1383647Y1291273D01*
Y1219244D01*
G03X1383706Y1219102I200J0D01*
G01X1384105Y1218703D01*
G02X1384162Y1218563I-143J-140D01*
G01Y1218534D01*
G03X1384220Y1218394I200J1D01*
G01X1384498Y1218116D01*
X1384500Y1218113D01*
G03X1384514Y1218099I857J843D01*
G01X1388271Y1214342D01*
G03X1388285Y1214328I857J843D01*
G01X1388288Y1214326D01*
X1388566Y1214048D01*
G03X1388706Y1213990I141J142D01*
G01X1388735D01*
G02X1388875Y1213933I0J-200D01*
G01X1389316Y1213492D01*
G03X1389458Y1213433I142J141D01*
G01X1435223D01*
G02X1435255Y1213430I-3J-200D01*
G01X1435257D01*
G02X1435363Y1213376I-34J-197D01*
G01X1444419Y1204320D01*
G02X1444472Y1204219I-143J-140D01*
G01Y1204217D01*
G02X1444476Y1204180I-196J-40D01*
G01Y1126674D01*
G02X1444417Y1126532I-200J0D01*
G01X1444042Y1126157D01*
G02X1443900Y1126098I-142J141D01*
G01X1443131D01*
G02X1442989Y1126157I0J200D01*
G01X1440681Y1128465D01*
G02X1440622Y1128607I141J142D01*
G01Y1159590D01*
G02X1440628Y1159627I200J-13D01*
G02X1440751Y1159763I193J-51D01*
G01X1440926Y1159829D01*
X1441100Y1159895D01*
G02X1441248Y1159893I71J-187D01*
G01X1441269Y1159884D01*
X1441306Y1159857D01*
X1441321Y1159840D01*
G03X1442448Y1159332I1127J996D01*
G03Y1162336I0J1502D01*
G03X1441080Y1161454I0J-1502D01*
G01X1441074Y1161441D01*
G02X1441012Y1161371I-177J94D01*
G01X1440990Y1161356D01*
X1440967Y1161348D01*
G02X1440915Y1161337I-67J188D01*
G01X1440690Y1161320D01*
X1440611Y1161314D01*
G02X1440507Y1161334I-16J200D01*
G02X1440487Y1161346I93J177D01*
G02X1440456Y1161371I109J167D01*
G01X1440213Y1161614D01*
G03X1440184Y1161644I-1094J-1029D01*
G01X1438397Y1163431D01*
G02X1438353Y1163498I142J141D01*
G01X1438339Y1163532D01*
Y1163697D01*
G02X1438342Y1163732I200J0D01*
G02X1438387Y1163827I197J-35D01*
G01X1438396Y1163836D01*
G03X1438822Y1164884I-1076J1048D01*
G03X1438453Y1165870I-1502J0D01*
G01X1438452Y1165871D01*
X1438444Y1165881D01*
G02X1438404Y1165982I159J121D01*
G02X1438403Y1166001I199J20D01*
G01Y1166267D01*
G02X1438404Y1166286I200J-1D01*
G02X1438444Y1166387I199J-20D01*
G01X1438452Y1166397D01*
X1438453Y1166398D01*
G03Y1168370I-1132J986D01*
G01X1438452Y1168371D01*
X1438444Y1168381D01*
G02X1438404Y1168482I159J121D01*
G02X1438403Y1168501I199J20D01*
G01Y1168767D01*
G02X1438404Y1168786I200J-1D01*
G02X1438444Y1168887I199J-20D01*
G01X1438452Y1168897D01*
X1438453Y1168898D01*
G03Y1170870I-1132J986D01*
G01X1438452Y1170871D01*
X1438444Y1170881D01*
G02X1438404Y1170982I159J121D01*
G02X1438403Y1171001I199J20D01*
G01Y1171267D01*
G02X1438404Y1171286I200J-1D01*
G02X1438444Y1171387I199J-20D01*
G01X1438452Y1171397D01*
X1438453Y1171398D01*
G03Y1173370I-1132J986D01*
G01X1438452Y1173371D01*
X1438444Y1173381D01*
G02X1438404Y1173482I159J121D01*
G02X1438403Y1173501I199J20D01*
G01Y1173767D01*
G02X1438404Y1173786I200J-1D01*
G02X1438444Y1173887I199J-20D01*
G01X1438452Y1173897D01*
X1438453Y1173898D01*
G03X1438822Y1174884I-1133J986D01*
G03X1437320Y1176386I-1502J0D01*
G03X1436334Y1176017I0J-1502D01*
G01X1436333Y1176016D01*
X1436323Y1176008D01*
G02X1436222Y1175968I-121J159D01*
G02X1436203Y1175967I-20J199D01*
G01X1435937D01*
G02X1435918Y1175968I1J200D01*
G02X1435817Y1176008I20J199D01*
G01X1435807Y1176016D01*
G03X1434820Y1176386I-987J-1131D01*
G03X1433318Y1174884I0J-1502D01*
G03X1433687Y1173898I1502J0D01*
G01X1433688Y1173897D01*
X1433696Y1173887D01*
G02X1433736Y1173786I-159J-121D01*
G02X1433737Y1173767I-199J-20D01*
G01Y1173501D01*
G02X1433736Y1173482I-200J1D01*
G02X1433696Y1173381I-199J20D01*
G01X1433688Y1173371D01*
X1433687Y1173370D01*
G03Y1171398I1132J-986D01*
G01X1433688Y1171397D01*
X1433696Y1171387D01*
G02X1433736Y1171286I-159J-121D01*
G02X1433737Y1171267I-199J-20D01*
G01Y1171001D01*
G02X1433736Y1170982I-200J1D01*
G02X1433696Y1170881I-199J20D01*
G01X1433688Y1170871D01*
X1433687Y1170870D01*
G03Y1168898I1132J-986D01*
G01X1433688Y1168897D01*
X1433696Y1168887D01*
G02X1433736Y1168786I-159J-121D01*
G02X1433737Y1168767I-199J-20D01*
G01Y1168501D01*
G02X1433736Y1168482I-200J1D01*
G02X1433696Y1168381I-199J20D01*
G01X1433688Y1168371D01*
X1433687Y1168370D01*
G03Y1166398I1132J-986D01*
G01X1433688Y1166397D01*
X1433696Y1166387D01*
G02X1433736Y1166286I-159J-121D01*
G02X1433737Y1166267I-199J-20D01*
G01Y1166001D01*
G02X1433736Y1165982I-200J1D01*
G02X1433696Y1165881I-199J20D01*
G01X1433688Y1165871D01*
X1433687Y1165870D01*
G03Y1163898I1132J-986D01*
G01X1433688Y1163897D01*
X1433696Y1163887D01*
G02X1433736Y1163786I-159J-121D01*
G02X1433737Y1163767I-199J-20D01*
G01Y1163501D01*
G02X1433736Y1163482I-200J1D01*
G02X1433696Y1163381I-199J20D01*
G01X1433688Y1163371D01*
X1433687Y1163370D01*
G03X1433318Y1162384I1133J-986D01*
G03X1434820Y1160882I1502J0D01*
G03X1435865Y1161305I0J1502D01*
G01X1435867Y1161307D01*
G02X1435934Y1161351I141J-142D01*
G01X1435968Y1161365D01*
X1436217D01*
G03X1436258Y1161322I1107J1015D01*
G01X1436664Y1160917D01*
X1437238Y1160342D01*
X1437239D01*
X1437560Y1160020D01*
G02X1437564Y1160016I-139J-143D01*
G02X1437611Y1159932I-146J-137D01*
G02X1437618Y1159879I-193J-52D01*
G01Y1120178D01*
G02X1437562Y1120039I-200J0D01*
G01X1437479Y1119953D01*
G02X1437350Y1119893I-143J140D01*
G03X1436405Y1119458I117J-1497D01*
G01X1435041Y1118093D01*
G02X1434899Y1118034I-142J141D01*
G01X1428255D01*
G02X1428113Y1118093I0J200D01*
G01X1424223Y1121984D01*
G03X1423161Y1122424I-1062J-1062D01*
G01X1413763D01*
G03X1412701Y1121984I0J-1502D01*
G01X1410175Y1119458D01*
G03X1409736Y1118396I1062J-1061D01*
G03X1410105Y1117409I1501J-1D01*
G01X1410129Y1117382D01*
X1410155Y1117314D01*
X1410154Y1117014D01*
G02X1410106Y1116884I-200J0D01*
G01X1410105Y1116883D01*
G03X1409735Y1115896I1131J-987D01*
G03X1409739Y1115791I1502J5D01*
G01Y1115789D01*
X1409743Y1115727D01*
X1409680Y1115621D01*
X1409281Y1115439D01*
G02X1409057Y1115479I-83J182D01*
G01X1408552Y1115984D01*
G02X1408494Y1116126I142J141D01*
G01Y1127412D01*
G02X1408574Y1127572I200J0D01*
G01X1408867Y1127793D01*
X1408959Y1127809D01*
X1409005Y1127796D01*
G03X1409425Y1127736I420J1442D01*
G03Y1130740I0J1502D01*
G03X1409005Y1130680I0J-1502D01*
G01X1408959Y1130667D01*
X1408867Y1130683D01*
X1408574Y1130904D01*
G02X1408494Y1131064I120J160D01*
G01Y1160579D01*
G02X1408577Y1160741I200J0D01*
G01X1408839Y1160930D01*
G02X1409019Y1160958I117J-162D01*
G03X1409490Y1160882I472J1426D01*
G01X1409492D01*
G03X1410994Y1162384I0J1502D01*
G03X1410624Y1163371I-1501J0D01*
G01Y1163372D01*
X1410623D01*
G02X1410575Y1163502I152J130D01*
G01Y1163766D01*
G02X1410623Y1163896I200J0D01*
G01X1410624Y1163897D01*
G03Y1165871I-1131J987D01*
G01Y1165872D01*
X1410623D01*
G02X1410575Y1166002I152J130D01*
G01Y1166266D01*
G02X1410623Y1166396I200J0D01*
G01X1410624Y1166397D01*
G03Y1168371I-1131J987D01*
G01Y1168372D01*
X1410623D01*
G02X1410575Y1168502I152J130D01*
G01Y1168766D01*
G02X1410623Y1168896I200J0D01*
G01X1410624Y1168897D01*
G03Y1170871I-1131J987D01*
G01Y1170872D01*
X1410623D01*
G02X1410575Y1171002I152J130D01*
G01Y1171266D01*
G02X1410623Y1171396I200J0D01*
G01X1410624Y1171397D01*
G03Y1173371I-1131J987D01*
G01Y1173372D01*
X1410623D01*
G02X1410575Y1173502I152J130D01*
G01Y1173766D01*
G02X1410623Y1173896I200J0D01*
G01X1410624Y1173897D01*
G03X1410994Y1174884I-1131J987D01*
G03X1409492Y1176386I-1502J0D01*
G03X1408505Y1176016I0J-1501D01*
G01X1408504D01*
Y1176015D01*
G02X1408374Y1175967I-130J152D01*
G01X1408110D01*
G02X1407980Y1176015I0J200D01*
G01X1407979Y1176016D01*
G03X1406992Y1176386I-987J-1131D01*
G03X1405490Y1174884I0J-1502D01*
G03X1405860Y1173897I1501J0D01*
G01Y1173896D01*
X1405861D01*
G02X1405909Y1173766I-152J-130D01*
G01Y1173502D01*
G02X1405861Y1173372I-200J0D01*
G01X1405860Y1173371D01*
G03Y1171397I1131J-987D01*
G01Y1171396D01*
X1405861D01*
G02X1405909Y1171266I-152J-130D01*
G01Y1171002D01*
G02X1405861Y1170872I-200J0D01*
G01X1405860Y1170871D01*
G03Y1168897I1131J-987D01*
G01Y1168896D01*
X1405861D01*
G02X1405909Y1168766I-152J-130D01*
G01Y1168502D01*
G02X1405861Y1168372I-200J0D01*
G01X1405860Y1168371D01*
G03Y1166397I1131J-987D01*
G01Y1166396D01*
X1405861D01*
G02X1405909Y1166266I-152J-130D01*
G01Y1166002D01*
G02X1405861Y1165872I-200J0D01*
G01X1405860Y1165871D01*
G03Y1163897I1131J-987D01*
G01Y1163896D01*
X1405861D01*
G02X1405909Y1163766I-152J-130D01*
G01X1405910Y1163466D01*
X1405884Y1163398D01*
X1405860Y1163371D01*
G03X1405490Y1162384I1131J-987D01*
G01Y1115421D01*
G03X1405930Y1114359I1502J0D01*
G01X1408020Y1112269D01*
G02X1408060Y1112043I-141J-142D01*
G01X1407901Y1111703D01*
G02X1407703Y1111588I-181J84D01*
G01X1407702D01*
G03X1407571Y1111594I-134J-1496D01*
G03Y1108590I0J-1502D01*
G03X1408419Y1108852I0J1503D01*
G01X1408464Y1108883D01*
X1408576Y1108890D01*
X1408937Y1108699D01*
G02X1409044Y1108522I-93J-177D01*
G01Y1106298D01*
G03X1412048I1502J0D01*
G01Y1111867D01*
G03X1411608Y1112929I-1502J0D01*
G01X1410820Y1113716D01*
G02X1410780Y1113940I142J141D01*
G01X1410936Y1114282D01*
G02X1411131Y1114398I182J-84D01*
G03X1411237Y1114394I110J1498D01*
G03X1412739Y1115896I0J1502D01*
G03X1412313Y1116944I-1502J0D01*
G02X1412256Y1117083I143J140D01*
G01Y1117293D01*
G03X1412299Y1117334I-1015J1107D01*
G01X1414326Y1119361D01*
G02X1414468Y1119420I142J-141D01*
G01X1419230D01*
G02X1419380Y1119353I1J-200D01*
G01X1419579Y1119130D01*
G02X1419628Y1118974I-150J-133D01*
G03X1419618Y1118801I1491J-173D01*
G03X1420062Y1117735I1502J0D01*
G02X1420121Y1117593I-141J-142D01*
G01Y1117309D01*
G02X1420062Y1117167I-200J0D01*
G03X1419618Y1116101I1058J-1066D01*
G03X1419691Y1115639I1502J1D01*
G01X1419704Y1115598D01*
X1419695Y1115513D01*
X1419497Y1115180D01*
X1419429Y1115131D01*
X1419386Y1115123D01*
G03X1418194Y1113929I283J-1475D01*
G01X1418184Y1113880D01*
X1418124Y1113804D01*
X1417726Y1113632D01*
X1417629Y1113639D01*
X1417587Y1113666D01*
G03X1416784Y1113899I-803J-1269D01*
G03X1416502Y1113872I2J-1502D01*
G01X1416464Y1113865D01*
X1416389Y1113879D01*
X1416094Y1114068D01*
X1416049Y1114130D01*
X1416040Y1114167D01*
G03X1414584Y1115299I-1456J-370D01*
G03X1413082Y1113797I0J-1502D01*
G03X1413612Y1112652I1502J0D01*
G02X1413683Y1112500I-129J-153D01*
G01Y1112194D01*
G02X1413612Y1112042I-200J1D01*
G03X1413082Y1110897I972J-1145D01*
G03X1413612Y1109752I1502J0D01*
G02X1413683Y1109600I-129J-153D01*
G01Y1109294D01*
G02X1413612Y1109142I-200J1D01*
G03X1413082Y1107997I972J-1145D01*
G03X1414584Y1106495I1502J0D01*
G03X1416037Y1107615I0J1503D01*
G01X1416046Y1107650D01*
X1416088Y1107710D01*
X1416371Y1107898D01*
X1416442Y1107914D01*
X1416478Y1107909D01*
G03X1416684Y1107895I205J1488D01*
G03X1416890Y1107909I1J1502D01*
G01X1416926Y1107914D01*
X1416997Y1107898D01*
X1417280Y1107710D01*
X1417322Y1107650D01*
X1417331Y1107615D01*
G03X1418784Y1106495I1453J383D01*
G03X1420286Y1107997I0J1502D01*
G03X1419918Y1108982I-1502J0D01*
G01X1419893Y1109011D01*
X1419868Y1109081D01*
X1419881Y1109432D01*
X1419912Y1109502D01*
X1419939Y1109528D01*
G03X1420386Y1110597I-1055J1069D01*
G03X1420009Y1111592I-1502J0D01*
G01X1419976Y1111629D01*
X1419953Y1111725D01*
X1420048Y1112095D01*
G02X1420174Y1112234I194J-49D01*
G03X1421171Y1113648I-504J1414D01*
G03X1421098Y1114110I-1502J-1D01*
G01X1421085Y1114151D01*
X1421094Y1114236D01*
X1421292Y1114569D01*
X1421360Y1114618D01*
X1421403Y1114626D01*
G03X1422622Y1116101I-283J1475D01*
G03X1422178Y1117167I-1502J0D01*
G02X1422119Y1117309I141J142D01*
G01Y1117593D01*
G02X1422178Y1117735I200J0D01*
G03X1422590Y1118494I-1058J1066D01*
G01Y1118495D01*
G02X1422729Y1118645I196J-42D01*
G01X1423066Y1118745D01*
G02X1423264Y1118695I57J-192D01*
G01X1426207Y1115753D01*
G02X1426259Y1115563I-142J-141D01*
G01X1426175Y1115230D01*
G02X1426039Y1115087I-194J49D01*
G01X1426038D01*
G03X1425483Y1114780I433J-1438D01*
G01X1425481D01*
Y1114779D01*
G02X1425351Y1114731I-130J152D01*
G01X1425087D01*
G02X1424957Y1114779I0J200D01*
G01X1424956Y1114780D01*
G03X1423969Y1115150I-987J-1131D01*
G03Y1112146I0J-1502D01*
G03X1424956Y1112516I0J1501D01*
G01X1424957D01*
Y1112517D01*
G02X1425087Y1112565I130J-152D01*
G01X1425351D01*
G02X1425481Y1112517I0J-200D01*
G01X1425482Y1112516D01*
G03X1426469Y1112146I987J1131D01*
G03X1427971Y1113648I0J1502D01*
G01Y1113650D01*
G03X1427755Y1114425I-1502J-1D01*
G01X1427727Y1114471D01*
X1427725Y1114580D01*
X1427923Y1114930D01*
G02X1428097Y1115032I174J-98D01*
G01X1435606D01*
G03X1436666Y1115471I-1J1501D01*
G01X1437277Y1116082D01*
G02X1437494Y1116126I142J-141D01*
G01X1437551Y1116103D01*
X1437618Y1116002D01*
Y1115488D01*
G03X1437619Y1115440I1502J7D01*
G01Y1114949D01*
G03X1437678Y1114808I200J1D01*
G01X1438019Y1114466D01*
X1438026Y1114459D01*
G03X1438058Y1114426I1094J1029D01*
G01X1438149Y1114335D01*
X1440108Y1112377D01*
X1441090Y1111394D01*
G02X1441114Y1111365I-141J-141D01*
G02X1440872Y1111068I-166J-112D01*
G01X1440868Y1111069D01*
X1440866Y1111071D01*
X1440826Y1111088D01*
X1440797Y1111119D01*
G03X1439699Y1111595I-1098J-1028D01*
G03Y1108589I0J-1503D01*
G01X1439700D01*
G03X1440527Y1108837I0J1502D01*
G01X1440548Y1108851D01*
X1440649Y1108886D01*
X1440705Y1108889D01*
X1441055Y1108705D01*
G02X1441095Y1108677I-94J-176D01*
G01X1441101Y1108672D01*
G02X1441163Y1108527I-138J-145D01*
G01Y1105119D01*
G03X1441222Y1104977I200J0D01*
G01X1441956Y1104243D01*
G03X1442098Y1104184I142J141D01*
G01X1443859D01*
G02X1443891Y1104181I-3J-200D01*
G01X1443893D01*
G02X1443999Y1104127I-34J-197D01*
G01X1444419Y1103707D01*
G02X1444473Y1103601I-143J-140D01*
G01Y1103599D01*
G02X1444476Y1103567I-197J-35D01*
G01Y1098586D01*
G02X1444475Y1098572I-200J7D01*
G02X1444474Y1098560I-200J11D01*
G02X1444445Y1098479I-198J25D01*
G01X1444418Y1098437D01*
G03X1443005Y1097581I6173J-11783D01*
G03Y1075727I7585J-10927D01*
G03X1444369Y1074896I7591J10924D01*
G01X1444370D01*
G02X1444447Y1074825I-92J-177D01*
G01X1444461Y1074803D01*
X1444469Y1074775D01*
G02X1444476Y1074722I-193J-52D01*
G01Y1032966D01*
G02X1444432Y1032841I-200J0D01*
G03X1444430Y1032839I140J-142D01*
G02X1444418Y1032825I-157J123D01*
G01X1443149Y1031555D01*
X1443126Y1031532D01*
X1443058Y1031465D01*
G03X1442787Y1031064I895J-897D01*
G02X1442775Y1031039I-186J74D01*
G03X1442588Y1030364I1119J-674D01*
G01Y1011350D01*
G02X1442559Y1011336I-101J172D01*
G01X1442201Y1011200D01*
G02X1442104Y1011193I-62J190D01*
G01X1442061Y1011203D01*
X1442011Y1011232D01*
X1441989Y1011257D01*
G03X1440869Y1011758I-1120J-1001D01*
G03Y1008754I0J-1502D01*
G03X1441989Y1009255I0J1502D01*
G02X1442209Y1009309I149J-133D01*
G01X1442559Y1009176D01*
G02X1442588Y1009162I-72J-186D01*
G01Y1001545D01*
G02X1442529Y1001403I-200J0D01*
G01X1442193Y1001067D01*
G03X1442134Y1000925I141J-142D01*
G01Y994657D01*
G02X1442126Y994601I-200J0D01*
G02X1442120Y994583I-193J54D01*
G01X1442105Y994547D01*
X1425862Y978304D01*
G03X1425803Y978162I141J-142D01*
G01Y963395D01*
G02X1425795Y963339I-200J0D01*
G02X1425789Y963321I-193J54D01*
G01X1425774Y963285D01*
X1422081Y959592D01*
G02X1421941Y959533I-142J141D01*
G01X1421822D01*
G02X1421689Y959582I-2J200D01*
G03X1420699Y959954I-990J-1131D01*
G03X1419197Y958452I0J-1502D01*
G03X1419619Y957408I1502J0D01*
G01X1419676Y957349D01*
X1419675Y957186D01*
X1415266Y952777D01*
G02X1415199Y952733I-141J142D01*
G01X1415165Y952719D01*
X1307976D01*
G02X1307920Y952727I0J200D01*
G02X1307902Y952733I54J193D01*
G01X1307866Y952748D01*
X1303585Y957029D01*
G02X1303541Y957096I142J141D01*
G01X1303527Y957130D01*
Y968217D01*
G02X1303575Y968345I200J-2D01*
G01X1303690Y968468D01*
Y968470D01*
X1303745Y968527D01*
G02X1303785Y968560I146J-137D01*
G01X1303787D01*
G02X1303808Y968572I109J-167D01*
G01X1303809D01*
X1303900Y968614D01*
X1303935Y968617D01*
G03X1305026Y969241I-132J1496D01*
G01X1305051Y969276D01*
X1305075Y969296D01*
G02X1305190Y969341I127J-155D01*
G01X1305192D01*
X1305208Y969340D01*
X1305556Y969329D01*
G02X1305639Y969302I-19J-199D01*
G01X1305661Y969289D01*
X1305696Y969254D01*
X1305709Y969232D01*
G03X1307000Y968498I1291J768D01*
G03Y971502I0J1502D01*
G03X1305767Y970858I0J-1502D01*
G01X1305752Y970836D01*
X1305733Y970820D01*
G02X1305596Y970772I-130J152D01*
G01X1305224Y970784D01*
X1305209Y970785D01*
X1305165Y970811D01*
G02X1305125Y970842I102J172D01*
G01X1305108Y970859D01*
X1305095Y970881D01*
G03X1303902Y971612I-1291J-768D01*
G01X1303901D01*
X1303862Y971615D01*
X1303830Y971630D01*
G02X1303768Y971674I83J182D01*
G01X1303706Y971741D01*
X1303575Y971881D01*
G02X1303527Y972010I152J130D01*
G01Y1000122D01*
G02X1303531Y1000159I200J-3D01*
G01Y1000161D01*
G02X1303584Y1000262I196J-39D01*
G01X1335389Y1032067D01*
G03X1335976Y1033483I-1414J1416D01*
G03X1333976Y1035484I-2001J0D01*
G01X1333974D01*
G03X1332559Y1034898I0J-2001D01*
G01X1304210Y1006550D01*
G02X1303527Y1006832I-283J283D01*
G01Y1034945D01*
G02X1303535Y1035001I200J0D01*
G01X1310362Y1058449D01*
G03X1310434Y1058738I-3771J1093D01*
G01X1310436Y1058746D01*
X1311193Y1061342D01*
G03X1311196Y1061352I-3726J1123D01*
G01Y1061353D01*
X1311198Y1061360D01*
G03X1311209Y1061397I-3724J1127D01*
G01Y1061399D01*
X1311363Y1061926D01*
G03X1311371Y1061990I-192J57D01*
G01X1311348Y1062520D01*
Y1062523D01*
G03X1311347Y1062561I-3891J-83D01*
G01X1311346Y1062579D01*
Y1062584D01*
X1311345Y1062596D01*
X1311337Y1062792D01*
X1310791Y1075481D01*
X1310682Y1078006D01*
Y1078007D01*
G03X1310680Y1078062I-3890J-114D01*
G01X1310643Y1078899D01*
G03X1310617Y1078990I-200J-8D01*
G01X1310208Y1079707D01*
X1310207Y1079709D01*
G03X1310175Y1079766I-3409J-1877D01*
G01X1310050Y1079985D01*
Y1079986D01*
X1309238Y1081409D01*
X1307047Y1085252D01*
X1307042Y1085287D01*
X1307039Y1085303D01*
Y1102686D01*
G02X1307239Y1102886I200J0D01*
G01X1324122D01*
G03X1325464Y1103442I-2J1902D01*
G01X1330199Y1108177D01*
G02X1330341Y1108236I142J-141D01*
G01X1331033D01*
G02X1331207Y1108135I0J-200D01*
G01X1331378Y1107834D01*
G02X1331377Y1107633I-173J-100D01*
G03X1331167Y1106867I1292J-766D01*
G03X1331176Y1106700I1502J-3D01*
G01X1331180Y1106663D01*
X1331161Y1106591D01*
X1330980Y1106341D01*
G02X1330860Y1106263I-162J118D01*
G01X1330859D01*
G03X1329803Y1105432I303J-1471D01*
G01X1329788Y1105400D01*
X1327983Y1103595D01*
G03X1327572Y1102604I991J-992D01*
G01Y1098156D01*
G03X1327983Y1097165I1402J1D01*
G01X1334021Y1091127D01*
G02X1334080Y1090985I-141J-142D01*
G01Y1058224D01*
G03X1334490Y1057234I1401J0D01*
G01X1342472Y1049252D01*
G03X1343462Y1048842I990J991D01*
G01X1348683D01*
G02X1348825Y1048783I0J-200D01*
G01X1378467Y1019140D01*
G02X1378526Y1018998I-141J-142D01*
G01Y1010699D01*
G03X1378937Y1009708I1402J1D01*
G01X1389695Y998950D01*
G03X1390685Y998540I990J991D01*
G01X1394344D01*
X1394377Y998528D01*
G03X1394885Y998439I509J1413D01*
G03Y1001443I0J1502D01*
G03X1394377Y1001354I1J-1502D01*
G01X1394344Y1001342D01*
X1391350D01*
G02X1391208Y1001401I0J200D01*
G01X1381389Y1011221D01*
G02X1381330Y1011363I141J142D01*
G01Y1019662D01*
G03X1380919Y1020653I-1402J-1D01*
G01X1350338Y1051234D01*
G03X1349348Y1051644I-990J-991D01*
G01X1344127D01*
G02X1343985Y1051703I0J200D01*
G01X1336941Y1058747D01*
G02X1336882Y1058889I141J142D01*
G01Y1091650D01*
G03X1336472Y1092640I-1401J0D01*
G01X1330435Y1098678D01*
G02X1330376Y1098820I141J142D01*
G01Y1101940D01*
G02X1330435Y1102082I200J0D01*
G01X1331770Y1103418D01*
X1331802Y1103433D01*
G03X1332664Y1104792I-640J1359D01*
G03X1332655Y1104959I-1502J3D01*
G01X1332651Y1104996D01*
X1332670Y1105068D01*
X1332851Y1105318D01*
G02X1332971Y1105396I162J-118D01*
G01X1332972D01*
G03X1333032Y1105410I-311J1469D01*
G01X1333034D01*
X1333071Y1105419D01*
X1333147Y1105409D01*
X1333421Y1105251D01*
G02X1333514Y1105134I-99J-174D01*
G01Y1105133D01*
G03X1334956Y1104050I1442J419D01*
G03X1335535Y1104166I0J1503D01*
G02X1335699Y1104162I78J-184D01*
G01X1336006Y1104016D01*
X1336061Y1103952D01*
X1336073Y1103910D01*
G03X1337427Y1102836I1440J425D01*
G01X1337428D01*
G02X1337578Y1102752I-13J-199D01*
G01X1337786Y1102460D01*
X1337801Y1102371D01*
X1337789Y1102327D01*
G03X1337732Y1101917I1446J-410D01*
G03X1340736I1502J0D01*
G03X1339321Y1103416I-1501J0D01*
G01X1339320D01*
G02X1339170Y1103500I13J199D01*
G01X1338962Y1103792D01*
X1338947Y1103881D01*
X1338959Y1103925D01*
G03X1339016Y1104335I-1446J410D01*
G03X1338953Y1104765I-1502J0D01*
G01X1338937Y1104818D01*
X1338964Y1104924D01*
X1339443Y1105403D01*
X1339490Y1105429D01*
X1339518Y1105436D01*
G03X1340630Y1106548I-349J1461D01*
G01X1340637Y1106576D01*
X1340663Y1106623D01*
X1340676Y1106636D01*
Y1108421D01*
G02X1340774Y1108593I200J0D01*
G01X1341115Y1108796D01*
X1341220Y1108798D01*
X1341267Y1108772D01*
G03X1341984Y1108590I717J1321D01*
G03X1342832Y1108852I0J1503D01*
G01X1342877Y1108883D01*
X1342989Y1108890D01*
X1343351Y1108699D01*
G02X1343458Y1108522I-93J-177D01*
G01Y1107721D01*
G02X1343399Y1107579I-200J0D01*
G01X1343179Y1107360D01*
G03X1342740Y1106300I1062J-1061D01*
G01Y1106298D01*
G03X1344241Y1104796I1502J0D01*
G03X1345303Y1105236I0J1502D01*
G01X1346021Y1105954D01*
G03X1346460Y1107014I-1062J1061D01*
G01Y1111869D01*
G03X1346021Y1112929I-1501J-1D01*
G01X1344951Y1113999D01*
G02X1344892Y1114141I141J142D01*
G01Y1114288D01*
G02X1345092Y1114488I200J0D01*
G01X1345125D01*
X1345157Y1114477D01*
G03X1345649Y1114394I492J1419D01*
G01X1345650D01*
G03X1347152Y1115896I0J1502D01*
G03X1346726Y1116944I-1502J0D01*
G02X1346669Y1117083I143J140D01*
G01Y1117293D01*
G03X1346712Y1117334I-1015J1107D01*
G01X1348760Y1119383D01*
G02X1348902Y1119442I142J-141D01*
G01X1353646D01*
G02X1353797Y1119374I1J-200D01*
G01X1353995Y1119148D01*
G02X1354043Y1118992I-150J-132D01*
G01Y1118991D01*
G03X1354031Y1118802I1490J-189D01*
G01Y1118801D01*
G03X1354475Y1117735I1502J0D01*
G02X1354534Y1117593I-141J-142D01*
G01Y1117309D01*
G02X1354475Y1117167I-200J0D01*
G03X1354031Y1116101I1058J-1066D01*
G03X1354104Y1115639I1502J1D01*
G01X1354117Y1115598D01*
X1354108Y1115513D01*
X1353910Y1115180D01*
X1353842Y1115131D01*
X1353799Y1115123D01*
G03X1352607Y1113929I283J-1475D01*
G01X1352597Y1113880D01*
X1352537Y1113804D01*
X1352139Y1113632D01*
X1352042Y1113639D01*
X1352000Y1113666D01*
G03X1351197Y1113899I-803J-1269D01*
G03X1350915Y1113872I2J-1502D01*
G01X1350877Y1113865D01*
X1350802Y1113879D01*
X1350507Y1114068D01*
X1350462Y1114130D01*
X1350453Y1114167D01*
G03X1348997Y1115299I-1456J-370D01*
G03X1347495Y1113797I0J-1502D01*
G03X1348025Y1112652I1502J0D01*
G02X1348096Y1112500I-129J-153D01*
G01Y1112194D01*
G02X1348025Y1112042I-200J1D01*
G03X1347495Y1110897I972J-1145D01*
G03X1348025Y1109752I1502J0D01*
G02X1348096Y1109600I-129J-153D01*
G01Y1109294D01*
G02X1348025Y1109142I-200J1D01*
G03X1347495Y1107997I972J-1145D01*
G03X1348997Y1106495I1502J0D01*
G03X1350450Y1107615I0J1503D01*
G01X1350459Y1107650D01*
X1350501Y1107710D01*
X1350784Y1107898D01*
X1350855Y1107914D01*
X1350891Y1107909D01*
G03X1351097Y1107895I205J1488D01*
G03X1351303Y1107909I1J1502D01*
G01X1351339Y1107914D01*
X1351410Y1107898D01*
X1351693Y1107710D01*
X1351735Y1107650D01*
X1351744Y1107615D01*
G03X1353197Y1106495I1453J383D01*
G03X1354699Y1107997I0J1502D01*
G03X1354331Y1108982I-1502J0D01*
G01X1354306Y1109011D01*
X1354281Y1109081D01*
X1354294Y1109432D01*
X1354325Y1109502D01*
X1354352Y1109528D01*
G03X1354799Y1110597I-1055J1069D01*
G03X1354422Y1111592I-1502J0D01*
G01X1354389Y1111629D01*
X1354366Y1111725D01*
X1354461Y1112095D01*
G02X1354587Y1112234I194J-49D01*
G03X1355584Y1113648I-504J1414D01*
G03X1355511Y1114110I-1502J-1D01*
G01X1355498Y1114151D01*
X1355507Y1114236D01*
X1355705Y1114569D01*
X1355773Y1114618D01*
X1355816Y1114626D01*
G03X1357035Y1116101I-283J1475D01*
G03X1356591Y1117167I-1502J0D01*
G02X1356532Y1117309I141J142D01*
G01Y1117593D01*
G02X1356591Y1117735I200J0D01*
G03X1357035Y1118801I-1058J1066D01*
G01Y1118803D01*
G03X1356984Y1119190I-1502J-1D01*
G01X1356977Y1119215D01*
Y1119242D01*
G02X1357177Y1119442I200J0D01*
G01X1357316D01*
G02X1357458Y1119383I0J-200D01*
G01X1360876Y1115964D01*
G03X1361938Y1115524I1062J1062D01*
G01X1371140D01*
G03X1372202Y1115964I0J1502D01*
G01X1373073Y1116835D01*
G02X1373215Y1116894I142J-141D01*
G01X1375973D01*
G02X1376135Y1116811I0J-200D01*
G01X1376324Y1116549D01*
G02X1376352Y1116369I-162J-117D01*
G03X1376276Y1115898I1426J-472D01*
G01Y1115896D01*
G03X1376971Y1114629I1502J0D01*
G01X1377010Y1114605D01*
X1377057Y1114528D01*
X1377097Y1114172D01*
G02X1377039Y1114009I-199J-21D01*
G01X1376025Y1112996D01*
G03X1375586Y1111936I1062J-1061D01*
G01Y1111662D01*
G02X1375479Y1111485I-200J0D01*
G01X1375117Y1111294D01*
X1375005Y1111301D01*
X1374960Y1111332D01*
G03X1374112Y1111594I-848J-1241D01*
G03Y1108590I0J-1502D01*
G03X1374960Y1108852I0J1503D01*
G01X1375005Y1108883D01*
X1375117Y1108890D01*
X1375479Y1108699D01*
G02X1375586Y1108522I-93J-177D01*
G01Y1106365D01*
G03X1378588I1501J0D01*
G01Y1111229D01*
G02X1378647Y1111371I200J0D01*
G01X1380483Y1113207D01*
G02X1380655Y1113263I141J-141D01*
G01X1380975Y1113214D01*
G02X1381122Y1113109I-30J-198D01*
G01Y1113108D01*
G03X1381484Y1112652I1335J688D01*
G02X1381555Y1112500I-129J-153D01*
G01Y1112194D01*
G02X1381484Y1112042I-200J1D01*
G03X1380954Y1110897I972J-1145D01*
G03X1381484Y1109752I1502J0D01*
G02X1381555Y1109600I-129J-153D01*
G01Y1109294D01*
G02X1381484Y1109142I-200J1D01*
G03X1380954Y1107997I972J-1145D01*
G03X1382456Y1106495I1502J0D01*
G03X1383909Y1107615I0J1503D01*
G01X1383918Y1107650D01*
X1383960Y1107710D01*
X1384243Y1107898D01*
X1384314Y1107914D01*
X1384350Y1107909D01*
G03X1384556Y1107895I205J1488D01*
G03X1384762Y1107909I1J1502D01*
G01X1384798Y1107914D01*
X1384869Y1107898D01*
X1385152Y1107710D01*
X1385194Y1107650D01*
X1385203Y1107615D01*
G03X1386656Y1106495I1453J383D01*
G03X1388158Y1107997I0J1502D01*
G03X1387790Y1108982I-1502J0D01*
G01X1387765Y1109011D01*
X1387740Y1109081D01*
X1387753Y1109432D01*
X1387784Y1109502D01*
X1387811Y1109528D01*
G03X1388258Y1110597I-1055J1069D01*
G03X1387881Y1111592I-1502J0D01*
G01X1387848Y1111629D01*
X1387825Y1111725D01*
X1387920Y1112095D01*
G02X1388046Y1112234I194J-49D01*
G03X1389043Y1113648I-504J1414D01*
G03X1388970Y1114110I-1502J-1D01*
G01X1388957Y1114151D01*
X1388966Y1114236D01*
X1389164Y1114569D01*
X1389232Y1114618D01*
X1389275Y1114626D01*
G03X1390494Y1116101I-283J1475D01*
G03X1390050Y1117167I-1502J0D01*
G02X1389991Y1117309I141J142D01*
G01Y1117593D01*
G02X1390050Y1117735I200J0D01*
G03X1390494Y1118801I-1058J1066D01*
G03X1387490I-1502J0D01*
G03X1387934Y1117735I1502J0D01*
G02X1387993Y1117593I-141J-142D01*
G01Y1117309D01*
G02X1387934Y1117167I-200J0D01*
G03X1387490Y1116101I1058J-1066D01*
G03X1387563Y1115639I1502J1D01*
G01X1387576Y1115598D01*
X1387567Y1115513D01*
X1387369Y1115180D01*
X1387301Y1115131D01*
X1387258Y1115123D01*
G03X1386066Y1113929I283J-1475D01*
G01X1386056Y1113880D01*
X1385996Y1113804D01*
X1385598Y1113632D01*
X1385501Y1113639D01*
X1385459Y1113666D01*
G03X1384656Y1113899I-803J-1269D01*
G03X1384374Y1113872I2J-1502D01*
G01X1384336Y1113865D01*
X1384261Y1113879D01*
X1383966Y1114068D01*
X1383921Y1114130D01*
X1383912Y1114167D01*
G03X1382456Y1115299I-1456J-370D01*
G03X1382235Y1115282I4J-1502D01*
G01X1382233D01*
G02X1382074Y1115328I-29J198D01*
G01X1381844Y1115526D01*
G02X1381774Y1115678I130J152D01*
G01Y1119965D01*
G03X1381335Y1121025I-1501J-1D01*
G01X1375093Y1127266D01*
G02X1375034Y1127408I141J142D01*
G01Y1159576D01*
G02X1375163Y1159763I200J0D01*
G01X1375573Y1159918D01*
X1375693Y1159888D01*
X1375734Y1159841D01*
G03X1376861Y1159332I1127J993D01*
G03Y1162336I0J1502D01*
G03X1375493Y1161454I0J-1502D01*
G02X1375326Y1161337I-182J82D01*
G01X1374921Y1161306D01*
X1374823Y1161355D01*
X1374793Y1161401D01*
G03X1374595Y1161646I-1261J-816D01*
G01X1372795Y1163446D01*
G03X1372752Y1163487I-1058J-1066D01*
G01Y1163697D01*
G02X1372809Y1163836I200J-1D01*
G03X1373235Y1164884I-1076J1048D01*
G03X1372865Y1165871I-1501J0D01*
G01Y1165872D01*
X1372864D01*
G02X1372816Y1166002I152J130D01*
G01Y1166266D01*
G02X1372864Y1166396I200J0D01*
G01X1372865Y1166397D01*
G03Y1168371I-1131J987D01*
G01Y1168372D01*
X1372864D01*
G02X1372816Y1168502I152J130D01*
G01Y1168766D01*
G02X1372864Y1168896I200J0D01*
G01X1372865Y1168897D01*
G03Y1170871I-1131J987D01*
G01Y1170872D01*
X1372864D01*
G02X1372816Y1171002I152J130D01*
G01Y1171266D01*
G02X1372864Y1171396I200J0D01*
G01X1372865Y1171397D01*
G03Y1173371I-1131J987D01*
G01Y1173372D01*
X1372864D01*
G02X1372816Y1173502I152J130D01*
G01Y1173766D01*
G02X1372864Y1173896I200J0D01*
G01X1372865Y1173897D01*
G03X1373235Y1174884I-1131J987D01*
G03X1371733Y1176386I-1502J0D01*
G03X1370746Y1176016I0J-1501D01*
G01X1370745D01*
Y1176015D01*
G02X1370615Y1175967I-130J152D01*
G01X1370351D01*
G02X1370221Y1176015I0J200D01*
G01X1370220Y1176016D01*
G03X1369233Y1176386I-987J-1131D01*
G03X1367731Y1174884I0J-1502D01*
G03X1368101Y1173897I1501J0D01*
G01Y1173896D01*
X1368102D01*
G02X1368150Y1173766I-152J-130D01*
G01Y1173502D01*
G02X1368102Y1173372I-200J0D01*
G01X1368101Y1173371D01*
G03Y1171397I1131J-987D01*
G01Y1171396D01*
X1368102D01*
G02X1368150Y1171266I-152J-130D01*
G01Y1171002D01*
G02X1368102Y1170872I-200J0D01*
G01X1368101Y1170871D01*
G03Y1168897I1131J-987D01*
G01Y1168896D01*
X1368102D01*
G02X1368150Y1168766I-152J-130D01*
G01Y1168502D01*
G02X1368102Y1168372I-200J0D01*
G01X1368101Y1168371D01*
G03Y1166397I1131J-987D01*
G01Y1166396D01*
X1368102D01*
G02X1368150Y1166266I-152J-130D01*
G01Y1166002D01*
G02X1368102Y1165872I-200J0D01*
G01X1368101Y1165871D01*
G03Y1163897I1131J-987D01*
G01Y1163896D01*
X1368102D01*
G02X1368150Y1163766I-152J-130D01*
G01Y1163502D01*
G02X1368102Y1163372I-200J0D01*
G01X1368101Y1163371D01*
G03X1367731Y1162384I1131J-987D01*
G03X1369233Y1160882I1502J0D01*
G03X1370281Y1161308I0J1502D01*
G02X1370420Y1161365I140J-143D01*
G01X1370630D01*
G03X1370671Y1161322I1107J1015D01*
G01X1371973Y1160021D01*
G02X1372032Y1159879I-141J-142D01*
G01Y1126701D01*
G03X1372471Y1125641I1501J1D01*
G01X1377873Y1120239D01*
G02X1377917Y1120021I-141J-142D01*
G01X1377894Y1119965D01*
X1377794Y1119898D01*
X1372510D01*
G03X1371448Y1119458I0J-1502D01*
G01X1370577Y1118587D01*
G02X1370435Y1118528I-142J141D01*
G01X1362643D01*
G02X1362501Y1118587I0J200D01*
G01X1359083Y1122005D01*
G03X1358023Y1122444I-1061J-1062D01*
G01X1349211D01*
G02X1349026Y1122568I0J200D01*
G01X1349002Y1122624D01*
X1349026Y1122742D01*
X1350735Y1124451D01*
G03X1351174Y1125511I-1062J1061D01*
G01Y1128983D01*
G03X1350735Y1130043I-1501J-1D01*
G01X1348461Y1132316D01*
G02X1348402Y1132458I141J142D01*
G01Y1147407D01*
G03X1347963Y1148467I-1501J-1D01*
G01X1342965Y1153464D01*
G02X1342906Y1153606I141J142D01*
G01Y1160579D01*
G02X1342989Y1160741I200J0D01*
G01X1343252Y1160930D01*
G02X1343432Y1160958I117J-162D01*
G03X1343903Y1160882I472J1426D01*
G01X1343905D01*
G03X1345407Y1162384I0J1502D01*
G03X1345037Y1163371I-1501J0D01*
G01Y1163372D01*
X1345036D01*
G02X1344988Y1163502I152J130D01*
G01Y1163766D01*
G02X1345036Y1163896I200J0D01*
G01X1345037Y1163897D01*
G03Y1165871I-1131J987D01*
G01Y1165872D01*
X1345036D01*
G02X1344988Y1166002I152J130D01*
G01Y1166266D01*
G02X1345036Y1166396I200J0D01*
G01X1345037Y1166397D01*
G03Y1168371I-1131J987D01*
G01Y1168372D01*
X1345036D01*
G02X1344988Y1168502I152J130D01*
G01Y1168766D01*
G02X1345036Y1168896I200J0D01*
G01X1345037Y1168897D01*
G03Y1170871I-1131J987D01*
G01Y1170872D01*
X1345036D01*
G02X1344988Y1171002I152J130D01*
G01Y1171266D01*
G02X1345036Y1171396I200J0D01*
G01X1345037Y1171397D01*
G03Y1173371I-1131J987D01*
G01Y1173372D01*
X1345036D01*
G02X1344988Y1173502I152J130D01*
G01Y1173766D01*
G02X1345036Y1173896I200J0D01*
G01X1345037Y1173897D01*
G03X1345407Y1174884I-1131J987D01*
G03X1343905Y1176386I-1502J0D01*
G03X1342918Y1176016I0J-1501D01*
G01X1342917D01*
Y1176015D01*
G02X1342787Y1175967I-130J152D01*
G01X1342523D01*
G02X1342393Y1176015I0J200D01*
G01X1342392Y1176016D01*
G03X1341405Y1176386I-987J-1131D01*
G03X1339903Y1174884I0J-1502D01*
G03X1340273Y1173897I1501J0D01*
G01Y1173896D01*
X1340274D01*
G02X1340322Y1173766I-152J-130D01*
G01Y1173502D01*
G02X1340274Y1173372I-200J0D01*
G01X1340273Y1173371D01*
G03Y1171397I1131J-987D01*
G01Y1171396D01*
X1340274D01*
G02X1340322Y1171266I-152J-130D01*
G01Y1171002D01*
G02X1340274Y1170872I-200J0D01*
G01X1340273Y1170871D01*
G03Y1168897I1131J-987D01*
G01Y1168896D01*
X1340274D01*
G02X1340322Y1168766I-152J-130D01*
G01Y1168502D01*
G02X1340274Y1168372I-200J0D01*
G01X1340273Y1168371D01*
G03Y1166397I1131J-987D01*
G01Y1166396D01*
X1340274D01*
G02X1340322Y1166266I-152J-130D01*
G01Y1166002D01*
G02X1340274Y1165872I-200J0D01*
G01X1340273Y1165871D01*
G03Y1163897I1131J-987D01*
G01Y1163896D01*
X1340274D01*
G02X1340322Y1163766I-152J-130D01*
G01X1340323Y1163466D01*
X1340297Y1163398D01*
X1340273Y1163371D01*
G03X1339904Y1162386I1132J-986D01*
G01Y1152899D01*
G03X1340343Y1151839I1501J1D01*
G01X1345341Y1146842D01*
G02X1345400Y1146700I-141J-142D01*
G01Y1131751D01*
G03X1345839Y1130691I1501J1D01*
G01X1346130Y1130400D01*
G02X1346189Y1130248I-141J-142D01*
G01X1346171Y1129909D01*
X1346133Y1129834D01*
X1346100Y1129807D01*
G03X1345732Y1129408I1199J-1476D01*
G01X1345703Y1129365D01*
X1345609Y1129318D01*
X1345215Y1129341D01*
G02X1345050Y1129446I11J200D01*
G03X1343725Y1130240I-1325J-709D01*
G03Y1127236I0J-1502D01*
G03X1343886Y1127245I-3J1502D01*
G02X1344088Y1127132I21J-199D01*
G01X1344251Y1126792D01*
G02X1344212Y1126564I-180J-86D01*
G01X1338659Y1121012D01*
G03X1338102Y1119667I1345J-1345D01*
G01Y1113559D01*
G02X1338043Y1113417I-200J0D01*
G01X1336794Y1112167D01*
G02X1336652Y1112108I-142J141D01*
G01X1331887D01*
X1331878Y1112099D01*
G02X1331736Y1112040I-142J141D01*
G01X1330223D01*
G02X1330042Y1112154I0J200D01*
G01X1329862Y1112535D01*
X1329876Y1112648D01*
X1329914Y1112694D01*
G03X1330256Y1113648I-1160J954D01*
G03X1328754Y1115150I-1502J0D01*
G03X1327767Y1114780I0J-1501D01*
G01X1327766D01*
Y1114779D01*
G02X1327636Y1114731I-130J152D01*
G01X1327372D01*
G02X1327242Y1114779I0J200D01*
G01X1327241Y1114780D01*
G03X1326254Y1115150I-987J-1131D01*
G03Y1112146I0J-1502D01*
G03X1327241Y1112516I0J1501D01*
G01X1327242D01*
Y1112517D01*
G02X1327372Y1112565I130J-152D01*
G01X1327636D01*
G02X1327766Y1112517I0J-200D01*
G01X1327767Y1112516D01*
G03X1328154Y1112271I988J1132D01*
G01X1328155D01*
G02X1328272Y1112116I-81J-183D01*
G01X1328321Y1111779D01*
G02X1328251Y1111597I-198J-28D01*
G03X1328125Y1111483I1212J-1466D01*
G01X1323390Y1106747D01*
G02X1323248Y1106688I-142J141D01*
G01X1322740D01*
G02X1322568Y1106786I0J200D01*
G01X1322365Y1107128D01*
X1322363Y1107233D01*
X1322389Y1107280D01*
G03X1322571Y1107997I-1321J717D01*
G03X1322203Y1108982I-1502J0D01*
G01X1322178Y1109011D01*
X1322153Y1109081D01*
X1322166Y1109432D01*
X1322197Y1109502D01*
X1322224Y1109528D01*
G03X1322671Y1110597I-1055J1069D01*
G03X1322294Y1111592I-1502J0D01*
G01X1322261Y1111629D01*
X1322238Y1111725D01*
X1322333Y1112095D01*
G02X1322459Y1112234I194J-49D01*
G03X1323456Y1113648I-504J1414D01*
G03X1323383Y1114110I-1502J-1D01*
G01X1323370Y1114151D01*
X1323379Y1114236D01*
X1323577Y1114569D01*
X1323645Y1114618D01*
X1323688Y1114626D01*
G03X1324907Y1116101I-283J1475D01*
G03X1324463Y1117167I-1502J0D01*
G02X1324404Y1117309I141J142D01*
G01Y1117593D01*
G02X1324463Y1117735I200J0D01*
G03X1324907Y1118801I-1058J1066D01*
G03X1321903I-1502J0D01*
G03X1322347Y1117735I1502J0D01*
G02X1322406Y1117593I-141J-142D01*
G01Y1117309D01*
G02X1322347Y1117167I-200J0D01*
G03X1321903Y1116101I1058J-1066D01*
G03X1321976Y1115639I1502J1D01*
G01X1321989Y1115598D01*
X1321980Y1115513D01*
X1321782Y1115180D01*
X1321714Y1115131D01*
X1321671Y1115123D01*
G03X1320479Y1113929I283J-1475D01*
G01X1320469Y1113880D01*
X1320409Y1113804D01*
X1320011Y1113632D01*
X1319914Y1113639D01*
X1319872Y1113666D01*
G03X1319069Y1113899I-803J-1269D01*
G03X1318787Y1113872I2J-1502D01*
G01X1318749Y1113865D01*
X1318674Y1113879D01*
X1318379Y1114068D01*
X1318334Y1114130D01*
X1318325Y1114167D01*
G03X1316869Y1115299I-1456J-370D01*
G03X1315367Y1113797I0J-1502D01*
G03X1315897Y1112652I1502J0D01*
G02X1315968Y1112500I-129J-153D01*
G01Y1112194D01*
G02X1315897Y1112042I-200J1D01*
G03X1315367Y1110897I972J-1145D01*
G03X1315897Y1109752I1502J0D01*
G02X1315968Y1109600I-129J-153D01*
G01Y1109294D01*
G02X1315897Y1109142I-200J1D01*
G03X1315367Y1107997I972J-1145D01*
G03X1315549Y1107280I1503J0D01*
G01X1315575Y1107233D01*
X1315573Y1107128D01*
X1315370Y1106786D01*
G02X1315198Y1106688I-172J102D01*
G01X1307239D01*
G02X1307039Y1106888I0J200D01*
G01Y1127806D01*
G02X1307189Y1127991I200J-9D01*
G03Y1154057I-2661J13033D01*
G02X1307039Y1154242I50J194D01*
G01Y1278417D01*
G02X1307098Y1278559I200J0D01*
G01X1308380Y1279841D01*
G02X1308522Y1279900I142J-141D01*
G01X1311517D01*
G03X1311659Y1279959I0J200D01*
G01X1312641Y1280941D01*
G03X1312700Y1281083I-141J142D01*
G01Y1298092D01*
G02X1312759Y1298234I200J0D01*
G01X1320997Y1306473D01*
G02X1321139Y1306532I142J-141D01*
G01X1409190D01*
G02X1409236Y1306483I-121J-159D01*
G01X1409421Y1306205D01*
G02X1409448Y1306044I-166J-111D01*
G01X1409438Y1306014D01*
X1409437Y1306013D01*
G03X1409314Y1305418I1380J-595D01*
G01Y1305417D01*
G03X1412320I1503J0D01*
G03X1412196Y1306013I-1503J-2D01*
G01Y1306014D01*
X1412195Y1306016D01*
G02X1412213Y1306204I184J77D01*
G01X1412286Y1306315D01*
X1412368Y1306439D01*
G02X1412389Y1306464I163J-116D01*
G01X1412398Y1306473D01*
G02X1412540Y1306532I142J-141D01*
G01X1429030D01*
G02X1429172Y1306473I0J-200D01*
G01X1429715Y1305930D01*
G02X1429774Y1305788I-141J-142D01*
G01Y1302541D01*
G02X1429749Y1302443I-200J-1D01*
G03X1429703Y1302354I1330J-744D01*
G02X1429695Y1302349I-110J167D01*
G01X1429652Y1302323D01*
X1429639Y1302317D01*
G02X1429463Y1302327I-78J184D01*
G01X1429459Y1302330D01*
X1429458D01*
X1429434Y1302344D01*
G02X1429397Y1302372I101J173D01*
G01X1429382Y1302387D01*
X1429356Y1302425D01*
X1429350Y1302437D01*
G03X1428009Y1303262I-1341J-677D01*
G03X1426701Y1302500I0J-1504D01*
G01X1426689Y1302479D01*
X1426674Y1302462D01*
G02X1426639Y1302432I-147J136D01*
G01X1426511Y1302350D01*
X1426456Y1302348D01*
X1426168Y1302334D01*
G02X1426124Y1302337I-8J200D01*
G02X1426067Y1302356I34J197D01*
G01X1426053Y1302363D01*
G02X1425996Y1302415I104J171D01*
G01X1425990Y1302425D01*
G03X1424732Y1303105I-1258J-824D01*
G03X1423230Y1301603I0J-1502D01*
G01Y1301600D01*
G03X1423293Y1301170I1502J0D01*
G01X1423297Y1301158D01*
G02X1423299Y1301077I-195J-45D01*
G01X1423291Y1301032D01*
X1423072Y1300737D01*
G02X1422912Y1300656I-161J119D01*
G01X1422845D01*
G02X1422809Y1300660I4J200D01*
G01X1422773Y1300668D01*
G02X1422654Y1300752I48J194D01*
G01X1422589Y1300866D01*
G02X1422570Y1300928I179J89D01*
G01X1422565Y1300962D01*
X1422574Y1301001D01*
X1422581Y1301030D01*
X1422590Y1301057D01*
X1422595Y1301069D01*
X1422596Y1301071D01*
G03X1422740Y1301712I-1358J642D01*
G03X1421238Y1303214I-1502J0D01*
G03X1419736Y1301728I0J-1502D01*
G01Y1301710D01*
G03X1419822Y1301210I1502J1D01*
G01X1419826Y1301198D01*
X1419836Y1301154D01*
G02X1419808Y1301018I-197J-30D01*
G01X1419780Y1300976D01*
X1419760Y1300947D01*
X1419609Y1300728D01*
X1419594Y1300714D01*
X1419566Y1300686D01*
X1419530Y1300671D01*
G02X1419454Y1300656I-76J185D01*
G01X1419288D01*
G02X1419116Y1300755I1J200D01*
G01X1419057Y1300857D01*
G02X1419034Y1300998I173J101D01*
G01X1419039Y1301026D01*
X1419051Y1301050D01*
G03X1419213Y1301728I-1340J679D01*
G01Y1301746D01*
G03X1417711Y1303231I-1502J-17D01*
G03X1416209Y1301729I0J-1502D01*
G03X1416306Y1301198I1502J0D01*
G01X1416310Y1301188D01*
G02X1416318Y1301101I-191J-61D01*
G01X1416312Y1301055D01*
X1416110Y1300762D01*
G03X1416105Y1300754I167J-110D01*
G01X1416092Y1300732D01*
X1416058Y1300698D01*
X1416034Y1300684D01*
G02X1416009Y1300671I-105J171D01*
G02X1415972Y1300660I-75J185D01*
G02X1415933Y1300656I-40J196D01*
G01X1389440D01*
G02X1389240Y1300856I0J200D01*
G01Y1301120D01*
G02X1389299Y1301262I200J0D01*
G01X1390114Y1302077D01*
G03X1390554Y1303139I-1062J1062D01*
G03X1389052Y1304640I-1501J0D01*
G37*
G36*
G01X1386548Y327688D02*
G03I-577J0D01*
G37*
G36*
G01X1398127Y390484D02*
G03I-577J0D01*
G37*
G36*
G01X1389872Y408443D02*
G03I-577J0D01*
G37*
G36*
G01X1388391Y397136D02*
G03I-577J0D01*
G37*
G36*
G01X1387386Y414173D02*
G03I-577J0D01*
G37*
G36*
G01X1389365Y428348D02*
G03I-577J0D01*
G37*
G36*
G01X1463561Y601227D02*
X1463457Y601184D01*
G02X1463238Y601227I-78J184D01*
G01X1460817Y603649D01*
G02X1460813Y603653I139J143D01*
G03X1460258Y604004I-954J-894D01*
G02X1460252Y604006I60J191D01*
G01X1460191Y604070D01*
X1460106Y604355D01*
G02X1460101Y604448I192J57D01*
G01X1460109Y604494D01*
X1460139Y604533D01*
G03X1460446Y605443I-1195J910D01*
G03X1457442I-1502J0D01*
G03X1457695Y604609I1502J0D01*
G01X1457696Y604608D01*
X1457701Y604600D01*
G02X1457706Y604590I-176J-94D01*
G02X1457729Y604508I-176J-94D01*
G01X1457732Y604452D01*
X1457537Y604085D01*
G02X1457534Y604080I-173J100D01*
G02X1457524Y604066I-168J109D01*
G01X1452365D01*
G02X1452351Y604086I156J124D01*
G01X1452180Y604407D01*
G02X1452159Y604508I179J90D01*
G01X1452162Y604562D01*
X1452192Y604608D01*
X1452193Y604609D01*
G03X1452446Y605443I-1249J834D01*
G03X1449442I-1502J0D01*
G03X1449695Y604609I1502J0D01*
G01X1449696Y604608D01*
X1449701Y604600D01*
G02X1449706Y604590I-176J-94D01*
G02X1449729Y604508I-176J-94D01*
G01X1449732Y604452D01*
X1449537Y604085D01*
G02X1449534Y604080I-173J100D01*
G02X1449524Y604066I-168J109D01*
G01X1441143D01*
G02X1441001Y604125I0J200D01*
G01X1440250Y604876D01*
Y604896D01*
G03X1440446Y605637I-1306J742D01*
G03X1438944Y607139I-1502J0D01*
G01X1438942D01*
G03X1437751Y606551I1J-1502D01*
G01X1437726Y606518D01*
X1437619Y606458D01*
G02X1437537Y606434I-96J175D01*
G01X1437331Y606417D01*
G02X1437174Y606475I-16J199D01*
G01X1436575Y607074D01*
G03X1434944Y607750I-1632J-1631D01*
G03X1433194Y606946I0J-2307D01*
G01X1433167Y606914D01*
X1433091Y606878D01*
X1432827Y606869D01*
X1432813D01*
G02X1432778Y606871I-6J200D01*
G01X1432575Y607074D01*
G03X1430944Y607750I-1632J-1631D01*
G03X1428638Y605443I0J-2306D01*
G03X1429313Y603812I2306J-1D01*
G01X1433216Y599909D01*
G03X1434846Y599234I1630J1631D01*
G01X1435137D01*
G02X1435279Y599175I0J-200D01*
G01X1435542Y598911D01*
G02Y598629I-142J-141D01*
G01X1435503Y598590D01*
X1435399Y598562D01*
X1435367Y598571D01*
G03X1434945Y598632I-424J-1441D01*
G01X1434944D01*
G03X1434863Y598630I-3J-1502D01*
G01X1434852Y598629D01*
G03X1433442Y597130I92J-1499D01*
G03X1436446I1502J0D01*
G03X1436391Y597533I-1504J0D01*
G01Y597534D01*
G02X1436442Y597728I193J53D01*
G02X1436725I141J-141D01*
G01X1436945Y597508D01*
G03X1437362Y597178I1630J1632D01*
G02X1437455Y597035I-105J-170D01*
G03X1438944Y595730I1489J197D01*
G03X1440350Y596703I0J1502D01*
G01X1440371Y596761D01*
X1440474Y596832D01*
X1442063D01*
G02X1442222Y596753I0J-200D01*
G01X1442297Y596655D01*
G02X1442331Y596503I-163J-116D01*
G01X1442326Y596486D01*
G03X1442273Y596092I1449J-396D01*
G01Y596089D01*
G03X1445277I1502J0D01*
G01Y596092D01*
G03X1445224Y596486I-1502J-2D01*
G01X1445219Y596503D01*
G02X1445253Y596655I197J36D01*
G01X1445328Y596753D01*
G02X1445487Y596832I159J-121D01*
G01X1447377D01*
X1447491Y596727D01*
X1447496Y596676D01*
G03X1450492Y596674I1498J106D01*
G01Y596678D01*
X1450497Y596727D01*
X1450611Y596832D01*
X1453219D01*
G02X1453354Y596779I-1J-200D01*
G01X1453390Y596746D01*
G02X1453446Y596627I-143J-140D01*
G01Y596621D01*
G03X1454944Y595227I1498J108D01*
G01X1454945D01*
G03X1455870Y595546I-1J1502D01*
G01X1455871Y595547D01*
G02X1456007Y595589I123J-158D01*
G01X1456041Y595587D01*
X1456108Y595557D01*
X1462156Y589510D01*
G02X1462214Y589368I-142J-141D01*
G01Y446391D01*
G02X1462193Y446301I-200J-1D01*
G02X1462156Y446250I-178J91D01*
G01X1455010Y439105D01*
G03X1454346Y437502I1603J-1603D01*
G01Y434353D01*
G02X1454324Y434262I-200J0D01*
G02X1454288Y434212I-178J90D01*
G01X1452667Y432591D01*
G02X1452617Y432555I-140J142D01*
G02X1452526Y432533I-91J178D01*
G01X1424313D01*
G02X1424171Y432592I0J200D01*
G01X1418695Y438068D01*
G02X1418638Y438228I142J141D01*
G01X1418670Y438578D01*
X1418715Y438655D01*
X1418752Y438680D01*
G03X1419405Y439919I-849J1239D01*
G03X1417903Y441421I-1502J0D01*
G03X1416664Y440768I0J-1502D01*
G01X1416639Y440731D01*
X1416562Y440686D01*
X1416212Y440654D01*
G02X1416052Y440711I-19J199D01*
G01X1395433Y461329D01*
G02X1395374Y461471I141J142D01*
G01Y491479D01*
G03X1395339Y491779I-1306J0D01*
G01X1395334Y491802D01*
Y493263D01*
G02X1395338Y493301I200J-2D01*
G02X1395391Y493403I196J-37D01*
G01X1398321Y496333D01*
G02X1398423Y496386I139J-143D01*
G02X1398461Y496390I40J-196D01*
G01X1400627D01*
G02X1400656Y496388I1J-200D01*
G01X1405461Y491583D01*
X1405474Y491544D01*
G03X1406910Y490480I1436J437D01*
G03X1408412Y491982I0J1502D01*
G03X1407348Y493418I-1501J0D01*
G01X1407309Y493431D01*
X1406813Y493927D01*
G02X1406822Y494019I198J27D01*
G01X1406873Y494168D01*
X1406939Y494360D01*
G02X1407000Y494449I189J-64D01*
G01X1407022Y494467D01*
X1407073Y494488D01*
X1407102Y494492D01*
G03X1408412Y495982I-192J1490D01*
G03X1406910Y497484I-1502J0D01*
G03X1405420Y496174I0J-1502D01*
G01X1405416Y496145D01*
X1405395Y496094D01*
X1405377Y496072D01*
G02X1405288Y496011I-153J128D01*
G01X1405096Y495945D01*
X1404947Y495894D01*
G02X1404855Y495885I-65J189D01*
G01X1399660Y501080D01*
G02X1399658Y501107I198J28D01*
G01Y516993D01*
G03X1399287Y517889I-1267J0D01*
G01X1396818Y520357D01*
X1396538Y520637D01*
G02X1396486Y520728I142J141D01*
G02X1396480Y520764I194J51D01*
G01Y525834D01*
G02X1396533Y525969I200J-1D01*
G01X1396791Y526204D01*
X1396798Y526210D01*
X1396878Y526236D01*
X1396921Y526232D01*
G03X1397079Y526224I155J1494D01*
G03Y529228I0J1502D01*
G03X1396921Y529220I-3J-1502D01*
G01X1396878Y529216D01*
X1396798Y529242D01*
X1396791Y529248D01*
X1396533Y529483D01*
G02X1396480Y529618I147J136D01*
G01Y540891D01*
G02X1396513Y541000I200J-1D01*
G01X1396527Y541021D01*
X1396931Y541423D01*
G02X1396940Y541430I127J-154D01*
G01X1397988D01*
G03X1398912Y541813I0J1306D01*
G01X1401318Y544219D01*
G03X1401665Y544840I-924J924D01*
G01X1401672Y544868D01*
X1401698Y544915D01*
X1401902Y545119D01*
G03X1402197Y545584I-896J895D01*
G03X1402272Y546015I-1191J429D01*
G01Y563928D01*
G03X1402197Y564359I-1266J2D01*
G03X1401902Y564824I-1191J-430D01*
G01X1398128Y568597D01*
X1397902Y568823D01*
G02X1397844Y568965I142J141D01*
G01Y619757D01*
G02X1397941Y619928I200J0D01*
G01X1398002Y619965D01*
G02X1398061Y619986I96J-176D01*
G02X1398097Y619989I35J-197D01*
G01X1398208D01*
X1398251Y619979D01*
X1398274Y619968D01*
G03X1398946Y619809I673J1343D01*
G03Y622813I0J1502D01*
G03X1398233Y622633I0J-1502D01*
G01X1398232D01*
G02X1398131Y622609I-95J176D01*
G01X1398081Y622610D01*
X1397941Y622694D01*
G02X1397844Y622865I103J171D01*
G01Y623757D01*
G02X1397941Y623928I200J0D01*
G01X1398002Y623965D01*
G02X1398061Y623986I96J-176D01*
G02X1398097Y623989I35J-197D01*
G01X1398208D01*
X1398251Y623979D01*
X1398274Y623968D01*
G03X1398946Y623809I673J1343D01*
G03Y626813I0J1502D01*
G03X1398233Y626633I0J-1502D01*
G01X1398232D01*
G02X1398131Y626609I-95J176D01*
G01X1398081Y626610D01*
X1397941Y626694D01*
G02X1397844Y626865I103J171D01*
G01Y627757D01*
G02X1397941Y627928I200J0D01*
G01X1398002Y627965D01*
G02X1398061Y627986I96J-176D01*
G02X1398097Y627989I35J-197D01*
G01X1398208D01*
X1398251Y627979D01*
X1398274Y627968D01*
G03X1398946Y627809I673J1343D01*
G03X1400448Y629311I0J1502D01*
G03X1399396Y630744I-1502J0D01*
G01X1399395D01*
X1399384Y630748D01*
G02X1399310Y630797I71J187D01*
G01X1399309Y630798D01*
G02X1399268Y630861I144J139D01*
G02X1399260Y630888I187J70D01*
G01X1399190Y631168D01*
Y631170D01*
X1399178Y631222D01*
G02X1399192Y631356I194J47D01*
G02X1399202Y631373I177J-93D01*
G01X1399215Y631393D01*
X1406452Y638630D01*
G02X1406463Y638640I140J-143D01*
G02X1406554Y638683I128J-154D01*
G02X1406591Y638686I35J-197D01*
G01X1408728D01*
G03X1409156Y638761I-1J1266D01*
G03X1409621Y639056I-430J1191D01*
G01X1410713Y640148D01*
G03X1411084Y641044I-896J896D01*
G01Y641984D01*
G02X1411085Y642002I200J-2D01*
G02X1411135Y642117I199J-18D01*
G01X1411159Y642142D01*
X1411200Y642173D01*
X1411210Y642179D01*
G03X1411456Y642371I-650J1087D01*
G01X1416680Y647594D01*
G02X1416682Y647596I142J-140D01*
G02X1416789Y647650I139J-143D01*
G02X1416822Y647653I35J-197D01*
G01X1461030D01*
G02X1461062Y647650I-3J-200D01*
G01X1461064D01*
G02X1461170Y647596I-34J-197D01*
G01X1463523Y645243D01*
G02X1463576Y645141I-143J-139D01*
G02X1463580Y645103I-196J-40D01*
G01Y601312D01*
G02X1463561Y601227I-200J0D01*
G37*
G36*
G01X1446335Y1110768D02*
G03X1446306Y1110872I-200J0D01*
G01X1446291Y1110896D01*
X1446284Y1110921D01*
G02X1446276Y1110976I192J56D01*
G01Y1113330D01*
G02X1446335Y1113472I200J0D01*
G01X1446712Y1113848D01*
G03X1447152Y1114910I-1062J1062D01*
G01Y1121373D01*
G03X1446712Y1122435I-1502J0D01*
G01X1446335Y1122811D01*
G02X1446276Y1122953I141J142D01*
G01Y1204366D01*
G03X1446217Y1204508I-200J0D01*
G01X1435793Y1214932D01*
G03X1435651Y1214991I-142J-141D01*
G01X1389122D01*
G02X1389031Y1215013I0J200D01*
G02X1388981Y1215049I90J178D01*
G01X1385221Y1218809D01*
G02X1385185Y1218859I142J140D01*
G02X1385163Y1218950I178J91D01*
G01Y1277449D01*
G02X1385222Y1277591I200J0D01*
G01X1393265Y1285634D01*
G03X1393324Y1285776I-141J142D01*
G01Y1296017D01*
G02X1393383Y1296159I200J0D01*
G01X1396614Y1299390D01*
G02X1396756Y1299449I142J-141D01*
G01X1495709D01*
G02X1495809Y1299422I0J-200D01*
G01X1554354Y1260303D01*
G02X1554440Y1260170I-111J-166D01*
G01Y1260168D01*
G02X1554443Y1260137I-197J-35D01*
G01Y1260038D01*
G02X1554371Y1259884I-200J0D01*
G01X1554133Y1259687D01*
G02X1553967Y1259645I-127J154D01*
G03X1553740Y1259667I-229J-1180D01*
G03Y1257263I0J-1202D01*
G03X1553884Y1257272I-3J1202D01*
G01X1553930Y1257278D01*
X1554020Y1257246D01*
X1554306Y1256945D01*
X1554334Y1256856D01*
X1554329Y1256826D01*
G03X1554308Y1256594I1281J-233D01*
G03X1554329Y1256362I1302J1D01*
G01Y1256359D01*
X1554334Y1256333D01*
X1554306Y1256244D01*
X1554052Y1255978D01*
G02X1553883Y1255917I-145J137D01*
G03X1553740Y1255926I-147J-1193D01*
G03Y1253522I0J-1202D01*
G03X1553883Y1253531I-4J1202D01*
G02X1554052Y1253470I24J-198D01*
G01X1554306Y1253204D01*
X1554334Y1253115D01*
X1554329Y1253087D01*
G03X1554308Y1252854I1281J-233D01*
G03X1554329Y1252622I1302J1D01*
G01Y1252619D01*
X1554334Y1252593D01*
X1554306Y1252504D01*
X1554052Y1252238D01*
G02X1553883Y1252177I-145J137D01*
G03X1553740Y1252186I-147J-1193D01*
G03Y1249782I0J-1202D01*
G03X1554129Y1249846I2J1202D01*
G02X1554158Y1249854I68J-188D01*
G01X1554210Y1249863D01*
G02X1554410Y1249663I0J-200D01*
G01X1554399Y1249608D01*
G02X1554390Y1249574I-197J34D01*
G03X1554368Y1249512I1216J-466D01*
G03X1554305Y1249125I1240J-400D01*
G01Y1248836D01*
G02X1554239Y1248687I-200J0D01*
G01X1553987Y1248460D01*
X1553905Y1248434D01*
X1553864Y1248439D01*
G03X1553740Y1248445I-120J-1196D01*
G03Y1246041I0J-1202D01*
G03X1553864Y1246047I4J1202D01*
G01X1553905Y1246052D01*
X1553987Y1246026D01*
X1554239Y1245799D01*
G02X1554305Y1245650I-134J-149D01*
G01Y1245373D01*
G03X1554327Y1245137I1303J2D01*
G01Y1245133D01*
X1554331Y1245112D01*
X1554303Y1245023D01*
X1554016Y1244723D01*
X1553928Y1244691D01*
X1553881Y1244697D01*
G03X1553740Y1244705I-138J-1194D01*
G03Y1242301I0J-1202D01*
G03X1553883Y1242310I-4J1202D01*
G02X1554052Y1242249I24J-198D01*
G01X1554306Y1241983D01*
X1554334Y1241894D01*
X1554329Y1241866D01*
G03X1554308Y1241633I1281J-233D01*
G03X1554330Y1241398I1302J3D01*
G01Y1241394D01*
X1554334Y1241372D01*
X1554306Y1241283D01*
X1554052Y1241017D01*
G02X1553883Y1240956I-145J137D01*
G03X1553740Y1240965I-147J-1193D01*
G03X1554942Y1239763I0J-1202D01*
G03X1554933Y1239906I-1202J-4D01*
G02X1554994Y1240075I198J24D01*
G01X1555260Y1240329D01*
X1555349Y1240357D01*
X1555373Y1240353D01*
G03X1555610Y1240331I238J1280D01*
G03X1555811Y1240347I-2J1302D01*
G01X1555859Y1240354D01*
X1555903Y1240340D01*
G02X1555983Y1240291I-62J-190D01*
G01X1556227Y1240047D01*
G02X1556284Y1239885I-142J-141D01*
G03X1556278Y1239763I1196J-120D01*
G03X1557480Y1238561I1202J0D01*
G03X1557602Y1238567I2J1202D01*
G02X1557764Y1238510I21J-199D01*
G01X1557791Y1238483D01*
G03X1557840Y1238446I144J139D01*
G01X1557841D01*
X1557870Y1238430D01*
X1557889Y1238412D01*
G02X1557915Y1238381I-139J-143D01*
G01X1558040Y1238149D01*
G02X1558054Y1238104I-183J-82D01*
G01X1558059Y1238079D01*
X1558055Y1238046D01*
Y1238045D01*
G03X1558046Y1237893I1294J-153D01*
G01Y1237616D01*
G02X1557980Y1237467I-200J0D01*
G01X1557728Y1237240D01*
X1557646Y1237214D01*
X1557605Y1237219D01*
G03X1557480Y1237225I-120J-1196D01*
G03Y1234821I0J-1202D01*
G03X1557605Y1234827I5J1202D01*
G01X1557646Y1234832D01*
X1557728Y1234806D01*
X1557980Y1234579D01*
G02X1558046Y1234430I-134J-149D01*
G01Y1234153D01*
G03X1558068Y1233917I1303J2D01*
G01Y1233913D01*
X1558072Y1233892D01*
X1558044Y1233803D01*
X1557757Y1233503D01*
X1557669Y1233471D01*
X1557622Y1233477D01*
G03X1557480Y1233485I-139J-1194D01*
G03X1558682Y1232283I0J-1202D01*
G03X1558674Y1232426I-1202J4D01*
G01X1558668Y1232473D01*
X1558700Y1232561D01*
X1558999Y1232848D01*
X1559088Y1232876D01*
X1559106Y1232873D01*
G03X1559349Y1232850I244J1280D01*
G03X1559584Y1232871I2J1302D01*
G01X1559586D01*
X1559611Y1232875D01*
X1559700Y1232848D01*
X1559966Y1232593D01*
G02X1560027Y1232427I-138J-145D01*
G01Y1232426D01*
G03X1560018Y1232283I1193J-147D01*
G03X1561220Y1233485I1202J0D01*
G03X1561078Y1233476I5J-1202D01*
G01X1561076D01*
X1561030Y1233471D01*
X1560942Y1233503D01*
X1560655Y1233803D01*
X1560627Y1233893D01*
X1560635Y1233939D01*
G03X1560652Y1234117I-1285J213D01*
G01Y1234430D01*
G02X1560718Y1234579I200J0D01*
G01X1560939Y1234778D01*
G02X1561093Y1234828I134J-149D01*
G01X1561094D01*
G03X1561220Y1234821I130J1195D01*
G03X1562422Y1236023I0J1202D01*
G01Y1236025D01*
G03X1562357Y1236414I-1202J-1D01*
G02X1562349Y1236444I189J66D01*
G01X1562340Y1236495D01*
G02X1562540Y1236695I200J0D01*
G01X1562596Y1236684D01*
G02X1562628Y1236675I-38J-196D01*
G03X1562781Y1236628I458J1219D01*
G03X1563304Y1236608I310J1265D01*
G01X1563350Y1236616D01*
X1563440Y1236588D01*
X1563707Y1236334D01*
G02X1563767Y1236168I-139J-144D01*
G01Y1236166D01*
G03X1563758Y1236023I1193J-147D01*
G03X1564960Y1234821I1202J0D01*
G03X1565084Y1234828I-6J1202D01*
G01X1565086D01*
G02X1565240Y1234778I20J-199D01*
G01X1565461Y1234579D01*
G02X1565527Y1234430I-134J-149D01*
G01Y1234155D01*
G03Y1234153I1303J-1D01*
G01X1565528Y1234137D01*
Y1234130D01*
G03X1565537Y1233996I1302J20D01*
G01Y1233994D01*
X1565538Y1233985D01*
X1565539Y1233980D01*
G03X1565542Y1233957I1293J157D01*
G02X1565543Y1233951I-196J-36D01*
G03X1565545Y1233939I1285J208D01*
G01X1565553Y1233892D01*
X1565525Y1233802D01*
X1565270Y1233536D01*
G02X1565104Y1233476I-144J139D01*
G01X1565103D01*
G03X1564960Y1233485I-147J-1193D01*
G03X1566162Y1232283I0J-1202D01*
G03X1566154Y1232426I-1202J4D01*
G01X1566148Y1232473D01*
X1566180Y1232561D01*
X1566480Y1232848D01*
X1566569Y1232876D01*
X1566592Y1232872D01*
G03X1566830Y1232850I238J1280D01*
G03X1567065Y1232872I-3J1302D01*
G01X1567069D01*
X1567091Y1232876D01*
X1567180Y1232848D01*
X1567480Y1232561D01*
X1567512Y1232473D01*
X1567506Y1232426D01*
G03X1567498Y1232283I1194J-139D01*
G03X1568700Y1233485I1202J0D01*
G03X1568558Y1233476I5J-1202D01*
G01X1568555D01*
G02X1568389Y1233536I-22J199D01*
G01X1568134Y1233802D01*
X1568106Y1233891D01*
X1568109Y1233910D01*
G03X1568132Y1234151I-1279J244D01*
G01Y1234430D01*
G02X1568198Y1234579I200J0D01*
G01X1568419Y1234778D01*
G02X1568573Y1234828I134J-149D01*
G01X1568574D01*
G03X1568700Y1234821I130J1195D01*
G03X1569902Y1236023I0J1202D01*
G03X1569893Y1236166I-1202J-4D01*
G02X1569954Y1236335I198J24D01*
G01X1570220Y1236589D01*
X1570309Y1236617D01*
X1570337Y1236612D01*
G03X1570747Y1236603I233J1281D01*
G01X1570749D01*
G03X1570811Y1236613I-176J1290D01*
G01X1570813D01*
X1570832Y1236616D01*
X1570921Y1236589D01*
X1571187Y1236335D01*
G02X1571248Y1236166I-137J-145D01*
G03X1571239Y1236023I1193J-147D01*
G03X1572441Y1234821I1202J0D01*
G03X1572566Y1234827I5J1202D01*
G01X1572607Y1234832D01*
X1572689Y1234805D01*
X1572941Y1234578D01*
G02X1573007Y1234429I-134J-149D01*
G01Y1234153D01*
G03X1573029Y1233917I1303J2D01*
G01Y1233913D01*
X1573033Y1233892D01*
X1573005Y1233803D01*
X1572718Y1233503D01*
X1572630Y1233471D01*
X1572583Y1233477D01*
G03X1572441Y1233485I-139J-1194D01*
G03X1573643Y1232283I0J-1202D01*
G03X1573635Y1232426I-1202J4D01*
G01X1573629Y1232473D01*
X1573661Y1232561D01*
X1573960Y1232848D01*
X1574049Y1232876D01*
X1574067Y1232873D01*
G03X1574310Y1232850I244J1280D01*
G01X1574343D01*
X1574361Y1232851D01*
X1574362D01*
G03X1574382Y1232852I-55J1301D01*
G03X1574545Y1232871I-69J1300D01*
G01X1574547D01*
X1574572Y1232875D01*
X1574661Y1232848D01*
X1574927Y1232593D01*
G02X1574988Y1232427I-138J-145D01*
G01Y1232426D01*
G03X1574979Y1232283I1193J-147D01*
G03X1576181Y1233485I1202J0D01*
G03X1576038Y1233476I4J-1202D01*
G01X1576037D01*
G02X1575869Y1233536I-24J199D01*
G01X1575615Y1233802D01*
X1575587Y1233891D01*
X1575591Y1233916D01*
G03X1575613Y1234153I-1281J238D01*
G01Y1234196D01*
X1575612Y1234204D01*
Y1234430D01*
G02X1575678Y1234579I200J0D01*
G01X1575932Y1234806D01*
X1576012Y1234832D01*
X1576054Y1234828D01*
G03X1576181Y1234821I130J1195D01*
G03X1577383Y1236023I0J1202D01*
G03X1577374Y1236166I-1202J-4D01*
G02X1577435Y1236335I198J24D01*
G01X1577701Y1236589D01*
X1577790Y1236616D01*
X1577810Y1236613D01*
G03X1578227Y1236603I239J1280D01*
G01X1578229D01*
G03X1578291Y1236613I-176J1290D01*
G01X1578293D01*
X1578312Y1236616D01*
X1578401Y1236589D01*
X1578667Y1236335D01*
G02X1578728Y1236166I-137J-145D01*
G03X1578719Y1236023I1193J-147D01*
G03X1579921Y1234821I1202J0D01*
G03X1580046Y1234827I5J1202D01*
G01X1580087Y1234832D01*
X1580169Y1234805D01*
X1580421Y1234578D01*
G02X1580487Y1234429I-134J-149D01*
G01Y1234153D01*
G03X1580509Y1233917I1303J2D01*
G01Y1233913D01*
X1580513Y1233892D01*
X1580485Y1233803D01*
X1580198Y1233503D01*
X1580110Y1233471D01*
X1580063Y1233477D01*
G03X1579921Y1233485I-139J-1194D01*
G03X1581123Y1232283I0J-1202D01*
G03X1581115Y1232426I-1202J4D01*
G01X1581109Y1232473D01*
X1581141Y1232561D01*
X1581440Y1232848D01*
X1581529Y1232876D01*
X1581547Y1232873D01*
G03X1581790Y1232850I244J1280D01*
G01X1581823D01*
X1581841Y1232851D01*
X1581842D01*
G03X1581862Y1232852I-55J1301D01*
G03X1582025Y1232871I-69J1300D01*
G01X1582027D01*
X1582052Y1232875D01*
X1582141Y1232848D01*
X1582407Y1232593D01*
G02X1582468Y1232427I-138J-145D01*
G01Y1232426D01*
G03X1582459Y1232283I1193J-147D01*
G03X1583661Y1233485I1202J0D01*
G03X1583518Y1233476I4J-1202D01*
G01X1583517D01*
G02X1583349Y1233536I-24J199D01*
G01X1583095Y1233802D01*
X1583067Y1233891D01*
X1583071Y1233916D01*
G03X1583093Y1234153I-1281J238D01*
G01Y1234196D01*
X1583092Y1234204D01*
Y1234430D01*
G02X1583158Y1234579I200J0D01*
G01X1583412Y1234806D01*
X1583492Y1234832D01*
X1583534Y1234828D01*
G03X1583661Y1234821I130J1195D01*
G03X1584863Y1236023I0J1202D01*
G03X1584854Y1236166I-1202J-4D01*
G02X1584915Y1236335I198J24D01*
G01X1585181Y1236589D01*
X1585270Y1236616D01*
X1585290Y1236613D01*
G03X1585707Y1236603I239J1280D01*
G01X1585709D01*
G03X1585771Y1236613I-176J1290D01*
G01X1585773D01*
X1585792Y1236616D01*
X1585881Y1236589D01*
X1586147Y1236335D01*
G02X1586208Y1236166I-137J-145D01*
G03X1586199Y1236023I1193J-147D01*
G03X1587401Y1234821I1202J0D01*
G03X1587525Y1234828I-6J1202D01*
G01X1587527D01*
G02X1587681Y1234778I20J-199D01*
G01X1587902Y1234579D01*
G02X1587968Y1234430I-134J-149D01*
G01Y1234153D01*
G03X1587975Y1234022I1303J4D01*
G03X1587986Y1233939I1296J130D01*
G01Y1233938D01*
G02X1587933Y1233768I-197J-32D01*
G01X1587711Y1233536D01*
G02X1587545Y1233476I-144J139D01*
G01X1587544D01*
G03X1587401Y1233485I-147J-1193D01*
G03X1588603Y1232283I0J-1202D01*
G03X1588595Y1232426I-1202J4D01*
G01X1588589Y1232473D01*
X1588621Y1232561D01*
X1588921Y1232848D01*
X1589010Y1232876D01*
X1589033Y1232872D01*
G03X1589271Y1232850I238J1281D01*
G03X1589507Y1232872I-2J1303D01*
G01X1589511D01*
X1589532Y1232876D01*
X1589621Y1232848D01*
X1589921Y1232561D01*
X1589953Y1232473D01*
X1589947Y1232426D01*
G03X1589939Y1232283I1194J-139D01*
G03X1591141Y1233485I1202J0D01*
G03X1590998Y1233477I-4J-1202D01*
G01X1590951Y1233471D01*
X1590863Y1233503D01*
X1590576Y1233803D01*
X1590548Y1233892D01*
X1590552Y1233915D01*
G03X1590574Y1234153I-1281J238D01*
G01Y1234430D01*
G02X1590640Y1234579I200J0D01*
G01X1590861Y1234778D01*
G02X1591015Y1234828I134J-149D01*
G01X1591016D01*
G03X1591141Y1234821I130J1195D01*
G03X1592343Y1236023I0J1202D01*
G03X1592334Y1236166I-1202J-4D01*
G02X1592395Y1236335I198J24D01*
G01X1592661Y1236589D01*
X1592750Y1236617D01*
X1592774Y1236613D01*
G03X1593011Y1236591I238J1280D01*
G03X1593239Y1236611I1J1302D01*
G01X1593241D01*
X1593273Y1236616D01*
X1593362Y1236589D01*
X1593663Y1236303D01*
X1593695Y1236213D01*
X1593689Y1236167D01*
G03X1593680Y1236023I1193J-147D01*
G03X1594882Y1234821I1202J0D01*
G03X1595007Y1234828I-5J1202D01*
G01X1595009D01*
G02X1595163Y1234778I20J-199D01*
G01X1595384Y1234579D01*
G02X1595450Y1234430I-134J-149D01*
G01Y1234185D01*
X1595449Y1234183D01*
Y1234153D01*
G03X1595457Y1234011I1303J2D01*
G01X1595459Y1233993D01*
Y1233992D01*
G03X1595471Y1233917I1292J168D01*
G01Y1233913D01*
X1595475Y1233892D01*
X1595447Y1233803D01*
X1595160Y1233503D01*
X1595072Y1233471D01*
X1595025Y1233477D01*
G03X1594882Y1233485I-139J-1194D01*
G03X1596084Y1232283I0J-1202D01*
G03X1596076Y1232425I-1202J3D01*
G01Y1232426D01*
G02X1596136Y1232594I199J24D01*
G01X1596402Y1232847D01*
X1596492Y1232875D01*
X1596538Y1232867D01*
G03X1596551Y1232865I205J1287D01*
G01X1596553D01*
G03X1596860Y1232855I196J1288D01*
G03X1596966Y1232868I-105J1298D01*
G01X1597012Y1232876D01*
X1597102Y1232848D01*
X1597369Y1232593D01*
G02X1597429Y1232427I-139J-144D01*
G01Y1232426D01*
G03X1597420Y1232283I1193J-147D01*
G03X1598622Y1233485I1202J0D01*
G03X1598479Y1233476I4J-1202D01*
G01X1598478D01*
G02X1598310Y1233536I-24J199D01*
G01X1598056Y1233802D01*
X1598028Y1233891D01*
X1598032Y1233913D01*
G03X1598054Y1234151I-1280J238D01*
G01Y1234430D01*
G02X1598120Y1234579I200J0D01*
G01X1598341Y1234778D01*
G02X1598495Y1234828I134J-149D01*
G01X1598496D01*
G03X1598622Y1234821I130J1195D01*
G03X1599824Y1236023I0J1202D01*
G01Y1236025D01*
G03X1599759Y1236414I-1202J-1D01*
G02X1599751Y1236444I189J66D01*
G01X1599742Y1236495D01*
G02X1599942Y1236695I200J0D01*
G01X1599998Y1236684D01*
G02X1600030Y1236675I-38J-196D01*
G03X1600183Y1236628I458J1219D01*
G03X1600706Y1236608I310J1265D01*
G01X1600752Y1236616D01*
X1600842Y1236588D01*
X1601109Y1236334D01*
G02X1601169Y1236168I-139J-144D01*
G01Y1236166D01*
G03X1601160Y1236023I1193J-147D01*
G03X1602362Y1237225I1202J0D01*
G03X1602220Y1237216I5J-1202D01*
G01X1602218D01*
X1602172Y1237211D01*
X1602084Y1237243D01*
X1601797Y1237543D01*
X1601769Y1237633D01*
X1601777Y1237679D01*
G03X1601791Y1237792I-1284J217D01*
G01Y1237794D01*
G03X1601793Y1237829I-1299J92D01*
G01Y1237830D01*
X1601794Y1237841D01*
Y1237845D01*
G02X1601845Y1237956I198J-24D01*
G01X1601943Y1238052D01*
X1601944Y1238053D01*
X1601977Y1238085D01*
X1602053Y1238158D01*
X1602054Y1238159D01*
G02X1602158Y1238211I138J-145D01*
G01X1602160D01*
G02X1602192Y1238214I35J-197D01*
G01X1606272D01*
G02X1606304Y1238211I-3J-200D01*
G01X1606306D01*
G02X1606410Y1238159I-34J-197D01*
G01X1606484Y1238088D01*
X1606617Y1237960D01*
G02X1606654Y1237905I-145J-138D01*
G01X1606669Y1237871D01*
X1606670Y1237851D01*
Y1237616D01*
G02X1606604Y1237467I-200J0D01*
G01X1606383Y1237268D01*
G02X1606229Y1237218I-134J149D01*
G01X1606228D01*
G03X1606102Y1237225I-130J-1195D01*
G03Y1234821I0J-1202D01*
G03X1606227Y1234828I-5J1202D01*
G01X1606229D01*
G02X1606383Y1234778I20J-199D01*
G01X1606604Y1234579D01*
G02X1606670Y1234430I-134J-149D01*
G01Y1234153D01*
G03X1606692Y1233920I1302J5D01*
G01Y1233914D01*
X1606696Y1233891D01*
X1606668Y1233802D01*
X1606414Y1233536D01*
G02X1606246Y1233476I-144J139D01*
G01X1606245D01*
G03X1606102Y1233485I-147J-1193D01*
G03X1607304Y1232283I0J-1202D01*
G03X1607295Y1232425I-1202J-5D01*
G01Y1232427D01*
X1607290Y1232473D01*
X1607322Y1232561D01*
X1607622Y1232848D01*
X1607711Y1232875D01*
X1607737Y1232871D01*
G03X1607973Y1232850I233J1281D01*
G03X1608213Y1232872I2J1303D01*
G02X1608219Y1232873I36J-196D01*
G01X1608234Y1232876D01*
X1608323Y1232848D01*
X1608622Y1232561D01*
X1608654Y1232473D01*
X1608648Y1232426D01*
G03X1608640Y1232283I1194J-139D01*
G03X1609842Y1231081I1202J0D01*
G03X1609985Y1231090I-4J1202D01*
G02X1610154Y1231029I24J-198D01*
G01X1610408Y1230763D01*
X1610436Y1230674D01*
X1610432Y1230652D01*
G03Y1230176I1280J-238D01*
G01Y1230172D01*
X1610436Y1230152D01*
X1610408Y1230063D01*
X1610154Y1229797D01*
G02X1609985Y1229736I-145J137D01*
G03X1609842Y1229745I-147J-1193D01*
G03Y1227341I0J-1202D01*
G03X1609985Y1227350I-4J1202D01*
G02X1610154Y1227289I24J-198D01*
G01X1610408Y1227023D01*
X1610436Y1226934D01*
X1610432Y1226910D01*
G03X1610410Y1226673I1280J-238D01*
G01Y1226396D01*
G02X1610344Y1226247I-200J0D01*
G01X1610123Y1226048D01*
G02X1609969Y1225998I-134J149D01*
G01X1609968D01*
G03X1609842Y1226005I-130J-1195D01*
G03Y1223601I0J-1202D01*
G03X1609967Y1223608I-5J1202D01*
G01X1609969D01*
G02X1610123Y1223558I20J-199D01*
G01X1610344Y1223359D01*
G02X1610410Y1223210I-134J-149D01*
G01Y1222932D01*
G03X1610425Y1222733I1302J-2D01*
G01Y1222731D01*
G03X1610427Y1222718I1288J192D01*
G01X1610435Y1222672D01*
X1610407Y1222582D01*
X1610152Y1222315D01*
G02X1609986Y1222255I-144J139D01*
G01X1609985D01*
G03X1609842Y1222264I-147J-1193D01*
G03Y1219860I0J-1202D01*
G03X1609986Y1219869I-3J1202D01*
G01X1610032Y1219875D01*
X1610122Y1219843D01*
X1610408Y1219542D01*
X1610436Y1219453D01*
X1610431Y1219422D01*
G03X1610433Y1218951I1281J-230D01*
G01Y1218945D01*
X1610436Y1218930D01*
X1610408Y1218841D01*
X1610153Y1218575D01*
G02X1609987Y1218515I-144J139D01*
G01X1609985D01*
G03X1609842Y1218524I-147J-1193D01*
G03X1608640Y1217322I0J-1202D01*
G03X1608661Y1217100I1202J2D01*
G01X1608670Y1217051D01*
X1608641Y1216958D01*
X1608336Y1216653D01*
X1608243Y1216624D01*
X1608194Y1216633D01*
G03X1607972Y1216654I-224J-1181D01*
G03X1609174Y1215452I0J-1202D01*
G03X1609153Y1215674I-1202J-2D01*
G01X1609144Y1215723D01*
X1609173Y1215816D01*
X1609478Y1216121D01*
X1609571Y1216150D01*
X1609620Y1216141D01*
G03X1609841Y1216120I224J1181D01*
G01X1609843D01*
G03X1609985Y1216129I-5J1202D01*
G02X1610154Y1216068I24J-198D01*
G01X1610408Y1215802D01*
X1610436Y1215713D01*
X1610432Y1215691D01*
G03X1611446Y1214177I1280J-239D01*
G03X1611684Y1214150I265J1275D01*
G01X1611686D01*
X1611713Y1214149D01*
X1611727D01*
X1611761Y1214135D01*
G02X1611805Y1214110I-76J-185D01*
G01X1611972Y1213940D01*
X1612035Y1213876D01*
G02X1612080Y1213750I-155J-126D01*
G01Y1213410D01*
G02X1612077Y1213377I-200J2D01*
G02X1612067Y1213342I-197J37D01*
G01X1612050Y1213302D01*
X1612022Y1213273D01*
X1611805Y1213054D01*
G02X1611761Y1213029I-120J160D01*
G01X1611726Y1213015D01*
X1611687Y1213014D01*
X1611686D01*
G03X1611546Y1213004I23J-1302D01*
G03X1611684Y1210410I165J-1292D01*
G01X1611686D01*
X1611713Y1210409D01*
X1611727D01*
X1611761Y1210395D01*
G02X1611805Y1210370I-76J-185D01*
G01X1611972Y1210200D01*
X1612035Y1210136D01*
G02X1612080Y1210010I-155J-126D01*
G01Y1209670D01*
G02X1612077Y1209637I-200J2D01*
G02X1612067Y1209602I-197J37D01*
G01X1612050Y1209562D01*
X1612022Y1209533D01*
X1611805Y1209314D01*
G02X1611761Y1209289I-120J160D01*
G01X1611726Y1209275D01*
X1611687Y1209274D01*
X1611686D01*
G03X1610410Y1207972I26J-1302D01*
G03X1611712Y1206670I1302J0D01*
G03X1611856Y1206678I0J1302D01*
G01X1611865Y1206679D01*
X1611880D01*
G02X1612080Y1206479I0J-200D01*
G01Y1206432D01*
G03X1612087Y1206295I1501J8D01*
G01Y1206293D01*
G03X1612088Y1206285I1490J182D01*
G01Y1206283D01*
G03X1612091Y1206256I1493J152D01*
G01Y1206253D01*
G03X1612093Y1206240I1484J222D01*
G01Y1206236D01*
G03X1612096Y1206216I1486J213D01*
G01Y1206212D01*
G03X1612129Y1206054I1484J228D01*
G01X1612136Y1206029D01*
Y1206028D01*
X1612158Y1205949D01*
X1612137Y1205912D01*
X1612046Y1205796D01*
X1612032Y1205778D01*
Y1205776D01*
X1611900Y1205610D01*
G02X1611829Y1205553I-157J123D01*
G01X1611787Y1205533D01*
X1611739Y1205534D01*
X1611712D01*
G03Y1202930I0J-1302D01*
G03X1611912Y1202945I3J1302D01*
G03X1613013Y1204168I-200J1287D01*
G01Y1204169D01*
G02X1613094Y1204322I200J-8D01*
G01X1613372Y1204506D01*
G02X1613460Y1204539I112J-166D01*
G01X1613507Y1204544D01*
X1613529Y1204536D01*
G03X1613691Y1204482I555J1395D01*
G03X1613852Y1204447I399J1448D01*
G01X1613866Y1204445D01*
X1613920Y1204428D01*
X1613930Y1204423D01*
X1613931D01*
X1613940Y1204419D01*
X1613988Y1204394D01*
G02X1614038Y1204356I-94J-176D01*
G01X1614081Y1204309D01*
X1614099Y1204288D01*
X1614120Y1204241D01*
Y1204239D01*
X1614151Y1204168D01*
X1614154Y1204134D01*
Y1204133D01*
G03X1615452Y1202930I1298J99D01*
G03X1616433Y1203375I0J1304D01*
G01X1616437Y1203380D01*
X1616457Y1203400D01*
G02X1616503Y1203430I131J-151D01*
G01X1616579Y1203466D01*
G02X1616582Y1203467I65J-189D01*
G02X1616664Y1203485I83J-182D01*
G01X1617959D01*
G02X1617992Y1203482I-2J-200D01*
G01X1618040Y1203472D01*
G02X1618082Y1203458I-42J-196D01*
G01X1618140Y1203431D01*
X1618141Y1203430D01*
X1618142D01*
G02X1618170Y1203414I-85J-181D01*
G01X1618191Y1203398D01*
X1618222Y1203363D01*
G03X1620178Y1203380I971J870D01*
G01X1620192Y1203396D01*
X1620209Y1203409D01*
G02X1620246Y1203431I120J-160D01*
G01X1620321Y1203466D01*
X1620323Y1203467D01*
X1620362Y1203485D01*
X1621699D01*
G02X1621732Y1203482I-2J-200D01*
G01X1621780Y1203472D01*
G02X1621822Y1203458I-42J-196D01*
G01X1621880Y1203431D01*
X1621881Y1203430D01*
X1621882D01*
G02X1621910Y1203414I-85J-181D01*
G01X1621931Y1203398D01*
X1621962Y1203363D01*
G03X1623918Y1203380I971J870D01*
G01X1623932Y1203396D01*
X1623949Y1203409D01*
G02X1623986Y1203431I120J-160D01*
G01X1624061Y1203466D01*
X1624063Y1203467D01*
X1624102Y1203485D01*
X1625439D01*
G02X1625472Y1203482I-2J-200D01*
G01X1625520Y1203472D01*
G02X1625562Y1203458I-42J-196D01*
G01X1625620Y1203431D01*
X1625621Y1203430D01*
X1625622D01*
G02X1625650Y1203414I-85J-181D01*
G01X1625671Y1203398D01*
X1625702Y1203363D01*
G03X1627658Y1203380I971J870D01*
G01X1627672Y1203396D01*
X1627689Y1203409D01*
G02X1627726Y1203431I120J-160D01*
G01X1627801Y1203466D01*
X1627803Y1203467D01*
X1627842Y1203485D01*
X1629179D01*
G02X1629212Y1203482I-2J-200D01*
G01X1629260Y1203472D01*
G02X1629302Y1203458I-42J-196D01*
G01X1629360Y1203431D01*
X1629361Y1203430D01*
X1629362D01*
G02X1629390Y1203414I-85J-181D01*
G01X1629411Y1203398D01*
X1629442Y1203363D01*
G03X1631398Y1203380I971J870D01*
G01X1631412Y1203396D01*
X1631429Y1203409D01*
G02X1631466Y1203431I120J-160D01*
G01X1631541Y1203466D01*
X1631543Y1203467D01*
X1631582Y1203485D01*
X1632919D01*
G02X1632952Y1203482I-2J-200D01*
G01X1633000Y1203472D01*
G02X1633042Y1203458I-42J-196D01*
G01X1633100Y1203431D01*
X1633101Y1203430D01*
X1633102D01*
G02X1633130Y1203414I-85J-181D01*
G01X1633151Y1203398D01*
X1633182Y1203363D01*
G03X1635138Y1203380I971J870D01*
G01X1635152Y1203396D01*
X1635169Y1203409D01*
G02X1635206Y1203431I120J-160D01*
G01X1635281Y1203466D01*
X1635283Y1203467D01*
X1635322Y1203485D01*
X1636659D01*
G02X1636692Y1203482I-2J-200D01*
G01X1636740Y1203472D01*
G02X1636782Y1203458I-42J-196D01*
G01X1636840Y1203431D01*
X1636841Y1203430D01*
X1636842D01*
G02X1636870Y1203414I-85J-181D01*
G01X1636891Y1203398D01*
X1636922Y1203363D01*
G03X1638878Y1203380I971J870D01*
G01X1638892Y1203396D01*
X1638909Y1203409D01*
G02X1638946Y1203431I120J-160D01*
G01X1639021Y1203466D01*
X1639023Y1203467D01*
X1639062Y1203485D01*
X1640441D01*
X1640487Y1203476D01*
X1640582Y1203431D01*
G02X1640621Y1203406I-88J-180D01*
G01X1640635Y1203391D01*
G03X1640654Y1203372I929J910D01*
G01X1640655Y1203371D01*
G03X1640658Y1203368I921J918D01*
G01X1640665Y1203360D01*
G03X1641610Y1202930I967J872D01*
G01X1641650Y1202929D01*
X1641684Y1202915D01*
G02X1641744Y1202875I-79J-184D01*
G01X1641847Y1202770D01*
X1641945Y1202670D01*
G02X1641982Y1202617I-143J-139D01*
G02X1642002Y1202530I-180J-87D01*
G01Y1202193D01*
G02X1641982Y1202106I-200J0D01*
G02X1641945Y1202053I-180J86D01*
G01X1641847Y1201953D01*
X1641744Y1201848D01*
G02X1641684Y1201808I-139J144D01*
G01X1641650Y1201794D01*
X1641610Y1201793D01*
G03Y1199189I23J-1302D01*
G01X1641650Y1199188D01*
X1641684Y1199174D01*
G02X1641744Y1199134I-79J-184D01*
G01X1641847Y1199029D01*
X1641945Y1198929D01*
G02X1641982Y1198876I-143J-139D01*
G02X1642002Y1198789I-180J-87D01*
G01Y1198432D01*
G02X1642000Y1198407I-200J3D01*
G01Y1198405D01*
G02X1641954Y1198302I-198J27D01*
G01X1641879Y1198225D01*
X1641817Y1198161D01*
X1641753Y1198095D01*
X1641725Y1198066D01*
X1641652Y1198035D01*
X1641614Y1198033D01*
G03Y1195431I39J-1301D01*
G01X1641652Y1195429D01*
X1641725Y1195398D01*
X1641753Y1195369D01*
X1641817Y1195303D01*
X1641956Y1195158D01*
G02X1641979Y1195124I-153J-128D01*
G01X1641987Y1195108D01*
G02X1642000Y1195059I-185J-75D01*
G01Y1195057D01*
G02X1642002Y1195032I-198J-28D01*
G01Y1194776D01*
G03X1642003Y1194734I1502J15D01*
G01Y1194733D01*
X1642004Y1194681D01*
X1641980Y1194627D01*
G02X1641958Y1194593I-178J91D01*
G01X1641913Y1194547D01*
Y1194545D01*
X1641744Y1194367D01*
G02X1641641Y1194316I-136J146D01*
G01X1641625Y1194313D01*
X1641609D01*
G03X1640331Y1193011I24J-1302D01*
G03X1641633Y1191709I1302J0D01*
G03X1642834Y1192506I0J1303D01*
G01X1642843Y1192527D01*
X1642884Y1192584D01*
G02X1642949Y1192634I152J-130D01*
G01X1642951D01*
G02X1642984Y1192647I89J-179D01*
G01X1643218Y1192695D01*
X1643321Y1192716D01*
G02X1643482Y1192673I34J-197D01*
G01X1643596Y1192561D01*
Y1192560D01*
X1643721Y1192435D01*
G02X1643779Y1192294I-142J-141D01*
G01Y1110455D01*
G02X1643726Y1110320I-200J1D01*
G01X1643515Y1110091D01*
X1643448Y1110059D01*
X1643410Y1110056D01*
G03Y1107660I94J-1198D01*
G01X1643448Y1107657D01*
X1643515Y1107625D01*
X1643726Y1107396D01*
G02X1643779Y1107261I-147J-136D01*
G01Y1106714D01*
G02X1643726Y1106579I-200J1D01*
G01X1643515Y1106350D01*
X1643448Y1106318D01*
X1643410Y1106315D01*
G03Y1103919I94J-1198D01*
G01X1643448Y1103916D01*
X1643515Y1103884D01*
X1643726Y1103655D01*
G02X1643779Y1103520I-147J-136D01*
G01Y1102974D01*
G02X1643726Y1102839I-200J1D01*
G01X1643515Y1102610D01*
X1643448Y1102578D01*
X1643410Y1102575D01*
G03Y1100179I94J-1198D01*
G01X1643448Y1100176D01*
X1643515Y1100144D01*
X1643726Y1099915D01*
G02X1643779Y1099780I-147J-136D01*
G01Y1099234D01*
G02X1643726Y1099099I-200J1D01*
G01X1643515Y1098870D01*
X1643448Y1098838D01*
X1643410Y1098835D01*
G03Y1096439I93J-1198D01*
G01X1643448Y1096436D01*
X1643515Y1096404D01*
X1643726Y1096175D01*
G02X1643779Y1096040I-147J-136D01*
G01Y1095494D01*
G02X1643726Y1095359I-200J1D01*
G01X1643515Y1095130D01*
X1643448Y1095098D01*
X1643410Y1095095D01*
G03X1642301Y1093897I93J-1198D01*
G01Y1093895D01*
G03X1642366Y1093506I1202J1D01*
G02X1642374Y1093476I-189J-66D01*
G01X1642383Y1093425D01*
G02X1642183Y1093225I-200J0D01*
G01X1642127Y1093236D01*
G02X1642095Y1093245I38J196D01*
G03X1642046Y1093262I-452J-1223D01*
G03X1641634Y1093329I-412J-1236D01*
G01X1641633D01*
G03X1641397Y1093307I2J-1302D01*
G01X1641393D01*
X1641372Y1093303D01*
X1641283Y1093331D01*
X1641017Y1093585D01*
G02X1640956Y1093754I137J145D01*
G03X1640965Y1093897I-1193J147D01*
G03X1639763Y1095099I-1202J0D01*
G03X1639639Y1095092I6J-1202D01*
G01X1639637D01*
G02X1639483Y1095142I-20J199D01*
G01X1639262Y1095341D01*
G02X1639196Y1095490I134J149D01*
G01Y1095668D01*
G03Y1095699I-1302J15D01*
G01Y1095767D01*
G03X1639174Y1096003I-1303J-2D01*
G01Y1096007D01*
X1639170Y1096028D01*
X1639198Y1096117D01*
X1639485Y1096417D01*
X1639573Y1096449D01*
X1639620Y1096443D01*
G03X1639763Y1096435I139J1194D01*
G03X1638561Y1097637I0J1202D01*
G03X1638569Y1097494I1202J-4D01*
G01X1638575Y1097447D01*
X1638543Y1097359D01*
X1638243Y1097072D01*
X1638154Y1097044D01*
X1638131Y1097048D01*
G03X1637893Y1097070I-238J-1281D01*
G01X1637890D01*
G03X1637665Y1097050I2J-1303D01*
G01X1637663D01*
X1637631Y1097045D01*
X1637542Y1097072D01*
X1637276Y1097327D01*
G02X1637215Y1097493I138J145D01*
G01Y1097494D01*
G03X1637224Y1097637I-1193J147D01*
G03X1636022Y1096435I-1202J0D01*
G03X1636165Y1096444I-4J1202D01*
G01X1636166D01*
G02X1636334Y1096384I24J-199D01*
G01X1636588Y1096118D01*
X1636616Y1096029D01*
X1636612Y1096003D01*
G03X1636590Y1095767I1281J-238D01*
G01Y1095490D01*
G02X1636524Y1095341I-200J0D01*
G01X1636303Y1095142D01*
G02X1636149Y1095092I-134J149D01*
G01X1636148D01*
G03X1636022Y1095099I-130J-1195D01*
G03X1634820Y1093897I0J-1202D01*
G03X1634829Y1093755I1202J5D01*
G01Y1093753D01*
X1634834Y1093707D01*
X1634802Y1093619D01*
X1634503Y1093332D01*
X1634413Y1093304D01*
X1634366Y1093312D01*
G03X1634140Y1093329I-210J-1285D01*
G03X1633913Y1093307I12J-1302D01*
G01X1633910D01*
X1633892Y1093304D01*
X1633803Y1093331D01*
X1633537Y1093585D01*
G02X1633476Y1093754I137J145D01*
G03X1633485Y1093897I-1193J147D01*
G03X1632283Y1095099I-1202J0D01*
G03X1632159Y1095092I6J-1202D01*
G01X1632157D01*
G02X1632003Y1095142I-20J199D01*
G01X1631782Y1095341D01*
G02X1631716Y1095490I134J149D01*
G01Y1095667D01*
G03X1631714Y1095728I-1302J-12D01*
G03X1631715Y1095740I-1296J114D01*
G01Y1095767D01*
G03X1631693Y1096000I-1302J-5D01*
G01Y1096006D01*
X1631689Y1096029D01*
X1631717Y1096118D01*
X1631971Y1096384D01*
G02X1632139Y1096444I144J-139D01*
G01X1632140D01*
G03X1632283Y1096435I147J1193D01*
G03X1631081Y1097637I0J1202D01*
G03X1631089Y1097494I1202J-4D01*
G01X1631095Y1097447D01*
X1631063Y1097359D01*
X1630763Y1097072D01*
X1630674Y1097045D01*
X1630648Y1097049D01*
G03X1630414Y1097070I-233J-1281D01*
G01X1630412D01*
G03X1630177Y1097048I3J-1302D01*
G01X1630173D01*
X1630151Y1097044D01*
X1630062Y1097072D01*
X1629762Y1097359D01*
X1629730Y1097447D01*
X1629736Y1097494D01*
G03X1629744Y1097637I-1194J139D01*
G03X1628542Y1096435I-1202J0D01*
G03X1628684Y1096444I-5J1202D01*
G01X1628687D01*
G02X1628853Y1096384I22J-199D01*
G01X1629108Y1096118D01*
X1629136Y1096029D01*
X1629133Y1096010D01*
G03X1629110Y1095769I1279J-244D01*
G01Y1095490D01*
G02X1629044Y1095341I-200J0D01*
G01X1628823Y1095142D01*
G02X1628669Y1095092I-134J149D01*
G01X1628668D01*
G03X1628542Y1095099I-130J-1195D01*
G03X1627340Y1093897I0J-1202D01*
G03X1627349Y1093755I1202J5D01*
G01Y1093753D01*
X1627354Y1093707D01*
X1627322Y1093619D01*
X1627023Y1093332D01*
X1626933Y1093304D01*
X1626886Y1093312D01*
G03X1626660Y1093329I-210J-1285D01*
G03X1626433Y1093307I12J-1302D01*
G01X1626430D01*
X1626412Y1093304D01*
X1626323Y1093331D01*
X1626057Y1093585D01*
G02X1625996Y1093754I137J145D01*
G03X1626005Y1093897I-1193J147D01*
G03X1624803Y1095099I-1202J0D01*
G03X1624679Y1095092I6J-1202D01*
G01X1624677D01*
G02X1624523Y1095142I-20J199D01*
G01X1624302Y1095341D01*
G02X1624236Y1095490I134J149D01*
G01Y1095667D01*
G03X1624234Y1095728I-1302J-12D01*
G03X1624235Y1095740I-1296J114D01*
G01Y1095767D01*
G03X1624213Y1096000I-1302J-5D01*
G01Y1096006D01*
X1624209Y1096029D01*
X1624237Y1096118D01*
X1624491Y1096384D01*
G02X1624659Y1096444I144J-139D01*
G01X1624660D01*
G03X1624803Y1096435I147J1193D01*
G03X1623601Y1097637I0J1202D01*
G03X1623609Y1097494I1202J-4D01*
G01X1623615Y1097447D01*
X1623583Y1097359D01*
X1623283Y1097072D01*
X1623194Y1097045D01*
X1623168Y1097049D01*
G03X1622934Y1097070I-233J-1281D01*
G01X1622932D01*
G03X1622697Y1097048I3J-1302D01*
G01X1622693D01*
X1622671Y1097044D01*
X1622582Y1097072D01*
X1622282Y1097359D01*
X1622250Y1097447D01*
X1622256Y1097494D01*
G03X1622264Y1097637I-1194J139D01*
G03X1621062Y1096435I-1202J0D01*
G03X1621204Y1096444I-5J1202D01*
G01X1621207D01*
G02X1621373Y1096384I22J-199D01*
G01X1621628Y1096118D01*
X1621656Y1096029D01*
X1621653Y1096010D01*
G03X1621630Y1095769I1279J-244D01*
G01Y1095490D01*
G02X1621564Y1095341I-200J0D01*
G01X1621343Y1095142D01*
G02X1621189Y1095092I-134J149D01*
G01X1621188D01*
G03X1621062Y1095099I-130J-1195D01*
G03X1619860Y1093897I0J-1202D01*
G03X1619869Y1093755I1202J5D01*
G01Y1093753D01*
X1619874Y1093707D01*
X1619842Y1093619D01*
X1619543Y1093332D01*
X1619453Y1093304D01*
X1619406Y1093312D01*
G03X1619122Y1093327I-210J-1285D01*
G03X1618960Y1093308I70J-1300D01*
G01X1618957D01*
X1618931Y1093303D01*
X1618842Y1093331D01*
X1618576Y1093585D01*
G02X1618515Y1093754I137J145D01*
G03X1618524Y1093897I-1193J147D01*
G03X1617322Y1095099I-1202J0D01*
G03X1617197Y1095093I-5J-1202D01*
G01X1617156Y1095088D01*
X1617074Y1095114D01*
X1616822Y1095341D01*
G02X1616756Y1095490I134J149D01*
G01Y1095671D01*
Y1095673D01*
G03X1616755Y1095737I-1303J12D01*
G01Y1095738D01*
G03X1616754Y1095753I-1301J-79D01*
G01Y1095767D01*
G03X1616732Y1096002I-1302J-3D01*
G01Y1096006D01*
X1616728Y1096028D01*
X1616756Y1096117D01*
X1617010Y1096383D01*
G02X1617179Y1096444I145J-137D01*
G03X1617322Y1096435I147J1193D01*
G03X1616120Y1097637I0J1202D01*
G03X1616129Y1097494I1202J4D01*
G02X1616068Y1097325I-198J-24D01*
G01X1615802Y1097071D01*
X1615713Y1097043D01*
X1615689Y1097047D01*
G03X1615452Y1097069I-238J-1280D01*
G01X1615451D01*
G03X1615225Y1097049I1J-1302D01*
G01X1615223D01*
X1615190Y1097043D01*
X1615101Y1097071D01*
X1614800Y1097357D01*
X1614768Y1097447D01*
X1614774Y1097493D01*
G03X1614783Y1097637I-1193J147D01*
G03X1613581Y1096435I-1202J0D01*
G03X1613725Y1096444I-3J1202D01*
G01X1613726D01*
G02X1613894Y1096384I24J-199D01*
G01X1614148Y1096118D01*
X1614175Y1096029D01*
X1614171Y1096002D01*
G03X1614150Y1095767I1281J-233D01*
G01Y1095490D01*
G02X1614084Y1095341I-200J0D01*
G01X1613830Y1095114D01*
X1613750Y1095088D01*
X1613708Y1095092D01*
G03X1613581Y1095099I-130J-1195D01*
G03X1612379Y1093897I0J-1202D01*
G03X1612388Y1093755I1202J5D01*
G01Y1093753D01*
X1612393Y1093707D01*
X1612361Y1093619D01*
X1612062Y1093332D01*
X1611972Y1093304D01*
X1611925Y1093312D01*
G03X1611699Y1093329I-210J-1285D01*
G03X1611472Y1093307I12J-1302D01*
G01X1611469D01*
X1611451Y1093304D01*
X1611362Y1093331D01*
X1611096Y1093585D01*
G02X1611035Y1093754I137J145D01*
G03X1611044Y1093897I-1193J147D01*
G03X1609842Y1095099I-1202J0D01*
G03X1609717Y1095092I5J-1202D01*
G01X1609715D01*
G02X1609561Y1095142I-20J199D01*
G01X1609340Y1095341D01*
G02X1609274Y1095490I134J149D01*
G01Y1095767D01*
G03X1609252Y1096000I-1302J-5D01*
G01Y1096006D01*
X1609248Y1096029D01*
X1609276Y1096118D01*
X1609530Y1096384D01*
G02X1609698Y1096444I144J-139D01*
G01X1609699D01*
G03X1609842Y1096435I147J1193D01*
G03X1608640Y1097637I0J1202D01*
G03X1608649Y1097495I1202J5D01*
G01Y1097493D01*
X1608654Y1097447D01*
X1608622Y1097359D01*
X1608322Y1097072D01*
X1608233Y1097045D01*
X1608207Y1097049D01*
G03X1607971Y1097070I-233J-1281D01*
G03X1607735Y1097048I2J-1303D01*
G01X1607731D01*
X1607710Y1097044D01*
X1607621Y1097072D01*
X1607321Y1097359D01*
X1607289Y1097447D01*
X1607295Y1097494D01*
G03X1607303Y1097637I-1194J139D01*
G03X1606101Y1096435I-1202J0D01*
G03X1606244Y1096443I4J1202D01*
G01X1606291Y1096449D01*
X1606379Y1096417D01*
X1606666Y1096117D01*
X1606694Y1096028D01*
X1606690Y1096005D01*
G03X1606668Y1095767I1281J-238D01*
G01Y1095490D01*
G02X1606602Y1095341I-200J0D01*
G01X1606381Y1095142D01*
G02X1606227Y1095092I-134J149D01*
G01X1606226D01*
G03X1606101Y1095099I-130J-1195D01*
G03X1604899Y1093897I0J-1202D01*
G03X1605962Y1092703I1202J0D01*
G01X1606019Y1092697D01*
X1606109Y1092625D01*
X1606247Y1092230D01*
G02X1606199Y1092023I-189J-65D01*
G01X1604236Y1090060D01*
G02X1604029Y1090012I-142J141D01*
G01X1603634Y1090150D01*
X1603562Y1090240D01*
X1603556Y1090296D01*
G03X1602362Y1091359I-1194J-139D01*
G03X1601160Y1090157I0J-1202D01*
G03X1601169Y1090014I1202J4D01*
G01Y1090013D01*
G02X1601109Y1089845I-199J-24D01*
G01X1600843Y1089591D01*
X1600754Y1089563D01*
X1600729Y1089567D01*
G03X1600492Y1089589I-238J-1281D01*
G03X1600257Y1089567I3J-1302D01*
G01X1600253D01*
X1600231Y1089563D01*
X1600142Y1089591D01*
X1599876Y1089845D01*
G02X1599815Y1090014I137J145D01*
G03X1599824Y1090157I-1193J147D01*
G03X1598622Y1088955I-1202J0D01*
G03X1598765Y1088964I-4J1202D01*
G02X1598934Y1088903I24J-198D01*
G01X1599188Y1088637D01*
X1599216Y1088548D01*
X1599212Y1088524D01*
G03X1599190Y1088287I1280J-238D01*
G01Y1088286D01*
G03X1599212Y1088050I1301J2D01*
G01Y1088046D01*
X1599216Y1088025D01*
X1599188Y1087936D01*
X1598934Y1087670D01*
G02X1598766Y1087610I-144J139D01*
G01X1598765D01*
G03X1598622Y1087619I-147J-1193D01*
G03Y1085215I0J-1202D01*
G03X1598764Y1085223I3J1202D01*
G01X1598811Y1085229D01*
X1598899Y1085197D01*
X1599186Y1084897D01*
X1599214Y1084808D01*
X1599210Y1084785D01*
G03X1599188Y1084548I1280J-238D01*
G01Y1084270D01*
G02X1599122Y1084121I-200J0D01*
G01X1598870Y1083894D01*
X1598788Y1083868D01*
X1598747Y1083873D01*
G03X1598622Y1083879I-120J-1196D01*
G03Y1081475I0J-1202D01*
G03X1598747Y1081481I5J1202D01*
G01X1598788Y1081486D01*
X1598870Y1081460D01*
X1599122Y1081233D01*
G02X1599188Y1081084I-134J-149D01*
G01Y1080806D01*
G03Y1080804I1302J-1D01*
G03X1599210Y1080566I1302J0D01*
G02X1599211Y1080560I-196J-36D01*
G01X1599214Y1080545D01*
X1599186Y1080456D01*
X1598899Y1080156D01*
X1598811Y1080124D01*
X1598764Y1080130D01*
G03X1598622Y1080138I-139J-1194D01*
G03Y1077734I0J-1202D01*
G03X1598765Y1077743I-4J1202D01*
G01X1598766D01*
G02X1598934Y1077683I24J-199D01*
G01X1599188Y1077417D01*
X1599215Y1077328D01*
X1599212Y1077307D01*
G03X1599190Y1077066I1280J-238D01*
G03X1599212Y1076827I1302J-1D01*
G01Y1076823D01*
X1599215Y1076804D01*
X1599188Y1076715D01*
X1598934Y1076449D01*
G02X1598766Y1076389I-144J139D01*
G01X1598765D01*
G03X1598622Y1076398I-147J-1193D01*
G03Y1073994I0J-1202D01*
G03X1598765Y1074003I-4J1202D01*
G01X1598766D01*
G02X1598934Y1073943I24J-199D01*
G01X1599188Y1073677D01*
X1599215Y1073588D01*
X1599212Y1073567D01*
G03X1599190Y1073326I1280J-238D01*
G03X1599211Y1073094I1302J1D01*
G01Y1073090D01*
X1599216Y1073063D01*
X1599188Y1072974D01*
X1598934Y1072708D01*
G02X1598766Y1072648I-144J139D01*
G01X1598765D01*
G03X1598621Y1072657I-147J-1193D01*
G03Y1070253I0J-1202D01*
G03X1599222Y1070414I0J1202D01*
G01X1599245Y1070427D01*
X1599295Y1070441D01*
X1599322D01*
G02X1599522Y1070241I0J-200D01*
G01Y1070211D01*
G02X1599500Y1070120I-200J0D01*
G02X1599464Y1070070I-178J90D01*
G01X1598466Y1069072D01*
G02X1598416Y1069036I-140J142D01*
G02X1598325Y1069014I-91J178D01*
G01X1506804D01*
G02X1506686Y1069054I2J199D01*
G01X1506664Y1069073D01*
G02X1506629Y1069118I138J144D01*
G01X1506612Y1069148D01*
X1506610Y1069158D01*
X1506606Y1069188D01*
G03X1504884Y1074793I-18615J-2652D01*
G03X1469376Y1069187I-16893J-8257D01*
G01Y1069186D01*
X1469373Y1069167D01*
G02X1469309Y1069062I-195J47D01*
G01X1469282Y1069039D01*
X1469249Y1069027D01*
G02X1469179Y1069014I-71J187D01*
G01X1459888D01*
G02X1459797Y1069036I0J200D01*
G02X1459747Y1069072I90J178D01*
G01X1455234Y1073585D01*
G02X1455178Y1073754I142J141D01*
G01X1455248Y1074090D01*
X1455250Y1074097D01*
X1455258Y1074124D01*
G02X1455292Y1074184I188J-67D01*
G01X1455308Y1074203D01*
X1455347Y1074231D01*
X1455374Y1074241D01*
G03X1463893Y1086654I-4784J12413D01*
G03X1450591Y1099956I-13302J0D01*
G01X1450589D01*
G03X1446859Y1099422I1J-13302D01*
G01X1446845Y1099418D01*
X1446790Y1099410D01*
G02X1446671Y1099450I1J200D01*
G01X1446415Y1099642D01*
G02X1446335Y1099802I120J160D01*
G01Y1110768D01*
G37*
G36*
G01X1403609Y358397D02*
X1426083D01*
G02X1426225Y358338I0J-200D01*
G01X1431082Y353481D01*
G02X1431141Y353339I-141J-142D01*
G01Y348973D01*
G03X1431200Y348831I200J0D01*
G01X1431598Y348433D01*
G02X1431627Y348396I-142J-141D01*
G03X1431816Y348156I1115J684D01*
G01X1433249Y346724D01*
X1433258Y346694D01*
G03X1434697Y345623I1439J431D01*
G03X1436199Y347125I0J1502D01*
G03X1435186Y348545I-1502J0D01*
G02X1435182Y348547I87J179D01*
G01X1435093Y348579D01*
X1435073Y348599D01*
Y350031D01*
G02X1435132Y350173I200J0D01*
G01X1435788Y350829D01*
X1435855Y350859D01*
X1435876Y350860D01*
G03X1437263Y351950I-58J1501D01*
G01Y351952D01*
G02X1437315Y352038I192J-57D01*
G02X1437405Y352090I142J-141D01*
G01X1437740Y352177D01*
G02X1437817Y352181I49J-194D01*
G01X1438353Y351645D01*
G02X1438412Y351503I-141J-142D01*
G01Y351153D01*
X1438402Y351109D01*
X1438392Y351090D01*
G03X1438217Y350387I1327J-704D01*
G03X1441221I1502J0D01*
G03X1441047Y351088I-1502J-1D01*
G02X1441045Y351092I178J91D01*
G01X1441026Y351130D01*
Y352127D01*
G03X1440643Y353051I-1306J0D01*
G01X1440419Y353275D01*
Y353277D01*
X1440559Y353417D01*
G02X1440756Y353468I142J-141D01*
G01X1440757D01*
G03X1441180Y353407I424J1441D01*
G03Y356411I0J1502D01*
G03X1439678Y354921I0J-1502D01*
G01Y354891D01*
X1439660Y354833D01*
X1439644Y354810D01*
G02X1439555Y354739I-164J114D01*
G01X1439212Y354598D01*
G02X1439108Y354585I-76J185D01*
G01X1431123Y362571D01*
G02X1431064Y362713I141J142D01*
G01Y371373D01*
G02X1431123Y371515I200J0D01*
G01X1431812Y372204D01*
G02X1431954Y372263I142J-141D01*
G01X1436286D01*
G02X1436314Y372261I0J-200D01*
G01X1437319Y371256D01*
X1437332Y371217D01*
G03X1438768Y370153I1436J437D01*
G03X1440270Y371655I0J1502D01*
G03X1440261Y371819I-1502J0D01*
G01X1440256Y371862D01*
X1440269Y371902D01*
G02X1440310Y371974I191J-61D01*
G01X1440510Y372196D01*
G02X1440659Y372263I149J-133D01*
G01X1440766D01*
G02X1440920Y372190I0J-200D01*
G01X1441117Y371951D01*
G02X1441156Y371874I-155J-127D01*
G01X1441167Y371833D01*
X1441158Y371787D01*
G03X1441131Y371505I1475J-284D01*
G01Y371502D01*
G03X1444135I1502J0D01*
G01Y371505D01*
G03X1444108Y371787I-1502J-2D01*
G01X1444099Y371833D01*
X1444110Y371874D01*
G02X1444149Y371951I194J-50D01*
G01X1444346Y372190D01*
G02X1444500Y372263I154J-127D01*
G01X1461410D01*
G02X1461438Y372261I0J-200D01*
G01X1462851Y370849D01*
G02X1462910Y370707I-141J-142D01*
G01Y315745D01*
G03X1463292Y314823I1306J1D01*
G01X1476053Y302063D01*
G02X1476112Y301921I-141J-142D01*
G01Y258042D01*
G02X1476053Y257900I-200J0D01*
G01X1474115Y255962D01*
G02X1473973Y255903I-142J141D01*
G01X1471718D01*
X1471701Y255906D01*
G03X1471471Y255926I-228J-1286D01*
G01X1455890D01*
G02X1455748Y255985I0J200D01*
G01X1453736Y257997D01*
G03X1453594Y258056I-142J-141D01*
G01X1452071D01*
G03X1451929Y257997I0J-200D01*
G01X1451741Y257809D01*
G02X1451699Y257777I-141J142D01*
G01X1451677Y257764D01*
X1451650Y257757D01*
G03X1450704Y257016I376J-1454D01*
G01X1450690Y256990D01*
X1449776Y256076D01*
G02X1449634Y256017I-142J141D01*
G01X1447780D01*
G02X1447638Y256076I0J200D01*
G01X1443939Y259776D01*
G03X1443046Y260146I-895J-897D01*
G01X1442959D01*
X1442936Y260151D01*
G03X1442636Y260186I-300J-1271D01*
G01X1429990D01*
X1429958Y260202D01*
G03X1429247Y260382I-713J-1322D01*
G03X1428536Y260202I2J-1502D01*
G01X1428504Y260186D01*
X1426619D01*
G02X1426477Y260245I0J200D01*
G01X1423059Y263663D01*
G02X1423000Y263805I141J142D01*
G01Y293952D01*
G03X1422965Y294252I-1306J0D01*
G01X1422960Y294275D01*
Y296758D01*
G03X1422590Y297651I-1267J-2D01*
G01X1401405Y318835D01*
G02X1401386Y318857I141J141D01*
G02X1401348Y318947I160J121D01*
G02X1401346Y318977I198J28D01*
G01Y320907D01*
Y320910D01*
G02X1401408Y321052I200J-3D01*
G01X1401417Y321059D01*
G02X1401459Y321087I131J-151D01*
G01X1401643Y321177D01*
X1401783Y321245D01*
G02X1401892Y321264I88J-180D01*
G01X1401918Y321261D01*
X1401970Y321240D01*
X1401993Y321222D01*
G03X1402921Y320901I928J1181D01*
G03Y323905I0J1502D01*
G03X1401993Y323584I0J-1502D01*
G01X1401992Y323583D01*
G02X1401890Y323542I-123J158D01*
G01X1401864Y323539D01*
X1401809Y323549D01*
X1401643Y323629D01*
X1401459Y323719D01*
G02X1401417Y323747I89J179D01*
G01X1401408Y323754D01*
G02X1401346Y323896I138J145D01*
G01Y356134D01*
G02X1401405Y356276I200J0D01*
G01X1403467Y358338D01*
G02X1403609Y358397I142J-141D01*
G37*
G36*
G01X1416924Y384373D02*
G03I-577J0D01*
G37*
G36*
G01X1411977Y398032D02*
G03I-577J0D01*
G37*
G36*
G01X1414466Y415642D02*
G03I-577J0D01*
G37*
G36*
G01X1417407Y407134D02*
G03I-577J0D01*
G37*
G36*
G01X1508917Y54588D02*
X1537184D01*
X1537398Y54374D01*
Y52805D01*
X1537184Y52591D01*
X1508917D01*
G03X1502980Y46654I0J-5937D01*
G01Y7874D01*
G02X1497106Y2000I-5874J0D01*
G01X1449862D01*
G02X1443988Y7874I0J5874D01*
G01Y46654D01*
G03X1442424Y50670I-5938J0D01*
G01Y50786D01*
X1442657Y51019D01*
X1444546D01*
X1444895Y50670D01*
G02X1445986Y46656I-6843J-4015D01*
G01Y7874D01*
G03X1449862Y3998I3876J0D01*
G01X1497106D01*
G03X1500982Y7874I0J3876D01*
G01Y46654D01*
G02X1508917Y54588I7935J-1D01*
G37*
G36*
G01X1461335Y964253D02*
G03I-680J0D01*
G37*
G36*
G01X1536975Y1059258D02*
X1593219D01*
G02X1593361Y1059199I0J-200D01*
G01X1594525Y1058035D01*
G02X1594584Y1057893I-141J-142D01*
G01Y1045495D01*
G02X1594577Y1045441I-200J-2D01*
G01X1513768Y756443D01*
G02X1513717Y756355I-193J53D01*
G01X1509284Y751922D01*
G02X1509142Y751863I-142J141D01*
G01X1496132D01*
X1496095Y751879D01*
G03X1494905I-595J-1378D01*
G01X1494868Y751863D01*
X1489746D01*
G02X1489604Y751922I0J200D01*
G01X1485765Y755761D01*
G02X1485706Y755902I141J142D01*
G01Y756888D01*
G03X1485324Y757812I-1306J1D01*
G01X1476338Y766798D01*
G02X1476280Y766939I142J141D01*
G01Y823000D01*
G03X1476105Y823652I-1307J-1D01*
G02X1476078Y823752I173J100D01*
G01Y825734D01*
G02X1476145Y825883I200J0D01*
G01X1476397Y826111D01*
X1476477Y826137D01*
X1476520Y826132D01*
G03X1476677Y826124I155J1494D01*
G03Y829128I0J1502D01*
G03X1476520Y829120I-2J-1502D01*
G01X1476477Y829115D01*
X1476397Y829141D01*
X1476145Y829369D01*
G02X1476078Y829518I133J149D01*
G01Y835104D01*
G02X1476137Y835245I200J-1D01*
G01X1490341Y849449D01*
G02X1490482Y849508I142J-141D01*
G01X1503154D01*
G03X1504078Y849890I1J1306D01*
G01X1535181Y880993D01*
G03X1535564Y881917I-923J924D01*
G01Y908850D01*
G02X1535622Y908991I200J0D01*
G01X1538793Y912162D01*
G02X1538934Y912220I141J-142D01*
G01X1546503D01*
G02X1546680Y912114I1J-200D01*
G01X1546872Y911753D01*
X1546866Y911643D01*
X1546835Y911597D01*
G03X1546578Y910757I1244J-840D01*
G03X1549582I1502J0D01*
G03X1549287Y911651I-1502J0D01*
G01X1549258Y911690D01*
X1549243Y911787D01*
X1549379Y912191D01*
X1549450Y912259D01*
X1549497Y912273D01*
G03X1550056Y912603I-364J1255D01*
G01X1551486Y914033D01*
G03X1551868Y914957I-924J923D01*
G01Y932587D01*
G03X1551486Y933511I-1306J1D01*
G01X1540680Y944317D01*
G02X1540636Y944382I140J142D01*
G01X1535170Y957580D01*
G02X1535154Y957657I184J78D01*
G01Y991108D01*
G03X1535069Y991573I-1314J0D01*
G01X1535056Y991607D01*
Y1057339D01*
G02X1535115Y1057481I200J0D01*
G01X1536833Y1059199D01*
G02X1536975Y1059258I142J-141D01*
G37*
G36*
G01X1498337Y336543D02*
G03I-577J0D01*
G37*
G36*
G01X1519421Y880667D02*
X1529715Y890961D01*
G02X1529933Y891004I141J-142D01*
G01X1529990Y890980D01*
X1530056Y890881D01*
Y883708D01*
G02X1529998Y883567I-200J0D01*
G01X1520537Y874106D01*
G02X1520350Y874052I-142J141D01*
G01X1519968Y874142D01*
X1519892Y874211D01*
X1519875Y874260D01*
G03X1518452Y875282I-1423J-480D01*
G03X1516950Y873780I0J-1502D01*
G03X1517972Y872357I1502J0D01*
G01X1518021Y872340D01*
X1518090Y872264D01*
X1518180Y871882D01*
G02X1518126Y871695I-195J-45D01*
G01X1514595Y868164D01*
G02X1514432Y868106I-142J141D01*
G01X1514077Y868144D01*
X1514000Y868192D01*
X1513976Y868230D01*
G03X1512712Y868920I-1264J-813D01*
G03X1511210Y867418I0J-1502D01*
G03X1511900Y866154I1503J0D01*
G01X1511938Y866130D01*
X1511986Y866053D01*
X1512024Y865698D01*
G02X1511966Y865535I-199J-21D01*
G01X1506847Y860415D01*
G02X1506681Y860358I-141J142D01*
G01X1506323Y860401D01*
X1506246Y860451D01*
X1506222Y860491D01*
G03X1504938Y861213I-1284J-781D01*
G03X1503436Y859711I0J-1502D01*
G03X1504158Y858427I1503J0D01*
G01X1504198Y858403D01*
X1504248Y858326D01*
X1504291Y857968D01*
G02X1504234Y857802I-199J-25D01*
G01X1501730Y855299D01*
G02X1501589Y855240I-142J141D01*
G01X1494478D01*
G02X1494293Y855364I0J200D01*
G01X1494270Y855421D01*
X1494293Y855538D01*
X1498272Y859518D01*
G02X1498459Y859571I141J-142D01*
G01X1498839Y859483D01*
X1498916Y859414D01*
X1498933Y859365D01*
G03X1500353Y858353I1420J490D01*
G03X1501855Y859855I0J1502D01*
G03X1500843Y861275I-1502J0D01*
G01X1500794Y861292D01*
X1500725Y861369D01*
X1500637Y861749D01*
G02X1500690Y861936I195J46D01*
G01X1516748Y877994D01*
G02X1516901Y878052I141J-142D01*
G01X1517242Y878033D01*
X1517316Y877994D01*
X1517344Y877960D01*
G03X1518517Y877396I1173J938D01*
G03X1520019Y878898I0J1502D01*
G03X1519455Y880071I-1502J0D01*
G01X1519421Y880099D01*
X1519382Y880173D01*
X1519363Y880514D01*
G02X1519421Y880667I200J12D01*
G37*
G36*
G01X1497138Y978619D02*
X1522779D01*
G02X1522919Y978562I0J-200D01*
G01X1522920Y978561D01*
X1523730Y977751D01*
G02X1523732Y977749I-140J-142D01*
G02X1523789Y977609I-143J-140D01*
G01Y975297D01*
G02X1523780Y975238I-200J0D01*
G01X1523756Y975159D01*
X1523741Y975136D01*
G03Y973510I1263J-813D01*
G01X1523756Y973487D01*
X1523780Y973408D01*
G02X1523789Y973349I-191J-59D01*
G01Y958287D01*
G02X1523781Y958230I-200J-1D01*
G01X1523757Y958151D01*
X1523743Y958128D01*
G03Y956552I1280J-788D01*
G01X1523757Y956529D01*
X1523781Y956450D01*
G02X1523789Y956393I-192J-56D01*
G01Y950989D01*
G02X1523764Y950893I-200J1D01*
G01X1523708Y950791D01*
X1523677Y950757D01*
X1523657Y950743D01*
G03Y948257I844J-1243D01*
G01X1523677Y948243D01*
X1523708Y948209D01*
X1523764Y948107D01*
G02X1523789Y948011I-175J-97D01*
G01Y939822D01*
G02X1523688Y939648I-200J0D01*
G01X1523338Y939449D01*
X1523231Y939450D01*
X1523184Y939478D01*
G03X1522209Y939748I-977J-1632D01*
G03X1520308Y937846I0J-1901D01*
G03X1520424Y937189I1902J-3D01*
G03X1520864Y936501I1785J657D01*
G01X1523730Y933635D01*
G02X1523789Y933494I-141J-142D01*
G01Y925602D01*
G02X1523715Y925447I-200J0D01*
G01X1523439Y925222D01*
X1523352Y925201D01*
X1523307Y925210D01*
G03X1523000Y925242I-308J-1470D01*
G03Y922238I0J-1502D01*
G03X1523307Y922270I-1J1502D01*
G01X1523352Y922279D01*
X1523439Y922258D01*
X1523715Y922033D01*
G02X1523789Y921878I-126J-155D01*
G01Y920072D01*
G02X1523730Y919930I-200J0D01*
G01X1522657Y918857D01*
X1522629Y918828D01*
X1522555Y918798D01*
X1498285D01*
G02X1498143Y918857I0J200D01*
G01X1498032Y918968D01*
X1498002Y919035D01*
X1498000Y919073D01*
G03X1497192Y920333I-1500J-73D01*
G01X1497150Y920355D01*
X1497095Y920430D01*
X1497027Y920840D01*
X1497054Y920929D01*
X1497087Y920964D01*
G03X1497502Y922000I-1086J1036D01*
G03X1494498I-1502J0D01*
G03X1495308Y920667I1502J0D01*
G01X1495350Y920645D01*
X1495405Y920570D01*
X1495473Y920160D01*
X1495446Y920071D01*
X1495413Y920036D01*
G03X1494998Y918998I1087J-1036D01*
G02X1494798Y918798I-200J0D01*
G01X1490389D01*
G02X1490247Y918857I0J200D01*
G01X1488575Y920529D01*
X1488547Y920620D01*
X1488555Y920669D01*
G03X1488577Y920925I-1480J256D01*
G03X1487075Y922427I-1502J0D01*
G03X1486819Y922405I0J-1502D01*
G01X1486770Y922397D01*
X1486679Y922425D01*
X1484541Y924563D01*
X1484512Y924591D01*
X1484482Y924665D01*
Y925423D01*
G02X1484539Y925563I200J0D01*
G01X1484761Y925791D01*
X1484830Y925821D01*
X1484870Y925823D01*
G03Y928825I-46J1501D01*
G01X1484830Y928827D01*
X1484761Y928857D01*
X1484539Y929085D01*
G02X1484482Y929225I143J140D01*
G01Y930701D01*
G02X1484566Y930864I200J0D01*
G01X1484870Y931082D01*
X1484965Y931095D01*
X1485012Y931080D01*
G03X1485500Y930998I489J1420D01*
G03Y934002I0J1502D01*
G03X1485012Y933920I1J-1502D01*
G01X1484965Y933905D01*
X1484870Y933918D01*
X1484566Y934136D01*
G02X1484482Y934299I116J163D01*
G01Y938298D01*
G02X1484522Y938419I200J1D01*
G03X1484826Y939324I-1198J906D01*
G03X1484522Y940229I-1502J-1D01*
G02X1484482Y940350I160J120D01*
G01Y942011D01*
G02X1484542Y942154I200J0D01*
G01X1484546Y942157D01*
X1484803Y942387D01*
X1484885Y942413D01*
X1484927Y942408D01*
G03X1485100Y942398I173J1491D01*
G03X1486602Y943900I0J1502D01*
G01X1486603D01*
G03X1486266Y944848I-1502J0D01*
G01X1486230Y944892D01*
X1486215Y945004D01*
X1486409Y945434D01*
X1486502Y945497D01*
X1486560Y945499D01*
G03X1488002Y947000I-60J1501D01*
G03X1484998I-1502J0D01*
G01X1484997D01*
G03X1485334Y946052I1502J0D01*
G01X1485370Y946008D01*
X1485385Y945896D01*
X1485215Y945519D01*
G02X1485041Y945401I-183J82D01*
G03X1484970Y945396I70J-1500D01*
G03X1484927Y945392I118J-1497D01*
G01X1484885Y945387D01*
X1484803Y945413D01*
X1484549Y945640D01*
X1484516Y945669D01*
X1484482Y945746D01*
Y965963D01*
G02X1484539Y966103I200J0D01*
G01X1484540Y966104D01*
X1489403Y970967D01*
X1489475Y970998D01*
X1489515D01*
G03X1491002Y972485I-15J1502D01*
G01Y972525D01*
X1491033Y972597D01*
X1491737Y973301D01*
X1491861Y973323D01*
X1491919Y973296D01*
G03X1492560Y973152I642J1358D01*
G03X1494062Y974654I0J1502D01*
G03X1493918Y975295I-1502J-1D01*
G01X1493891Y975353D01*
X1493913Y975477D01*
X1496996Y978560D01*
G02X1496998Y978562I142J-140D01*
G02X1497138Y978619I140J-143D01*
G37*
G36*
G01X1504995Y897979D02*
X1518356D01*
G02X1518498Y897920I0J-200D01*
G01X1518510Y897908D01*
Y888551D01*
G02X1518451Y888409I-200J0D01*
G01X1515080Y885038D01*
G02X1514938Y884979I-142J141D01*
G01X1500117D01*
G02X1499975Y885038I0J200D01*
G01X1499093Y885920D01*
X1499064Y885948D01*
X1499034Y886022D01*
Y893570D01*
G02X1499099Y893718I200J0D01*
G03X1499586Y894825I-1015J1107D01*
G03X1499585Y894876I-1502J-4D01*
G01X1499584Y894918D01*
X1499614Y894995D01*
X1499950Y895331D01*
G03X1500009Y895473I-141J142D01*
G01Y895796D01*
G02X1500068Y895938I200J0D01*
G01X1500570Y896440D01*
G02X1500712Y896499I142J-141D01*
G01X1503349D01*
G03X1503491Y896558I0J200D01*
G01X1504853Y897920D01*
G02X1504995Y897979I142J-141D01*
G37*
G36*
G01X1611280Y54588D02*
X1639405D01*
X1639599Y54394D01*
Y52785D01*
X1639405Y52591D01*
X1611280D01*
G03X1605343Y46654I0J-5937D01*
G01Y7874D01*
G02X1599469Y2000I-5874J0D01*
G01X1552224D01*
G02X1546350Y7874I0J5874D01*
G01Y46654D01*
G03X1545263Y50079I-5939J0D01*
G01Y50191D01*
X1545272Y50200D01*
X1547511D01*
G02X1548348Y46654I-7097J-3547D01*
G01Y7874D01*
G03X1552224Y3998I3876J0D01*
G01X1599469D01*
G03X1603346Y7874I0J3877D01*
G01Y46654D01*
G02X1611280Y54588I7934J0D01*
G37*
G36*
G01X1630805Y333994D02*
X1631138Y334066D01*
G02X1631321Y334012I42J-195D01*
G01X1632619Y332714D01*
G03X1632968Y332465I923J925D01*
G02X1632984Y332456I-90J-179D01*
G03X1633640Y332272I657J1083D01*
G01X1646227D01*
X1646300Y332241D01*
X1646328Y332213D01*
X1681273Y297268D01*
G02X1681332Y297127I-141J-142D01*
G01Y261071D01*
G02X1681273Y260930I-200J1D01*
G01X1678833Y258490D01*
X1678805Y258461D01*
X1678731Y258431D01*
X1657169D01*
G03X1657027Y258372I0J-200D01*
G01X1656446Y257790D01*
X1656401Y257764D01*
X1656374Y257757D01*
G03X1655248Y256303I376J-1454D01*
G03X1655249Y256249I1502J1D01*
G02Y256236I-200J-6D01*
G02X1654849Y255847I-400J11D01*
G01X1652674D01*
G02X1652532Y255906I0J200D01*
G01X1648663Y259776D01*
G03X1647770Y260146I-895J-897D01*
G01X1647203D01*
X1647180Y260151D01*
G03X1646879Y260186I-300J-1271D01*
G01X1634739D01*
X1634692Y260198D01*
X1634670Y260209D01*
G03X1633971Y260382I-700J-1329D01*
G03X1633272Y260209I1J-1502D01*
G01X1633250Y260198D01*
X1633203Y260186D01*
X1631347D01*
G02X1631206Y260245I1J200D01*
G01X1627512Y263939D01*
G02X1627454Y264080I142J141D01*
G01Y333232D01*
G02X1627588Y333421I200J0D01*
G01X1627904Y333531D01*
G02X1628126Y333467I66J-189D01*
G03X1628287Y333295I1174J937D01*
G03X1628324Y333262I1018J1104D01*
G01X1628354Y333236D01*
X1628390Y333167D01*
X1628419Y332805D01*
X1628395Y332730D01*
X1628369Y332699D01*
G03X1628012Y331727I1145J-972D01*
G03X1628456Y330661I1502J0D01*
G01X1628484Y330633D01*
X1628514Y330562D01*
X1628520Y330204D01*
X1628492Y330131D01*
X1628464Y330102D01*
G03X1628051Y329067I1090J-1035D01*
G03X1631055I1502J0D01*
G03X1630611Y330133I-1502J0D01*
G01X1630583Y330161D01*
X1630553Y330232D01*
X1630547Y330590D01*
X1630575Y330663D01*
X1630603Y330692D01*
G03X1630579Y332786I-1090J1035D01*
G03X1630492Y332867I-1066J-1058D01*
G01X1630462Y332894D01*
X1630426Y332963D01*
X1630397Y333324D01*
X1630421Y333399D01*
X1630447Y333430D01*
G03X1630710Y333879I-1145J972D01*
G01X1630728Y333928D01*
X1630805Y333994D01*
G37*
G36*
G01X1713642Y54588D02*
X1742687D01*
X1742830Y54445D01*
Y52734D01*
X1742687Y52591D01*
X1713642D01*
G03X1707705Y46654I0J-5937D01*
G01Y7874D01*
G02X1701831Y2000I-5874J0D01*
G01X1654587D01*
G02X1648713Y7874I0J5874D01*
G01Y46210D01*
X1650710D01*
Y7874D01*
G03X1654585Y3998I3876J0D01*
G01X1701831D01*
G03X1705708Y7874I0J3877D01*
G01Y46654D01*
G02X1713642Y54588I7934J0D01*
G37*
G36*
G01X1733482Y1210401D02*
X1733604Y1210533D01*
X1733669Y1210603D01*
G02X1733729Y1210647I146J-136D01*
G01X1733762Y1210663D01*
X1733801Y1210666D01*
G03X1735197Y1212164I-106J1498D01*
G03X1735174Y1212428I-1502J2D01*
G01X1735165Y1212477D01*
X1735179Y1212523D01*
G02X1735229Y1212605I191J-60D01*
G01X1735406Y1212782D01*
G02X1735508Y1212835I139J-143D01*
G02X1735546Y1212839I40J-196D01*
G01X1743094D01*
G02X1743294Y1212639I0J-200D01*
G01Y1201989D01*
G03X1743969Y1200359I2306J0D01*
G01X1744005Y1200323D01*
G02X1744064Y1200181I-141J-142D01*
G01Y1134418D01*
G02X1744050Y1134343I-200J-1D01*
G01X1744035Y1134307D01*
X1741620Y1131892D01*
G02X1741570Y1131856I-140J142D01*
G02X1741479Y1131834I-91J178D01*
G01X1732569D01*
G02X1732515Y1131842I2J200D01*
G02X1732431Y1131893I59J191D01*
G01X1732345Y1131985D01*
X1732227Y1132111D01*
G02X1732185Y1132180I146J136D01*
G01X1732171Y1132219D01*
X1732174Y1132261D01*
G03X1732177Y1132361I-1499J95D01*
G01Y1132363D01*
G03X1732126Y1132750I-1502J-1D01*
G01X1732124Y1132759D01*
G02X1732170Y1132948I193J53D01*
G01X1732402Y1133196D01*
G02X1732550Y1133260I147J-136D01*
G01X1732587Y1133256D01*
X1732596Y1133254D01*
G03X1732881Y1133227I284J1475D01*
G01X1732890D01*
G03X1734383Y1134729I-9J1502D01*
G03X1731379I-1502J0D01*
G01Y1134726D01*
G03X1731430Y1134340I1502J2D01*
G01X1731432Y1134331D01*
Y1134225D01*
G02X1731386Y1134142I-193J53D01*
G01X1731154Y1133893D01*
G02X1731068Y1133839I-146J137D01*
G01X1731020Y1133824D01*
X1730989Y1133830D01*
X1730969Y1133834D01*
G03X1730948Y1133838I-292J-1473D01*
G01X1730946D01*
G03X1730813Y1133857I-279J-1476D01*
G01X1730769Y1133861D01*
X1730731Y1133883D01*
G02X1730668Y1133941I101J173D01*
G01X1730493Y1134189D01*
G02X1730461Y1134347I163J115D01*
G01X1730463Y1134356D01*
G03X1730509Y1134677I-1455J372D01*
G03X1730510Y1134719I-1501J57D01*
G01Y1134740D01*
G03X1729008Y1136231I-1502J-11D01*
G03X1727506Y1134742I0J-1502D01*
G01Y1134728D01*
G03X1727563Y1134318I1502J0D01*
G02X1727529Y1134141I-192J-55D01*
G01X1727418Y1134010D01*
X1727309Y1133881D01*
G02X1727229Y1133824I-152J129D01*
G01X1727184Y1133806D01*
X1727133Y1133811D01*
G03X1726963Y1133821I-173J-1492D01*
G01X1726961D01*
G03X1726884Y1133819I0J-1502D01*
G01X1726837Y1133817D01*
X1726795Y1133835D01*
G02X1726720Y1133890I78J185D01*
G01X1726515Y1134135D01*
G02X1726474Y1134216I153J128D01*
G01X1726463Y1134260D01*
X1726473Y1134306D01*
G03X1726510Y1134636I-1465J331D01*
G03X1725008Y1133134I-1502J0D01*
G01X1725010D01*
G03X1725087Y1133136I0J1502D01*
G01X1725134Y1133138D01*
X1725176Y1133120D01*
G02X1725251Y1133065I-78J-185D01*
G01X1725456Y1132820D01*
G02X1725497Y1132739I-153J-128D01*
G01X1725508Y1132695D01*
X1725498Y1132649D01*
G03X1725461Y1132320I1465J-331D01*
G01Y1132318D01*
G03X1725462Y1132252I1502J-10D01*
G01X1725464Y1132211D01*
X1725450Y1132174D01*
G02X1725407Y1132105I-188J69D01*
G01X1725207Y1131896D01*
G02X1725062Y1131834I-145J138D01*
G01X1721210D01*
G02X1721071Y1131890I0J200D01*
G01X1719398Y1133505D01*
G03X1719066Y1133792I-2730J-2822D01*
G01X1719028Y1133821D01*
X1718988Y1133903D01*
Y1134002D01*
G02X1719006Y1134086I200J1D01*
G03X1719018Y1134111I-1366J671D01*
G01X1719034Y1134121D01*
G02X1719138Y1134150I104J-171D01*
G01X1719495D01*
G02X1719600Y1134120I0J-200D01*
G02X1719671Y1134045I-105J-170D01*
G01X1719673Y1134042D01*
G03X1721008Y1133227I1335J686D01*
G03Y1136231I0J1502D01*
G03X1719674Y1135418I0J-1501D01*
G02X1719672Y1135414I-180J87D01*
G01X1719671Y1135413D01*
G02X1719600Y1135338I-176J95D01*
G02X1719495Y1135308I-105J170D01*
G01X1719138D01*
G02X1719034Y1135337I0J200D01*
G01X1719018Y1135347D01*
G03X1717626Y1136252I-1392J-618D01*
G03X1716437Y1135681I0J-1523D01*
G02X1716174Y1135637I-156J125D01*
G01X1713941Y1137045D01*
G03X1712357Y1137617I-2095J-3321D01*
G01X1712319Y1137622D01*
X1712254Y1137658D01*
X1712055Y1137898D01*
G02X1712010Y1138038I155J127D01*
G03X1712013Y1138130I-1499J95D01*
G03X1709009I-1502J0D01*
G03X1709010Y1138067I1502J-8D01*
G01X1709012Y1138026D01*
X1708984Y1137950D01*
X1708755Y1137712D01*
G02X1708611Y1137650I-145J138D01*
G01X1701670D01*
G03X1701425Y1137642I6J-3926D01*
G02X1701256Y1137718I-12J200D01*
G03X1700236Y1138211I-1020J-809D01*
G03X1699280Y1137793I0J-1302D01*
G01X1699278Y1137791D01*
X1699171Y1137745D01*
G02X1699091Y1137728I-81J183D01*
G01X1698881D01*
G02X1698801Y1137745I1J200D01*
G01X1698694Y1137791D01*
X1698692Y1137793D01*
G03X1697736Y1138211I-956J-884D01*
G03X1696561Y1137468I0J-1301D01*
G02X1696559Y1137466I-135J133D01*
G01X1696542Y1137430D01*
X1696445Y1137370D01*
X1695287D01*
X1695190Y1137430D01*
X1695172Y1137467D01*
G03X1692821Y1137468I-1176J-558D01*
G02X1692819Y1137466I-135J133D01*
G01X1692802Y1137430D01*
X1692705Y1137370D01*
X1691547D01*
X1691450Y1137430D01*
X1691435Y1137461D01*
G03X1690617Y1138160I-1179J-552D01*
G02X1690559Y1138187I54J192D01*
G03X1688385Y1138866I-2176J-3147D01*
G01X1687340D01*
G03X1686556Y1138785I-1J-3826D01*
G02X1686474I-41J196D01*
G03X1685690Y1138866I-783J-3745D01*
G01X1684645D01*
G03X1682469Y1138187I0J-3827D01*
G02X1682411Y1138160I-112J165D01*
G03X1681524Y1137273I364J-1251D01*
G02X1681497Y1137215I-192J54D01*
G03X1681181Y1136665I3149J-2175D01*
G02X1681089Y1136570I-182J84D01*
G03X1680930Y1136487I1677J-3406D01*
G01X1680906Y1136474D01*
X1680854Y1136461D01*
X1680829D01*
G02X1680729Y1136491I6J200D01*
G01X1680430Y1136676D01*
G02X1680359Y1136752I105J170D01*
G01X1680334Y1136798D01*
X1680336Y1136854D01*
G03X1680337Y1136875I-1300J72D01*
G01Y1136877D01*
G03X1680338Y1136907I-1301J58D01*
G01Y1136911D01*
G03X1679035Y1138212I-1303J-2D01*
G01X1675295D01*
G03X1673992Y1136909I0J-1303D01*
G03X1674014Y1136673I1303J2D01*
G01Y1136669D01*
X1674018Y1136648D01*
X1673990Y1136559D01*
X1673703Y1136259D01*
X1673615Y1136227D01*
X1673568Y1136233D01*
G03X1673425Y1136241I-139J-1194D01*
G03X1673203Y1136220I2J-1202D01*
G01X1673154Y1136211D01*
X1673061Y1136240D01*
X1672756Y1136545D01*
X1672727Y1136638D01*
X1672736Y1136687D01*
G03X1672757Y1136909I-1181J224D01*
G03X1670353I-1202J0D01*
G03X1670374Y1136687I1202J2D01*
G01X1670383Y1136638D01*
X1670354Y1136545D01*
X1670049Y1136240D01*
X1669956Y1136211D01*
X1669907Y1136220D01*
G03X1669685Y1136241I-224J-1181D01*
G03X1670887Y1135039I0J-1202D01*
G03X1670866Y1135261I-1202J-2D01*
G01X1670857Y1135310D01*
X1670886Y1135403D01*
X1671191Y1135708D01*
X1671284Y1135737D01*
X1671333Y1135728D01*
G03X1671555Y1135707I224J1181D01*
G03X1671777Y1135728I-2J1202D01*
G01X1671826Y1135737D01*
X1671919Y1135708D01*
X1672224Y1135403D01*
X1672253Y1135310D01*
X1672244Y1135261D01*
G03X1672223Y1135039I1181J-224D01*
G03X1674627I1202J0D01*
G03X1674619Y1135182I-1202J4D01*
G01X1674613Y1135229D01*
X1674645Y1135317D01*
X1674945Y1135604D01*
X1675034Y1135632D01*
X1675057Y1135628D01*
G03X1675295Y1135606I238J1281D01*
G01X1675572D01*
G02X1675721Y1135540I0J-200D01*
G01X1675920Y1135319D01*
G02X1675970Y1135165I-149J-134D01*
G01Y1135164D01*
G03X1675963Y1135039I1195J-130D01*
G03X1677165Y1133837I1202J0D01*
G03X1677308Y1133846I-4J1202D01*
G02X1677477Y1133785I24J-198D01*
G01X1677731Y1133519D01*
X1677759Y1133430D01*
X1677755Y1133406D01*
G03X1677733Y1133169I1280J-238D01*
G03X1677755Y1132934I1301J3D01*
G01Y1132930D01*
X1677759Y1132908D01*
X1677731Y1132819D01*
X1677477Y1132553D01*
G02X1677308Y1132492I-145J137D01*
G03X1677165Y1132501I-147J-1193D01*
G03X1675963Y1131299I0J-1202D01*
G03X1675970Y1131173I1202J4D01*
G01Y1131171D01*
X1675974Y1131130D01*
X1675948Y1131050D01*
X1675721Y1130796D01*
G02X1675572Y1130730I-149J134D01*
G01X1675330D01*
X1675329Y1130731D01*
X1675295D01*
G03X1675062Y1130709I5J-1302D01*
G01X1675056D01*
X1675033Y1130705D01*
X1674944Y1130733D01*
X1674678Y1130987D01*
G02X1674618Y1131155I139J144D01*
G01Y1131156D01*
G03X1674627Y1131299I-1193J147D01*
G03X1673425Y1130097I-1202J0D01*
G03X1673567Y1130106I-5J1202D01*
G01X1673569D01*
X1673615Y1130111D01*
X1673703Y1130079D01*
X1673990Y1129779D01*
X1674018Y1129689D01*
X1674012Y1129656D01*
G03X1673992Y1129429I1283J-227D01*
G01Y1129428D01*
G03X1674014Y1129189I1302J-1D01*
G02X1674015Y1129183I-196J-36D01*
G01X1674018Y1129167D01*
X1673990Y1129078D01*
X1673703Y1128779D01*
X1673615Y1128747D01*
X1673568Y1128753D01*
G03X1673425Y1128761I-139J-1194D01*
G03X1674627Y1127559I0J-1202D01*
G03X1674619Y1127702I-1202J4D01*
G01X1674613Y1127749D01*
X1674645Y1127837D01*
X1674944Y1128124D01*
X1675033Y1128152D01*
X1675052Y1128149D01*
G03X1675293Y1128126I244J1279D01*
G01X1675572D01*
G02X1675721Y1128060I0J-200D01*
G01X1675920Y1127839D01*
G02X1675970Y1127685I-149J-134D01*
G01Y1127684D01*
G03X1675963Y1127559I1195J-130D01*
G03X1677165Y1126357I1202J0D01*
G03X1677309Y1126366I-3J1202D01*
G01X1677355Y1126372D01*
X1677445Y1126340D01*
X1677731Y1126039D01*
X1677759Y1125950D01*
X1677751Y1125903D01*
G03X1677736Y1125775I1283J-215D01*
G03X1677753Y1125462I1299J-86D01*
G01Y1125460D01*
X1677759Y1125427D01*
X1677731Y1125338D01*
X1677445Y1125037D01*
X1677355Y1125005D01*
X1677309Y1125011D01*
G03X1677165Y1125020I-147J-1193D01*
G03X1675963Y1123818I0J-1202D01*
G03X1675970Y1123693I1202J5D01*
G01Y1123691D01*
G02X1675920Y1123537I-199J-20D01*
G01X1675721Y1123316D01*
G02X1675572Y1123250I-149J134D01*
G01X1675295D01*
G03X1675060Y1123228I3J-1302D01*
G01X1675056D01*
X1675034Y1123224D01*
X1674945Y1123252D01*
X1674679Y1123506D01*
G02X1674618Y1123675I137J145D01*
G03X1674627Y1123818I-1193J147D01*
G03X1673425Y1122616I-1202J0D01*
G03X1673568Y1122625I-4J1202D01*
G02X1673737Y1122564I24J-198D01*
G01X1673991Y1122298D01*
X1674019Y1122209D01*
X1674015Y1122185D01*
G03X1673993Y1121948I1280J-238D01*
G03X1674015Y1121713I1302J3D01*
G01Y1121709D01*
X1674019Y1121687D01*
X1673991Y1121598D01*
X1673737Y1121332D01*
G02X1673568Y1121271I-145J137D01*
G03X1673425Y1121280I-147J-1193D01*
G03X1674627Y1120078I0J-1202D01*
G03X1674618Y1120221I-1202J-4D01*
G02X1674679Y1120390I198J24D01*
G01X1674945Y1120644D01*
X1675034Y1120672D01*
X1675058Y1120668D01*
G03X1675295Y1120646I238J1280D01*
G01X1675572D01*
G02X1675721Y1120580I0J-200D01*
G01X1675920Y1120359D01*
G02X1675970Y1120205I-149J-134D01*
G01Y1120204D01*
G03X1675963Y1120078I1195J-130D01*
G03X1677165Y1118876I1202J0D01*
G03X1677309Y1118885I-3J1202D01*
G01X1677355Y1118891D01*
X1677445Y1118859D01*
X1677731Y1118558D01*
X1677759Y1118469D01*
X1677753Y1118435D01*
G03Y1117982I1282J-227D01*
G01Y1117980D01*
X1677759Y1117947D01*
X1677731Y1117858D01*
X1677445Y1117557D01*
X1677355Y1117525D01*
X1677309Y1117531D01*
G03X1677165Y1117540I-147J-1193D01*
G03X1675963Y1116338I0J-1202D01*
G03X1675970Y1116213I1202J5D01*
G01Y1116211D01*
G02X1675920Y1116057I-199J-20D01*
G01X1675721Y1115836D01*
G02X1675572Y1115770I-149J134D01*
G01X1675295D01*
G03X1675060Y1115748I3J-1302D01*
G01X1675056D01*
X1675034Y1115744D01*
X1674945Y1115772D01*
X1674679Y1116026D01*
G02X1674618Y1116195I137J145D01*
G03X1674627Y1116338I-1193J147D01*
G03X1673425Y1115136I-1202J0D01*
G03X1673568Y1115145I-4J1202D01*
G02X1673737Y1115084I24J-198D01*
G01X1673991Y1114818D01*
X1674019Y1114729D01*
X1674015Y1114705D01*
G03X1673993Y1114468I1280J-238D01*
G03X1674015Y1114233I1302J3D01*
G01Y1114229D01*
X1674019Y1114207D01*
X1673991Y1114118D01*
X1673737Y1113852D01*
G02X1673568Y1113791I-145J137D01*
G03X1673425Y1113800I-147J-1193D01*
G03X1674627Y1112598I0J-1202D01*
G03X1674618Y1112741I-1202J-4D01*
G02X1674679Y1112910I198J24D01*
G01X1674945Y1113164D01*
X1675034Y1113192D01*
X1675058Y1113188D01*
G03X1675295Y1113166I238J1280D01*
G01X1675572D01*
G02X1675721Y1113100I0J-200D01*
G01X1675920Y1112879D01*
G02X1675970Y1112725I-149J-134D01*
G01Y1112724D01*
G03X1675963Y1112598I1195J-130D01*
G03X1677165Y1111396I1202J0D01*
G03X1677309Y1111405I-3J1202D01*
G01X1677355Y1111411D01*
X1677445Y1111379D01*
X1677731Y1111078D01*
X1677759Y1110989D01*
X1677753Y1110955D01*
G03X1677736Y1110641I1282J-227D01*
G03X1677751Y1110513I1298J87D01*
G01X1677759Y1110467D01*
X1677731Y1110377D01*
X1677477Y1110110D01*
G02X1677309Y1110050I-144J139D01*
G01X1677308D01*
G03X1677164Y1110059I-147J-1193D01*
G03X1675962Y1108857I0J-1202D01*
G03X1675970Y1108715I1202J-3D01*
G01X1675976Y1108668D01*
X1675944Y1108580D01*
X1675644Y1108293D01*
X1675555Y1108265D01*
X1675531Y1108269D01*
G03X1675294Y1108291I-238J-1280D01*
G03X1675055Y1108269I-1J-1302D01*
G02X1675049Y1108268I-36J196D01*
G01X1675033Y1108265D01*
X1674944Y1108293D01*
X1674645Y1108580D01*
X1674613Y1108668D01*
X1674619Y1108715D01*
G03X1674627Y1108858I-1194J139D01*
G03X1672223I-1202J0D01*
G03X1672232Y1108715I1202J4D01*
G02X1672171Y1108546I-198J-24D01*
G01X1671905Y1108292D01*
X1671816Y1108264D01*
X1671792Y1108268D01*
G03X1671555Y1108290I-238J-1280D01*
G03X1671320Y1108268I3J-1302D01*
G01X1671316D01*
X1671294Y1108264D01*
X1671205Y1108292D01*
X1670939Y1108546D01*
G02X1670878Y1108715I137J145D01*
G03X1670887Y1108858I-1193J147D01*
G03X1668483I-1202J0D01*
G03X1668492Y1108716I1202J5D01*
G01Y1108714D01*
X1668497Y1108668D01*
X1668465Y1108580D01*
X1668165Y1108293D01*
X1668076Y1108266D01*
X1668049Y1108270D01*
G03X1667814Y1108291I-233J-1281D01*
G03X1667575Y1108269I-1J-1302D01*
G02X1667569Y1108268I-36J196D01*
G01X1667553Y1108265D01*
X1667464Y1108293D01*
X1667165Y1108580D01*
X1667133Y1108668D01*
X1667139Y1108715D01*
G03X1667147Y1108858I-1194J139D01*
G03X1664743I-1202J0D01*
G03X1664752Y1108714I1202J3D01*
G01X1664758Y1108668D01*
X1664726Y1108578D01*
X1664425Y1108292D01*
X1664336Y1108264D01*
X1664302Y1108270D01*
G03X1664075Y1108290I-227J-1282D01*
G01X1664074D01*
G03X1663839Y1108268I3J-1302D01*
G01X1663835D01*
X1663813Y1108264D01*
X1663724Y1108292D01*
X1663458Y1108546D01*
G02X1663397Y1108715I137J145D01*
G03X1663406Y1108858I-1193J147D01*
G03X1661002I-1202J0D01*
G03X1661010Y1108715I1202J-4D01*
G01X1661016Y1108668D01*
X1660984Y1108580D01*
X1660684Y1108293D01*
X1660595Y1108265D01*
X1660571Y1108269D01*
G03X1660334Y1108291I-238J-1280D01*
G03X1660099Y1108269I3J-1302D01*
G01X1660095D01*
X1660073Y1108265D01*
X1659984Y1108293D01*
X1659684Y1108580D01*
X1659652Y1108668D01*
X1659658Y1108715D01*
G03X1659666Y1108858I-1194J139D01*
G03X1657262I-1202J0D01*
G03X1657271Y1108715I1202J4D01*
G02X1657210Y1108546I-198J-24D01*
G01X1656944Y1108292D01*
X1656855Y1108264D01*
X1656831Y1108268D01*
G03X1656594Y1108290I-238J-1280D01*
G03X1656359Y1108268I3J-1302D01*
G01X1656355D01*
X1656333Y1108264D01*
X1656244Y1108292D01*
X1655978Y1108546D01*
G02X1655917Y1108715I137J145D01*
G03X1655926Y1108858I-1193J147D01*
G03X1653522I-1202J0D01*
G03X1653530Y1108716I1202J-3D01*
G01X1653536Y1108669D01*
X1653504Y1108581D01*
X1653204Y1108294D01*
X1653115Y1108266D01*
X1653089Y1108270D01*
G03X1652853Y1108292I-238J-1281D01*
G01X1652852D01*
G03X1652611Y1108269I3J-1303D01*
G01X1652607D01*
X1652593Y1108266D01*
X1652504Y1108294D01*
X1652204Y1108581D01*
X1652172Y1108669D01*
X1652178Y1108716D01*
G03X1652186Y1108858I-1194J139D01*
G03X1649782I-1202J0D01*
G03X1649791Y1108714I1202J3D01*
G01Y1108713D01*
G02X1649731Y1108545I-199J-24D01*
G01X1649465Y1108291D01*
X1649376Y1108264D01*
X1649349Y1108268D01*
G03X1649114Y1108289I-233J-1281D01*
G03X1648880Y1108268I-1J-1302D01*
G01X1648878D01*
X1648852Y1108264D01*
X1648763Y1108291D01*
X1648497Y1108545D01*
G02X1648437Y1108713I139J144D01*
G01Y1108714D01*
G03X1648446Y1108858I-1193J147D01*
G03X1647244Y1110060I-1202J0D01*
G03X1647100Y1110051I3J-1202D01*
G01X1647053Y1110045D01*
X1646965Y1110077D01*
X1646677Y1110377D01*
X1646649Y1110466D01*
X1646652Y1110486D01*
G03X1646101Y1111806I-1278J241D01*
G02X1646023Y1111910I112J165D01*
G02X1646013Y1111971I190J62D01*
G01Y1113223D01*
G02X1646101Y1113388I200J-1D01*
G03Y1115548I-727J1080D01*
G02X1646013Y1115713I112J166D01*
G01Y1116963D01*
G02X1646101Y1117128I200J-1D01*
G03Y1119288I-727J1080D01*
G02X1646013Y1119453I112J166D01*
G01Y1120703D01*
G02X1646101Y1120868I200J-1D01*
G03Y1123028I-727J1080D01*
G02X1646013Y1123193I112J166D01*
G01Y1124443D01*
G02X1646101Y1124608I200J-1D01*
G03Y1126768I-727J1080D01*
G02X1646013Y1126933I112J166D01*
G01Y1128184D01*
G02X1646101Y1128349I200J-1D01*
G03Y1130509I-727J1080D01*
G02X1646013Y1130674I112J166D01*
G01Y1135664D01*
G02X1646101Y1135829I200J-1D01*
G03Y1137989I-727J1080D01*
G02X1646013Y1138154I112J166D01*
G01Y1139404D01*
G02X1646101Y1139569I200J-1D01*
G03Y1141729I-727J1080D01*
G02X1646013Y1141894I112J166D01*
G01Y1143144D01*
G02X1646101Y1143309I200J-1D01*
G03Y1145469I-727J1080D01*
G02X1646013Y1145634I112J166D01*
G01Y1146884D01*
G02X1646101Y1147049I200J-1D01*
G03Y1149209I-727J1080D01*
G02X1646013Y1149374I112J166D01*
G01Y1150624D01*
G02X1646101Y1150789I200J-1D01*
G03Y1152949I-727J1080D01*
G02X1646013Y1153114I112J166D01*
G01Y1154365D01*
G02X1646101Y1154530I200J-1D01*
G03Y1156690I-727J1080D01*
G02X1646013Y1156855I112J166D01*
G01Y1158105D01*
G02X1646101Y1158270I200J-1D01*
G03Y1160430I-727J1080D01*
G02X1646013Y1160595I112J166D01*
G01Y1165585D01*
G02X1646101Y1165750I200J-1D01*
G03X1646676Y1166830I-727J1080D01*
G03X1646380Y1167657I-1303J0D01*
G01X1646356Y1167686D01*
X1646345Y1167719D01*
G02X1646335Y1167792I190J63D01*
G01X1646338Y1167857D01*
X1646348Y1168073D01*
G02X1646405Y1168193I199J-21D01*
G01X1647751Y1169539D01*
G02X1647871Y1169596I141J-142D01*
G01X1648087Y1169606D01*
X1648152Y1169609D01*
G02X1648225Y1169599I10J-200D01*
G01X1648258Y1169588D01*
X1648287Y1169564D01*
G03X1649114Y1169268I827J1007D01*
G03X1650414Y1170499I0J1302D01*
G01X1650416Y1170536D01*
X1650431Y1170569D01*
G02X1650472Y1170629I183J-81D01*
G01X1650559Y1170716D01*
G02X1650666Y1170770I139J-143D01*
G02X1650699Y1170773I35J-197D01*
G01X1651269D01*
G02X1651302Y1170770I-2J-200D01*
G02X1651409Y1170716I-32J-197D01*
G01X1651496Y1170629D01*
G02X1651537Y1170569I-142J-141D01*
G01X1651552Y1170536D01*
X1651554Y1170499D01*
G03X1654154I1300J71D01*
G01X1654156Y1170536D01*
X1654171Y1170569D01*
G02X1654212Y1170629I183J-81D01*
G01X1654299Y1170716D01*
G02X1654406Y1170770I139J-143D01*
G02X1654439Y1170773I35J-197D01*
G01X1654581D01*
G02X1654651Y1170760I-1J-200D01*
G01X1654684Y1170748D01*
X1654712Y1170724D01*
G03X1655183Y1170410I1483J1714D01*
G01X1655222Y1170391D01*
X1655329Y1170260D01*
X1655340Y1170220D01*
G03X1656594Y1169268I1254J350D01*
G03X1657789Y1170053I0J1302D01*
G01Y1170054D01*
G02X1657863Y1170142I184J-79D01*
G01X1657887Y1170158D01*
X1657942Y1170174D01*
X1658962D01*
G02X1658979Y1170173I-3J-200D01*
G02X1659134Y1170064I-24J-199D01*
G03X1661523Y1170040I1200J506D01*
G02X1661525Y1170044I180J-87D01*
G01X1661544Y1170085D01*
X1661579Y1170126D01*
X1661592Y1170134D01*
X1662787D01*
X1662842Y1170117D01*
X1662853Y1170110D01*
X1662884Y1170044D01*
G02X1662886Y1170040I-178J-91D01*
G03X1665264I1189J530D01*
G02X1665266Y1170044I180J-87D01*
G01X1665285Y1170085D01*
X1665320Y1170126D01*
X1665333Y1170134D01*
X1666527D01*
X1666582Y1170117D01*
X1666593Y1170110D01*
X1666624Y1170044D01*
G02X1666626Y1170040I-178J-91D01*
G03X1669004I1189J530D01*
G02X1669006Y1170044I180J-87D01*
G01X1669025Y1170085D01*
X1669060Y1170126D01*
X1669073Y1170134D01*
X1670267D01*
X1670322Y1170117D01*
X1670333Y1170110D01*
X1670364Y1170044D01*
G02X1670366Y1170040I-178J-91D01*
G03X1672744I1189J530D01*
G02X1672746Y1170044I180J-87D01*
G01X1672765Y1170085D01*
X1672800Y1170126D01*
X1672813Y1170134D01*
X1674007D01*
X1674062Y1170117D01*
X1674073Y1170110D01*
X1674104Y1170044D01*
G02X1674106Y1170040I-178J-91D01*
G03X1676484I1189J530D01*
G02X1676486Y1170044I180J-87D01*
G01X1676505Y1170085D01*
X1676540Y1170126D01*
X1676553Y1170134D01*
X1677747D01*
X1677802Y1170117D01*
X1677813Y1170110D01*
X1677844Y1170044D01*
G02X1677846Y1170040I-178J-91D01*
G03X1680224I1189J530D01*
G02X1680226Y1170044I180J-87D01*
G01X1680245Y1170085D01*
X1680280Y1170126D01*
X1680293Y1170134D01*
X1681487D01*
X1681542Y1170117D01*
X1681553Y1170110D01*
X1681584Y1170044D01*
G02X1681586Y1170040I-178J-91D01*
G03X1683964I1189J530D01*
G02X1683966Y1170044I180J-87D01*
G01X1683985Y1170085D01*
X1684020Y1170126D01*
X1684033Y1170134D01*
X1685227D01*
X1685282Y1170117D01*
X1685293Y1170110D01*
X1685324Y1170044D01*
G02X1685326Y1170040I-178J-91D01*
G03X1687704I1189J530D01*
G02X1687706Y1170044I180J-87D01*
G01X1687725Y1170085D01*
X1687760Y1170126D01*
X1687773Y1170134D01*
X1688968D01*
X1689023Y1170117D01*
X1689034Y1170110D01*
X1689065Y1170044D01*
G02X1689067Y1170040I-178J-91D01*
G03X1691445I1189J530D01*
G02X1691447Y1170044I180J-87D01*
G01X1691466Y1170085D01*
X1691501Y1170126D01*
X1691514Y1170134D01*
X1692708D01*
X1692763Y1170117D01*
X1692774Y1170110D01*
X1692805Y1170044D01*
G02X1692807Y1170040I-178J-91D01*
G03X1695185I1189J530D01*
G02X1695187Y1170044I180J-87D01*
G01X1695206Y1170085D01*
X1695241Y1170126D01*
X1695254Y1170134D01*
X1696448D01*
X1696503Y1170117D01*
X1696514Y1170110D01*
X1696545Y1170044D01*
G02X1696547Y1170040I-178J-91D01*
G03X1698925I1189J530D01*
G02X1698927Y1170044I180J-87D01*
G01X1698946Y1170085D01*
X1698981Y1170126D01*
X1698994Y1170134D01*
X1704741D01*
G03X1706264Y1170708I0J2307D01*
G02X1706266Y1170710I142J-140D01*
G01X1706293Y1170733D01*
X1706360Y1170758D01*
X1706450D01*
G03X1706698Y1170772I-6J2307D01*
G01X1706708Y1170773D01*
X1707232D01*
G03X1707374Y1170832I0J200D01*
G01X1707618Y1171076D01*
X1707639Y1171089D01*
G03X1708426Y1171876I-1189J1976D01*
G01X1708439Y1171897D01*
X1709675Y1173133D01*
G02X1709782Y1173187I139J-143D01*
G02X1709815Y1173190I35J-197D01*
G01X1710820D01*
G02X1710990Y1173096I0J-200D01*
G01X1711197Y1172763D01*
X1711202Y1172660D01*
X1711178Y1172613D01*
G03X1711024Y1171951I1348J-663D01*
G01Y1171950D01*
G03X1714028I1502J0D01*
G01Y1171951D01*
G03X1713795Y1172754I-1502J-1D01*
G01X1713770Y1172793D01*
X1713759Y1172881D01*
X1713870Y1173217D01*
G02X1713989Y1173341I190J-63D01*
G03X1715436Y1175315I-815J2115D01*
G02X1715444Y1175362I200J-10D01*
G03X1715521Y1175705I-2205J675D01*
G01X1715532Y1175779D01*
X1715644Y1175876D01*
X1717214D01*
G02X1717335Y1175835I0J-200D01*
G03X1718728Y1175366I1394J1838D01*
G01X1719995D01*
G03X1721625Y1176041I0J2306D01*
G01X1721931Y1176347D01*
G02X1722073Y1176406I142J-141D01*
G01X1723563D01*
G03X1724456Y1176776I-2J1267D01*
G01X1726382Y1178703D01*
G02X1726524Y1178762I142J-141D01*
G01X1731103D01*
G03X1731923Y1178913I-1J2306D01*
G01X1731957Y1178926D01*
X1732444D01*
G03X1733340Y1179297I0J1267D01*
G01X1733985Y1179942D01*
G02X1734092Y1179996I139J-143D01*
G02X1734125Y1179999I35J-197D01*
G01X1735905D01*
X1736013Y1179916D01*
X1736030Y1179850D01*
G03X1737482Y1178733I1452J385D01*
G03X1738984Y1180235I0J1502D01*
G01Y1180237D01*
G03X1738942Y1180588I-1502J-2D01*
G02Y1180682I195J47D01*
G03X1738984Y1181033I-1460J353D01*
G01Y1181035D01*
G03X1737947Y1182463I-1502J0D01*
G01X1737946D01*
X1737944Y1182464D01*
G02X1737847Y1182535I64J189D01*
G02X1737808Y1182653I161J119D01*
G01Y1182828D01*
X1737907Y1182940D01*
X1737983Y1182950D01*
G03Y1187526I-294J2288D01*
G01X1737907Y1187536D01*
X1737808Y1187648D01*
Y1191353D01*
G02X1737853Y1191479I200J0D01*
G02X1737966Y1191549I156J-125D01*
G01X1737967D01*
G03Y1194489I-307J1470D01*
G01X1737966D01*
G02X1737853Y1194559I43J195D01*
G02X1737808Y1194685I155J126D01*
G01Y1198682D01*
G03X1737751Y1198822I-200J0D01*
G01X1737749Y1198824D01*
G02X1737701Y1199016I145J138D01*
G01X1737723Y1199090D01*
X1737804Y1199358D01*
G02X1737956Y1199496I191J-58D01*
G03X1739164Y1200969I-294J1473D01*
G03X1737662Y1202471I-1502J0D01*
G03X1736189Y1201263I0J-1502D01*
G02X1736140Y1201167I-196J39D01*
G01X1736123Y1201148D01*
X1736077Y1201119D01*
X1735981Y1201090D01*
X1735713Y1201009D01*
G02X1735514Y1201059I-58J192D01*
G01X1735134Y1201439D01*
G02X1735086Y1201517I142J141D01*
G03X1734140Y1202463I-1424J-478D01*
G02X1734062Y1202511I63J190D01*
G01X1733487Y1203086D01*
G02X1733451Y1203136I142J140D01*
G02X1733429Y1203227I178J91D01*
G01Y1210265D01*
G02X1733439Y1210329I200J2D01*
G02X1733469Y1210386I190J-64D01*
G02X1733482Y1210401I158J-123D01*
G37*
G36*
G01X1806610Y1582196D02*
X1831979D01*
G02X1832121Y1582137I0J-200D01*
G01X1834557Y1579701D01*
G02X1834616Y1579559I-141J-142D01*
G01Y1214848D01*
X1834519Y1214736D01*
X1834445Y1214725D01*
G03Y1211753I220J-1486D01*
G01X1834519Y1211742D01*
X1834616Y1211630D01*
Y1145619D01*
G02X1834557Y1145477I-200J0D01*
G01X1832193Y1143113D01*
G02X1832051Y1143054I-142J141D01*
G01X1810756D01*
G02X1810568Y1143186I0J200D01*
G01X1810418Y1143598D01*
X1810451Y1143720D01*
X1810499Y1143761D01*
G03X1811037Y1144912I-964J1152D01*
G03X1809535Y1146414I-1502J0D01*
G03X1808548Y1146044I0J-1501D01*
G01X1808520Y1146020D01*
X1808453Y1145995D01*
X1808117D01*
X1808050Y1146020D01*
X1808022Y1146044D01*
G03X1807035Y1146414I-987J-1131D01*
G03X1805533Y1144912I0J-1502D01*
G03X1806071Y1143761I1502J1D01*
G01X1806119Y1143720D01*
X1806152Y1143598D01*
X1806002Y1143186D01*
G02X1805814Y1143054I-188J68D01*
G01X1782287D01*
G03X1782145Y1142995I0J-200D01*
G01X1778830Y1139680D01*
G02X1778688Y1139621I-142J141D01*
G01X1751006D01*
G02X1750806Y1139821I0J200D01*
G01Y1202900D01*
G03X1750131Y1204531I-2306J1D01*
G01X1749865Y1204797D01*
G02X1749806Y1204938I141J142D01*
G01Y1223862D01*
G02X1749865Y1224003I200J-1D01*
G01X1771131Y1245269D01*
G03X1771806Y1246900I-1631J1630D01*
G01Y1276345D01*
G02X1771865Y1276486I200J-1D01*
G01X1781310Y1285931D01*
G02X1781452Y1285990I142J-141D01*
G01X1818859D01*
G03X1819001Y1286049I0J200D01*
G01X1824890Y1291938D01*
G03X1824949Y1292080I-141J142D01*
G01Y1485080D01*
G03X1824890Y1485222I-200J0D01*
G01X1800307Y1509805D01*
G02X1800251Y1509980I141J142D01*
G01X1800314Y1510351D01*
X1800372Y1510427D01*
X1800417Y1510449D01*
G03X1805100Y1517889I-3569J7440D01*
G03X1798480Y1525978I-8252J0D01*
G01X1798410Y1525992D01*
X1798320Y1526103D01*
Y1573906D01*
G02X1798379Y1574048I200J0D01*
G01X1806468Y1582137D01*
G02X1806610Y1582196I142J-141D01*
G37*
G36*
G01X1751514Y1642625D02*
X1785766D01*
G02X1785908Y1642566I0J-200D01*
G01X1792873Y1635601D01*
G02X1792932Y1635459I-141J-142D01*
G01Y1541462D01*
X1792902Y1541389D01*
X1792897Y1541384D01*
Y1525253D01*
G02X1792795Y1525078I-200J-1D01*
G03X1788594Y1517889I4051J-7189D01*
G03X1793381Y1510400I8253J1D01*
G02X1793438Y1510360I-85J-181D01*
G01X1822712Y1481086D01*
G02X1822771Y1480944I-141J-142D01*
G01Y1292531D01*
G02X1822712Y1292389I-200J0D01*
G01X1820174Y1289851D01*
G02X1820032Y1289792I-142J141D01*
G01X1794234D01*
G02X1794092Y1289851I0J200D01*
G01X1790647Y1293296D01*
G02X1790588Y1293438I141J142D01*
G01Y1421030D01*
G03X1790529Y1421172I-200J0D01*
G01X1775377Y1436324D01*
G02X1775319Y1436467I142J141D01*
G01X1775321Y1436793D01*
X1775353Y1436866D01*
X1775382Y1436894D01*
G03X1775841Y1437975I-1043J1081D01*
G03X1774339Y1439477I-1502J0D01*
G03X1773258Y1439018I0J-1502D01*
G01X1773230Y1438989D01*
X1773157Y1438957D01*
X1772831Y1438955D01*
G02X1772688Y1439013I-2J200D01*
G01X1771865Y1439836D01*
G02X1771806Y1439977I141J142D01*
G01Y1588889D01*
G03X1771131Y1590520I-2306J1D01*
G01X1769301Y1592350D01*
G03X1767670Y1593026I-1632J-1631D01*
G01X1767470D01*
G02X1767329Y1593084I0J200D01*
G01X1766541Y1593872D01*
G03X1766399Y1593931I-142J-141D01*
G01X1754724D01*
G02X1754582Y1593990I0J200D01*
G01X1748281Y1600291D01*
G02X1748222Y1600433I141J142D01*
G01Y1639333D01*
G02X1748281Y1639475I200J0D01*
G01X1751372Y1642566D01*
G02X1751514Y1642625I142J-141D01*
G37*
G36*
G01X1782792Y1141615D02*
X1820658D01*
G02X1820800Y1141556I0J-200D01*
G01X1822303Y1140053D01*
G02X1822362Y1139911I-141J-142D01*
G01Y1125754D01*
G02X1822264Y1125582I-200J0D01*
G03X1821962Y1125347I764J-1293D01*
G01X1821934Y1125318D01*
X1821860Y1125288D01*
X1821496D01*
X1821422Y1125318D01*
X1821394Y1125347D01*
G03X1820328Y1125791I-1066J-1058D01*
G03X1819301Y1125385I0J-1502D01*
G01X1819273Y1125359D01*
X1819204Y1125331D01*
X1818852D01*
X1818783Y1125359D01*
X1818755Y1125385D01*
G03X1816701I-1027J-1096D01*
G01X1816673Y1125359D01*
X1816604Y1125331D01*
X1816252D01*
X1816183Y1125359D01*
X1816155Y1125385D01*
G03X1815128Y1125791I-1027J-1096D01*
G03Y1122787I0J-1502D01*
G03X1816155Y1123193I0J1502D01*
G01X1816183Y1123219D01*
X1816252Y1123247D01*
X1816604D01*
X1816673Y1123219D01*
X1816701Y1123193D01*
G03X1818755I1027J1096D01*
G01X1818783Y1123219D01*
X1818852Y1123247D01*
X1819204D01*
X1819273Y1123219D01*
X1819301Y1123193D01*
G03X1820328Y1122787I1027J1096D01*
G03X1821394Y1123231I0J1502D01*
G01X1821422Y1123260D01*
X1821496Y1123290D01*
X1821860D01*
X1821934Y1123260D01*
X1821962Y1123231D01*
G03X1822264Y1122996I1066J1058D01*
G02X1822362Y1122824I-102J-172D01*
G01Y1116052D01*
X1822303Y1115956D01*
X1822252Y1115930D01*
G03X1821862Y1115647I676J-1341D01*
G01X1821834Y1115618D01*
X1821760Y1115588D01*
X1821396D01*
X1821322Y1115618D01*
X1821294Y1115647D01*
G03X1820228Y1116091I-1066J-1058D01*
G03X1819201Y1115685I0J-1502D01*
G01X1819173Y1115659D01*
X1819104Y1115631D01*
X1818752D01*
X1818683Y1115659D01*
X1818655Y1115685D01*
G03X1816601I-1027J-1096D01*
G01X1816573Y1115659D01*
X1816504Y1115631D01*
X1816152D01*
X1816083Y1115659D01*
X1816055Y1115685D01*
G03X1815028Y1116091I-1027J-1096D01*
G03Y1113087I0J-1502D01*
G03X1816055Y1113493I0J1502D01*
G01X1816083Y1113519D01*
X1816152Y1113547D01*
X1816504D01*
X1816573Y1113519D01*
X1816601Y1113493D01*
G03X1818655I1027J1096D01*
G01X1818683Y1113519D01*
X1818752Y1113547D01*
X1819104D01*
X1819173Y1113519D01*
X1819201Y1113493D01*
G03X1820228Y1113087I1027J1096D01*
G03X1821294Y1113531I0J1502D01*
G01X1821322Y1113560D01*
X1821396Y1113590D01*
X1821760D01*
X1821834Y1113560D01*
X1821862Y1113531D01*
G03X1822252Y1113248I1066J1058D01*
G01X1822303Y1113222D01*
X1822362Y1113126D01*
Y1101186D01*
G02X1822303Y1101044I-200J0D01*
G01X1822050Y1100791D01*
G03X1821374Y1099160I1631J-1632D01*
G01Y1097017D01*
G03X1822050Y1095386I2307J1D01*
G01X1822303Y1095133D01*
G02X1822362Y1094991I-141J-142D01*
G01Y1080452D01*
G02X1822303Y1080310I-200J0D01*
G01X1821526Y1079533D01*
G02X1821384Y1079474I-142J141D01*
G01X1776347D01*
G02X1776205Y1079533I0J200D01*
G01X1768731Y1087007D01*
G02X1768672Y1087149I141J142D01*
G01Y1119269D01*
G02X1768747Y1119425I200J0D01*
G01X1769029Y1119649D01*
X1769117Y1119669D01*
X1769162Y1119658D01*
G03X1769499Y1119620I336J1464D01*
G03X1770526Y1120026I0J1502D01*
G01X1770554Y1120052D01*
X1770623Y1120080D01*
X1770975D01*
X1771044Y1120052D01*
X1771072Y1120026D01*
G03X1772099Y1119620I1027J1096D01*
G03X1773165Y1120064I0J1502D01*
G01X1773193Y1120093D01*
X1773267Y1120123D01*
X1773631D01*
X1773705Y1120093D01*
X1773733Y1120064D01*
G03X1774799Y1119620I1066J1058D01*
G03Y1122624I0J1502D01*
G03X1773733Y1122180I0J-1502D01*
G01X1773705Y1122151D01*
X1773631Y1122121D01*
X1773267D01*
X1773193Y1122151D01*
X1773165Y1122180D01*
G03X1772099Y1122624I-1066J-1058D01*
G03X1771072Y1122218I0J-1502D01*
G01X1771044Y1122192D01*
X1770975Y1122164D01*
X1770623D01*
X1770554Y1122192D01*
X1770526Y1122218D01*
G03X1769499Y1122624I-1027J-1096D01*
G03X1769162Y1122586I-1J-1502D01*
G01X1769117Y1122575D01*
X1769029Y1122595D01*
X1768747Y1122819D01*
G02X1768672Y1122975I125J156D01*
G01Y1128995D01*
G02X1768752Y1129154I200J-1D01*
G01X1769045Y1129375D01*
X1769137Y1129392D01*
X1769183Y1129379D01*
G03X1769599Y1129320I417J1443D01*
G03X1770626Y1129726I0J1502D01*
G01X1770654Y1129752D01*
X1770723Y1129780D01*
X1771075D01*
X1771144Y1129752D01*
X1771172Y1129726D01*
G03X1772199Y1129320I1027J1096D01*
G03X1773265Y1129764I0J1502D01*
G01X1773293Y1129793D01*
X1773367Y1129823D01*
X1773731D01*
X1773805Y1129793D01*
X1773833Y1129764D01*
G03X1774899Y1129320I1066J1058D01*
G03Y1132324I0J1502D01*
G03X1773833Y1131880I0J-1502D01*
G01X1773805Y1131851D01*
X1773731Y1131821D01*
X1773367D01*
X1773293Y1131851D01*
X1773265Y1131880D01*
G03X1772199Y1132324I-1066J-1058D01*
G03X1771172Y1131918I0J-1502D01*
G01X1771144Y1131892D01*
X1771075Y1131864D01*
X1770723D01*
X1770654Y1131892D01*
X1770626Y1131918D01*
G03X1769599Y1132324I-1027J-1096D01*
G03X1769183Y1132265I1J-1502D01*
G01X1769137Y1132252D01*
X1769045Y1132269D01*
X1768752Y1132490D01*
G02X1768672Y1132649I120J160D01*
G01Y1134846D01*
G02X1768731Y1134988I200J0D01*
G01X1771577Y1137834D01*
G02X1771719Y1137893I142J-141D01*
G01X1778904D01*
G03X1779046Y1137952I0J200D01*
G01X1782650Y1141556D01*
G02X1782792Y1141615I142J-141D01*
G37*
%LPC*%
G75*
G36*
G01X1464158Y194796D02*
X1464159D01*
G02X1465789Y194121I0J-2306D01*
G01X1466202Y193708D01*
G03X1466453Y193681I142J141D01*
G02X1467270Y193923I818J-1260D01*
G02X1468772Y192421I0J-1502D01*
G02X1468436Y191474I-1503J0D01*
G01X1468459Y191451D01*
X1468595Y191434D01*
X1468655Y191470D01*
G02X1469433Y191687I778J-1286D01*
G02X1470935Y190185I0J-1502D01*
G02X1469746Y188716I-1502J0D01*
G01X1469676Y188701D01*
X1469588Y188592D01*
Y188298D01*
G03X1469686Y188126I200J0D01*
G01X1469982Y187951D01*
G03X1470179Y187947I102J172D01*
G02X1470899Y188131I720J-1317D01*
G02X1472401Y186629I0J-1502D01*
G02X1471398Y185212I-1502J0D01*
G01X1471397D01*
G03X1471275Y185090I67J-189D01*
G01X1471172Y184796D01*
G03X1471189Y184625I188J-68D01*
G01X1471190Y184624D01*
G02X1471415Y183834I-1277J-791D01*
G02X1469972Y182333I-1502J0D01*
G03X1469835Y182272I7J-200D01*
G01X1469644Y182072D01*
G03X1469588Y181934I144J-139D01*
G01Y180462D01*
G03X1469648Y180319I200J0D01*
G01X1469880Y180091D01*
X1469955Y180061D01*
X1469995Y180062D01*
X1470023D01*
G02Y177058I0J-1502D01*
G01X1469995D01*
X1469955Y177059D01*
X1469880Y177029D01*
X1469648Y176801D01*
G03X1469588Y176658I140J-143D01*
G01Y174565D01*
G03X1469650Y174420I200J0D01*
G01X1469860Y174220D01*
G03X1470007Y174165I138J145D01*
G01X1470008D01*
G02X1470085Y174167I77J-1500D01*
G01X1470086D01*
G02Y171163I0J-1502D01*
G02X1468849Y171813I0J1502D01*
G01X1468824Y171850D01*
X1468747Y171895D01*
X1468396Y171927D01*
G03X1468237Y171870I-18J-199D01*
G01X1466259Y169892D01*
G02X1464628Y169216I-1632J1631D01*
G02X1462322Y171523I1J2307D01*
G01Y171524D01*
G02X1462997Y173154I2306J0D01*
G01X1464915Y175072D01*
G03X1464974Y175214I-141J142D01*
G01Y188329D01*
G03X1464915Y188471I-200J0D01*
G01X1462527Y190859D01*
G02X1461852Y192489I1631J1630D01*
G01Y192490D01*
G02X1464158Y194796I2306J0D01*
G37*
G36*
G01X1566520D02*
X1566521D01*
G02X1568151Y194121I0J-2306D01*
G01X1568564Y193708D01*
G03X1568815Y193681I142J141D01*
G02X1569632Y193923I818J-1260D01*
G02X1571134Y192421I0J-1502D01*
G02X1570798Y191474I-1503J0D01*
G01X1570821Y191451D01*
X1570957Y191434D01*
X1571017Y191470D01*
G02X1571795Y191687I778J-1286D01*
G02X1573297Y190185I0J-1502D01*
G02X1572108Y188716I-1502J0D01*
G01X1572038Y188701D01*
X1571950Y188592D01*
Y188298D01*
G03X1572048Y188126I200J0D01*
G01X1572344Y187951D01*
G03X1572541Y187947I102J172D01*
G02X1573261Y188131I720J-1317D01*
G02X1574763Y186629I0J-1502D01*
G02X1573760Y185212I-1502J0D01*
G01X1573759D01*
G03X1573637Y185090I67J-189D01*
G01X1573534Y184796D01*
G03X1573551Y184625I188J-68D01*
G01X1573552Y184624D01*
G02X1573777Y183834I-1277J-791D01*
G02X1572334Y182333I-1502J0D01*
G03X1572197Y182272I7J-200D01*
G01X1572006Y182072D01*
G03X1571950Y181934I144J-139D01*
G01Y180462D01*
G03X1572010Y180319I200J0D01*
G01X1572242Y180091D01*
X1572317Y180061D01*
X1572357Y180062D01*
X1572385D01*
G02Y177058I0J-1502D01*
G01X1572357D01*
X1572317Y177059D01*
X1572242Y177029D01*
X1572010Y176801D01*
G03X1571950Y176658I140J-143D01*
G01Y174565D01*
G03X1572012Y174420I200J0D01*
G01X1572222Y174220D01*
G03X1572369Y174165I138J145D01*
G01X1572370D01*
G02X1572447Y174167I77J-1500D01*
G01X1572448D01*
G02Y171163I0J-1502D01*
G02X1571211Y171813I0J1502D01*
G01X1571186Y171850D01*
X1571109Y171895D01*
X1570758Y171927D01*
G03X1570599Y171870I-18J-199D01*
G01X1568621Y169892D01*
G02X1566990Y169216I-1632J1631D01*
G02X1564684Y171523I1J2307D01*
G01Y171524D01*
G02X1565359Y173154I2306J0D01*
G01X1567277Y175072D01*
G03X1567336Y175214I-141J142D01*
G01Y188329D01*
G03X1567277Y188471I-200J0D01*
G01X1564889Y190859D01*
G02X1564214Y192489I1631J1630D01*
G01Y192490D01*
G02X1566520Y194796I2306J0D01*
G37*
G36*
G01X1668882D02*
G02X1670513Y194121I1J-2306D01*
G01X1670926Y193708D01*
G03X1671177Y193681I142J141D01*
G02X1671994Y193923I818J-1260D01*
G02X1673496Y192421I0J-1502D01*
G02X1673160Y191474I-1503J0D01*
G01X1673183Y191451D01*
X1673319Y191434D01*
X1673379Y191470D01*
G02X1674157Y191687I778J-1286D01*
G02X1675659Y190185I0J-1502D01*
G02X1674470Y188716I-1502J0D01*
G01X1674400Y188701D01*
X1674312Y188592D01*
Y188298D01*
G03X1674410Y188126I200J0D01*
G01X1674706Y187951D01*
G03X1674903Y187947I102J172D01*
G02X1675623Y188131I720J-1317D01*
G02X1677125Y186629I0J-1502D01*
G02X1676122Y185212I-1502J0D01*
G01X1676121D01*
G03X1675999Y185090I67J-189D01*
G01X1675896Y184796D01*
G03X1675913Y184625I188J-68D01*
G01X1675914Y184624D01*
G02X1676139Y183834I-1277J-791D01*
G02X1674696Y182333I-1502J0D01*
G03X1674559Y182272I7J-200D01*
G01X1674368Y182072D01*
G03X1674312Y181934I144J-139D01*
G01Y180462D01*
G03X1674372Y180319I200J0D01*
G01X1674604Y180091D01*
X1674679Y180061D01*
X1674719Y180062D01*
X1674747D01*
G02Y177058I0J-1502D01*
G01X1674719D01*
X1674679Y177059D01*
X1674604Y177029D01*
X1674372Y176801D01*
G03X1674312Y176658I140J-143D01*
G01Y174565D01*
G03X1674374Y174420I200J0D01*
G01X1674584Y174220D01*
G03X1674731Y174165I138J145D01*
G01X1674732D01*
G02X1674809Y174167I77J-1500D01*
G01X1674810D01*
G02Y171163I0J-1502D01*
G02X1673573Y171813I0J1502D01*
G01X1673548Y171850D01*
X1673471Y171895D01*
X1673120Y171927D01*
G03X1672961Y171870I-18J-199D01*
G01X1670983Y169892D01*
G02X1669352Y169216I-1632J1631D01*
G02X1667046Y171523I1J2307D01*
G01Y171524D01*
G02X1667721Y173154I2306J0D01*
G01X1669639Y175072D01*
G03X1669698Y175214I-141J142D01*
G01Y188329D01*
G03X1669639Y188471I-200J0D01*
G01X1667251Y190859D01*
G02X1666813Y191471I1631J1630D01*
G01X1666789Y191520D01*
X1666698Y191579D01*
X1666239Y191602D01*
X1666144Y191552D01*
X1666115Y191506D01*
G02X1664840Y190798I-1275J794D01*
G02Y193802I0J1502D01*
G01X1664841D01*
G02X1666035Y193211I0J-1502D01*
G01X1666068Y193167D01*
X1666168Y193126D01*
X1666623Y193192D01*
X1666707Y193260D01*
X1666726Y193311D01*
G02X1668882Y194796I2155J-822D01*
G37*
G36*
G01X1771244D02*
G02X1772875Y194121I1J-2306D01*
G01X1773288Y193708D01*
G03X1773539Y193681I142J141D01*
G02X1774356Y193923I818J-1260D01*
G02X1775858Y192421I0J-1502D01*
G02X1775522Y191474I-1503J0D01*
G01X1775545Y191451D01*
X1775681Y191434D01*
X1775741Y191470D01*
G02X1776519Y191687I778J-1286D01*
G02X1778021Y190185I0J-1502D01*
G02X1776832Y188716I-1502J0D01*
G01X1776762Y188701D01*
X1776674Y188592D01*
Y188298D01*
G03X1776772Y188126I200J0D01*
G01X1777068Y187951D01*
G03X1777265Y187947I102J172D01*
G02X1777985Y188131I720J-1317D01*
G02X1779487Y186629I0J-1502D01*
G02X1778484Y185212I-1502J0D01*
G01X1778483D01*
G03X1778361Y185090I67J-189D01*
G01X1778258Y184796D01*
G03X1778275Y184625I188J-68D01*
G01X1778276Y184624D01*
G02X1778501Y183834I-1277J-791D01*
G02X1777058Y182333I-1502J0D01*
G03X1776921Y182272I7J-200D01*
G01X1776730Y182072D01*
G03X1776674Y181934I144J-139D01*
G01Y180462D01*
G03X1776734Y180319I200J0D01*
G01X1776966Y180091D01*
X1777041Y180061D01*
X1777081Y180062D01*
X1777109D01*
G02Y177058I0J-1502D01*
G01X1777081D01*
X1777041Y177059D01*
X1776966Y177029D01*
X1776734Y176801D01*
G03X1776674Y176658I140J-143D01*
G01Y174565D01*
G03X1776736Y174420I200J0D01*
G01X1776946Y174220D01*
G03X1777093Y174165I138J145D01*
G01X1777094D01*
G02X1777171Y174167I77J-1500D01*
G01X1777172D01*
G02Y171163I0J-1502D01*
G02X1775935Y171813I0J1502D01*
G01X1775910Y171850D01*
X1775833Y171895D01*
X1775482Y171927D01*
G03X1775323Y171870I-18J-199D01*
G01X1773345Y169892D01*
G02X1771714Y169216I-1632J1631D01*
G02X1769408Y171523I1J2307D01*
G01Y171524D01*
G02X1770083Y173154I2306J0D01*
G01X1772001Y175072D01*
G03X1772060Y175214I-141J142D01*
G01Y188329D01*
G03X1772001Y188471I-200J0D01*
G01X1769613Y190859D01*
G02X1769175Y191471I1631J1630D01*
G01X1769151Y191520D01*
X1769060Y191579D01*
X1768601Y191602D01*
X1768506Y191552D01*
X1768477Y191506D01*
G02X1767202Y190798I-1275J794D01*
G02Y193802I0J1502D01*
G01X1767203D01*
G02X1768397Y193211I0J-1502D01*
G01X1768430Y193167D01*
X1768530Y193126D01*
X1768985Y193192D01*
X1769069Y193260D01*
X1769088Y193311D01*
G02X1771244Y194796I2155J-822D01*
G37*
G36*
G01X1546179Y345549D02*
X1549544Y348914D01*
G02X1551175Y349590I1632J-1631D01*
G02X1553480Y347366I0J-2306D01*
G01X1553483Y347286D01*
X1553599Y347174D01*
X1553862D01*
G02Y342560I0J-2307D01*
G01X1553483D01*
G03X1553341Y342501I0J-200D01*
G01X1551985Y341146D01*
G03X1551926Y341004I141J-142D01*
G01Y338017D01*
G03X1552044Y337834I200J-1D01*
G01X1552379Y337685D01*
G03X1552594Y337719I81J183D01*
G02X1553597Y338103I1003J-1118D01*
G02Y335099I0J-1502D01*
G02X1552594Y335483I0J1502D01*
G03X1552379Y335517I-134J-149D01*
G01X1552044Y335368D01*
G03X1551926Y335185I82J-182D01*
G01Y328807D01*
G03X1552041Y328626I200J0D01*
G01X1552422Y328446D01*
X1552535Y328460D01*
X1552580Y328497D01*
G02X1553534Y328839I954J-1160D01*
G02Y325835I0J-1502D01*
G02X1552580Y326177I0J1502D01*
G01X1552535Y326214D01*
X1552422Y326228D01*
X1552041Y326048D01*
G03X1551926Y325867I85J-181D01*
G01Y311406D01*
G02X1551484Y310050I-2306J2D01*
G03X1551446Y309932I162J-117D01*
G01Y307988D01*
G03X1551505Y307846I200J0D01*
G01X1552562Y306789D01*
G02X1553238Y305158I-1631J-1632D01*
G02X1550931Y302852I-2307J1D01*
G01X1550930D01*
G02X1549300Y303527I0J2306D01*
G01X1549138Y303689D01*
G03X1548876Y303707I-141J-142D01*
G02X1547972Y303404I-904J1197D01*
G02X1546915Y303839I0J1502D01*
G03X1546611Y303814I-141J-142D01*
G02X1544736Y302850I-1875J1341D01*
G02X1542430Y305156I0J2306D01*
G01Y309561D01*
G02X1543105Y311191I2306J0D01*
G01X1545445Y313530D01*
G03X1545504Y313672I-141J142D01*
G01Y314758D01*
X1545409Y314869D01*
X1545336Y314881D01*
G02Y317845I248J1482D01*
G01X1545409Y317857D01*
X1545504Y317968D01*
Y323766D01*
X1545414Y323876D01*
X1545343Y323890D01*
G02Y326836I293J1473D01*
G01X1545414Y326850D01*
X1545504Y326960D01*
Y332814D01*
X1545428Y332919D01*
X1545367Y332939D01*
G02Y335787I480J1424D01*
G01X1545428Y335807D01*
X1545504Y335912D01*
Y341467D01*
G03X1545440Y341614I-200J0D01*
G01X1545223Y341814D01*
G03X1545072Y341866I-135J-147D01*
G01X1545071D01*
G02X1544951Y341861I-122J1497D01*
G02Y344865I0J1502D01*
G02X1545396Y344797I-2J-1501D01*
G03X1545532Y344804I58J191D01*
G01X1545642Y344850D01*
G03X1545745Y344945I-75J185D01*
G02X1546179Y345549I2066J-1026D01*
G37*
G36*
G01X1596534Y381262D02*
G02X1598036Y379760I0J-1502D01*
G02X1596981Y378326I-1502J0D01*
G01X1596979D01*
G03X1596899Y378277I62J-190D01*
G01X1596392Y377770D01*
G03X1596342Y377574I142J-141D01*
G01X1596454Y377185D01*
X1596532Y377110D01*
X1596586Y377098D01*
G02X1597755Y375633I-333J-1465D01*
G02X1596700Y374199I-1502J0D01*
G01X1596698D01*
G03X1596618Y374150I62J-190D01*
G01X1592549Y370082D01*
G03X1592490Y369940I141J-142D01*
G01Y353185D01*
G03X1592598Y353007I200J0D01*
G01X1592965Y352818D01*
X1593078Y352826D01*
X1593123Y352859D01*
G02X1594466Y353290I1342J-1875D01*
G02X1596097Y352615I1J-2306D01*
G01X1599575Y349137D01*
G02X1600250Y347507I-1631J-1630D01*
G01Y336123D01*
G02X1599575Y334493I-2306J0D01*
G01X1595359Y330278D01*
G03X1595300Y330136I141J-142D01*
G01Y296138D01*
G03X1595372Y295984I200J0D01*
G01X1595644Y295758D01*
X1595730Y295736D01*
X1595774Y295744D01*
G02X1596197Y295784I428J-2267D01*
G01X1598281D01*
G02X1599912Y295108I-1J-2307D01*
G01X1600625Y294395D01*
G03X1600842Y294352I141J142D01*
G01X1600899Y294375D01*
X1600966Y294476D01*
Y336746D01*
G02X1601348Y337668I1306J-1D01*
G01X1604601Y340920D01*
G03X1604660Y341062I-141J142D01*
G01Y343002D01*
G03X1604637Y343095I-200J0D01*
G02X1604464Y343794I1329J700D01*
G02X1605381Y345178I1503J0D01*
G01X1605427Y345197D01*
X1605490Y345274D01*
X1605563Y345649D01*
G03X1605509Y345829I-196J39D01*
G01X1601773Y349564D01*
G03X1601693Y349613I-142J-141D01*
G01X1601692D01*
G02X1600636Y351047I446J1434D01*
G02X1602138Y352549I1502J0D01*
G02X1603572Y351494I0J-1502D01*
G01Y351492D01*
G03X1603621Y351412I190J62D01*
G01X1609364Y345669D01*
G02X1609746Y344747I-924J-923D01*
G01Y340214D01*
G02X1609364Y339292I-1306J1D01*
G01X1605493Y335421D01*
G03X1605434Y335279I141J-142D01*
G01Y275469D01*
G03X1605493Y275327I200J0D01*
G01X1626071Y254749D01*
G02X1626454Y253825I-923J-924D01*
G01Y175622D01*
G02X1626071Y174698I-1306J0D01*
G01X1606507Y155135D01*
G03X1606448Y154993I141J-142D01*
G01Y144431D01*
X1606467Y144391D01*
G02X1606605Y143762I-1364J-629D01*
G02X1605550Y142328I-1502J0D01*
G01X1605548D01*
G03X1605468Y142279I62J-190D01*
G01X1600041Y136852D01*
G03X1599982Y136710I141J-142D01*
G01Y117600D01*
G03X1600041Y117458I200J0D01*
G01X1609572Y107927D01*
G03X1609714Y107868I142J141D01*
G01X1610401D01*
G03X1610490Y107889I0J200D01*
G01X1610492Y107890D01*
G02X1611191Y108063I700J-1329D01*
G02X1612693Y106561I0J-1502D01*
G02X1611967Y105275I-1502J0D01*
G03X1611871Y105114I104J-171D01*
G01X1611853Y104782D01*
G03X1611933Y104612I200J-10D01*
G02X1612534Y103411I-901J-1202D01*
G02X1609530I-1502J0D01*
G02X1610538Y104829I1501J0D01*
G03X1610564Y105197I-65J190D01*
G03X1610557Y105200I-82J-182D01*
G02X1610493Y105231I622J1367D01*
G03X1610490Y105233I-112J-164D01*
G03X1610401Y105254I-89J-179D01*
G01X1609328D01*
G03X1609128Y105054I0J-200D01*
G01Y95111D01*
G02X1604516I-2306J0D01*
G01Y105231D01*
G03X1604457Y105373I-200J0D01*
G01X1594858Y114971D01*
G02X1594539Y115370I1631J1631D01*
G01X1594516Y115407D01*
X1594443Y115455D01*
X1594055Y115512D01*
X1593972Y115488D01*
X1593939Y115459D01*
G02X1592955Y115092I-984J1136D01*
G02X1591453Y116594I0J1502D01*
G02X1592032Y117779I1502J0D01*
G03X1592109Y117937I-123J158D01*
G01Y118251D01*
G03X1592032Y118409I-200J0D01*
G02X1591453Y119594I923J1185D01*
G02X1592955Y121096I1502J0D01*
G02X1593609Y120946I0J-1501D01*
G01X1593655Y120924D01*
X1593758Y120929D01*
X1594088Y121137D01*
G03X1594182Y121307I-106J170D01*
G01Y125107D01*
G02X1596489Y127414I2307J0D01*
G02X1596898Y127377I-3J-2307D01*
G01X1596942Y127369D01*
X1597028Y127391D01*
X1597297Y127617D01*
G03X1597368Y127770I-129J153D01*
G01Y137334D01*
G02X1597751Y138258I1306J0D01*
G01X1603620Y144127D01*
G03X1603669Y144207I-141J142D01*
G01Y144208D01*
G02X1603808Y144523I1435J-445D01*
G03X1603836Y144624I-172J102D01*
G01Y154574D01*
G03X1603712Y154759I-200J0D01*
G01X1603656Y154783D01*
X1603538Y154759D01*
X1599509Y150730D01*
G03X1599454Y150553I142J-141D01*
G01X1599521Y150181D01*
X1599581Y150104D01*
X1599626Y150084D01*
G02X1600505Y148717I-623J-1367D01*
G02X1599003Y147215I-1502J0D01*
G02X1597636Y148094I0J1502D01*
G01X1597616Y148139D01*
X1597539Y148199D01*
X1597167Y148266D01*
G03X1596990Y148211I-36J-197D01*
G01X1574295Y125516D01*
G03X1574236Y125374I141J-142D01*
G01Y124049D01*
G03X1574295Y123907I200J0D01*
G01X1578174Y120028D01*
G02X1578556Y119106I-924J-923D01*
G01Y107940D01*
G02X1578174Y107018I-1306J1D01*
G01X1574412Y103256D01*
G03X1574363Y103176I141J-142D01*
G01Y103175D01*
G02X1573449Y102212I-1434J446D01*
G01X1573389Y102190D01*
X1573318Y102088D01*
Y90310D01*
G03X1573429Y90131I200J0D01*
G01X1573751Y89972D01*
G03X1573962Y89993I89J179D01*
G02X1574876Y90303I914J-1192D01*
G02X1576378Y88801I0J-1502D01*
G02X1576350Y88514I-1502J2D01*
G03X1576392Y88348I196J-39D01*
G01X1576589Y88110D01*
G03X1576743Y88038I154J128D01*
G01X1577236D01*
G02X1578720Y87497I0J-2306D01*
G03X1578991Y87508I130J153D01*
G01X1579159Y87677D01*
G02X1580789Y88352I1630J-1631D01*
G01X1580790D01*
G02X1583096Y86046I0J-2306D01*
G01Y86045D01*
G02X1582421Y84415I-2306J0D01*
G01X1580201Y82195D01*
G02X1578571Y81520I-1630J1631D01*
G01X1572570D01*
G03X1572410Y81440I0J-200D01*
G01X1572190Y81144D01*
X1572173Y81051D01*
X1572187Y81006D01*
G02X1572248Y80584I-1441J-424D01*
G01Y80581D01*
G02X1569244I-1502J0D01*
G02X1570036Y81905I1503J0D01*
G01X1570038D01*
X1570079Y81928D01*
X1570133Y82004D01*
X1570187Y82369D01*
G03X1570131Y82540I-198J30D01*
G01X1567697Y84974D01*
G03X1567415I-141J-142D01*
G01X1567414Y84973D01*
G03X1567357Y84809I142J-141D01*
G02X1567374Y84535I-2290J-280D01*
G01Y74854D01*
G02X1566698Y73223I-2307J1D01*
G01X1564459Y70984D01*
G02X1562828Y70308I-1632J1631D01*
G02X1560522Y72615I1J2307D01*
G01Y72616D01*
G02X1561197Y74246I2306J0D01*
G01X1561271Y74320D01*
G03X1561329Y74465I-142J141D01*
G01X1561324Y74754D01*
G03X1561260Y74896I-200J-5D01*
G02X1560522Y76587I1568J1691D01*
G01Y82456D01*
G03X1560293Y82653I-200J-1D01*
G02X1560080Y82638I-212J1487D01*
G02X1558578Y84140I0J1502D01*
G01Y84142D01*
G02X1558748Y84835I1502J-1D01*
G03X1558712Y85069I-177J92D01*
G01X1557436Y86345D01*
G03X1557294Y86404I-142J-141D01*
G01X1540252D01*
G03X1540094Y86327I0J-200D01*
G01X1539900Y86078D01*
G03X1539864Y85906I158J-123D01*
G02X1539909Y85539I-1457J-365D01*
G02X1539503Y84512I-1502J0D01*
G01X1539477Y84485D01*
X1539449Y84414D01*
Y84064D01*
X1539477Y83993D01*
X1539503Y83966D01*
G02Y81912I-1096J-1027D01*
G01X1539477Y81885D01*
X1539449Y81814D01*
Y81464D01*
X1539477Y81393D01*
X1539503Y81366D01*
G02Y79312I-1096J-1027D01*
G01X1539477Y79285D01*
X1539449Y79214D01*
Y78864D01*
X1539477Y78793D01*
X1539503Y78766D01*
G02Y76712I-1096J-1027D01*
G01X1539477Y76685D01*
X1539449Y76614D01*
Y76264D01*
X1539477Y76193D01*
X1539503Y76166D01*
G02X1539909Y75139I-1096J-1027D01*
G02X1536905I-1502J0D01*
G02X1537311Y76166I1502J0D01*
G01X1537337Y76193D01*
X1537365Y76264D01*
Y76614D01*
X1537337Y76685D01*
X1537311Y76712D01*
G02Y78766I1096J1027D01*
G01X1537337Y78793D01*
X1537365Y78864D01*
Y79214D01*
X1537337Y79285D01*
X1537311Y79312D01*
G02Y81366I1096J1027D01*
G01X1537337Y81393D01*
X1537365Y81464D01*
Y81814D01*
X1537337Y81885D01*
X1537311Y81912D01*
G02Y83966I1096J1027D01*
G01X1537337Y83993D01*
X1537365Y84064D01*
Y84414D01*
X1537337Y84485D01*
X1537311Y84512D01*
G02X1536905Y85539I1096J1027D01*
G02X1536950Y85906I1502J2D01*
G03X1536914Y86078I-194J49D01*
G01X1536720Y86327D01*
G03X1536562Y86404I-158J-123D01*
G01X1521799D01*
G02X1520169Y87079I0J2306D01*
G01X1518229Y89019D01*
G02X1517554Y90649I1631J1630D01*
G01Y90650D01*
G02X1519860Y92956I2306J0D01*
G01X1519861D01*
G02X1521491Y92281I0J-2306D01*
G01X1522393Y91379D01*
G03X1522574Y91324I142J141D01*
G01X1522949Y91398D01*
X1523026Y91461D01*
X1523045Y91507D01*
G02X1524679Y92868I2127J-892D01*
G01X1524681D01*
G03X1524829Y93007I-44J195D01*
G01X1524928Y93344D01*
G03X1524877Y93542I-192J56D01*
G01X1524549Y93871D01*
G03X1524407Y93930I-142J-141D01*
G01X1520402D01*
G03X1520309Y93907I0J-200D01*
G02X1519610Y93734I-700J1329D01*
G02Y96738I0J1502D01*
G02X1520309Y96565I-1J-1502D01*
G03X1520402Y96542I93J177D01*
G01X1525033D01*
G02X1525955Y96160I-1J-1306D01*
G01X1526611Y95504D01*
G03X1526809Y95454I141J142D01*
G01X1527200Y95571D01*
X1527274Y95652D01*
X1527285Y95706D01*
G02X1527912Y96867I2258J-470D01*
G01X1529184Y98139D01*
G03Y98422I-141J141D01*
G01X1529128Y98478D01*
G03X1529048Y98527I-142J-141D01*
G01X1529047D01*
G02X1527991Y99961I446J1434D01*
G02X1529493Y101463I1502J0D01*
G02X1530927Y100408I0J-1502D01*
G01Y100406D01*
G03X1530976Y100326I190J62D01*
G01X1531374Y99927D01*
G03X1531516Y99868I142J141D01*
G01X1537728D01*
G03X1537870Y99927I0J200D01*
G01X1539887Y101944D01*
G03X1539942Y102123I-141J141D01*
G01X1539871Y102497D01*
X1539809Y102574D01*
X1539763Y102594D01*
G02X1538676Y104249I716J1655D01*
G01Y107649D01*
G02X1542280I1802J0D01*
G01Y105423D01*
G03X1542422Y105232I200J0D01*
G03X1542646Y105312I58J191D01*
G01X1543743Y106955D01*
G02X1544212Y107381I1087J-725D01*
G01X1546784Y108763D01*
G02X1547400Y108918I617J-1151D01*
G01X1551493D01*
G03X1551635Y108977I0J200D01*
G01X1555664Y113007D01*
G02X1556588Y113390I924J-923D01*
G01X1566991D01*
G03X1567176Y113513I0J200D01*
G01X1567199Y113569D01*
X1567176Y113687D01*
X1564738Y116125D01*
G02X1564356Y117047I924J923D01*
G01Y129021D01*
G02X1564738Y129943I1306J-1D01*
G01X1574394Y139599D01*
G03X1574438Y139817I-141J142D01*
G01X1574415Y139873D01*
X1574315Y139940D01*
X1565636D01*
G03X1565547Y139919I0J-200D01*
G01X1565545Y139918D01*
G02X1564846Y139745I-700J1329D01*
G02Y142749I0J1502D01*
G02X1565543Y142577I-1J-1502D01*
G03X1565547Y142575I91J178D01*
G01X1565568Y142564D01*
X1565612Y142554D01*
X1567517D01*
G03X1567678Y142635I0J200D01*
G01X1567898Y142933D01*
X1567913Y143027D01*
X1567899Y143072D01*
G02X1567831Y143518I1434J447D01*
G02X1570835I1502J0D01*
G02X1570767Y143072I-1502J1D01*
G01X1570753Y143027D01*
X1570768Y142933D01*
X1570988Y142635D01*
G03X1571149Y142554I161J119D01*
G01X1574932D01*
G03X1575074Y142613I0J200D01*
G01X1588184Y155723D01*
G03X1588227Y155940I-142J141D01*
G01X1588204Y155997D01*
X1588103Y156064D01*
X1577870D01*
G03X1577777Y156041I0J-200D01*
G02X1577078Y155868I-700J1329D01*
G02Y158872I0J1502D01*
G02X1577777Y158699I-1J-1502D01*
G03X1577870Y158676I93J177D01*
G01X1589060D01*
G03X1589202Y158735I0J200D01*
G01X1611967Y181501D01*
G03X1612026Y181643I-141J142D01*
G01Y213272D01*
G03X1611967Y213414I-200J0D01*
G01X1598218Y227163D01*
G03X1598138Y227212I-142J-141D01*
G01X1598137D01*
G02X1597081Y228646I446J1434D01*
G02X1598583Y230148I1502J0D01*
G02X1600017Y229093I0J-1502D01*
G01Y229091D01*
G03X1600066Y229011I190J62D01*
G01X1613119Y215958D01*
G03X1613337Y215914I142J141D01*
G01X1613393Y215937D01*
X1613460Y216037D01*
Y228437D01*
G03X1613363Y228608I-200J0D01*
G01X1613070Y228785D01*
G03X1612873Y228790I-103J-172D01*
G02X1612170Y228615I-704J1327D01*
G01X1612169D01*
G02Y231619I0J1502D01*
G01X1612170D01*
G02X1612873Y231444I-1J-1502D01*
G03X1613070Y231449I94J177D01*
G01X1613363Y231626D01*
G03X1613460Y231797I-103J171D01*
G01Y240796D01*
G03X1613401Y240938I-200J0D01*
G01X1611408Y242931D01*
G03X1611266Y242990I-142J-141D01*
G01X1610676D01*
G03X1610587Y242969I0J-200D01*
G01X1610585Y242968D01*
G02X1609886Y242795I-700J1329D01*
G02X1608384Y244297I0J1502D01*
G02X1608557Y244996I1502J-1D01*
G03X1608580Y245089I-177J93D01*
G01Y245329D01*
G03X1608380Y245529I-200J0D01*
G01X1608336D01*
X1608296Y245510D01*
G02X1607668Y245372I-629J1364D01*
G01X1607666D01*
G02Y248376I0J1502D01*
G02X1608072Y248320I0J-1502D01*
G01X1608117Y248307D01*
X1608208Y248324D01*
X1608501Y248546D01*
G03X1608580Y248705I-121J159D01*
G01Y251790D01*
G03X1608521Y251932I-200J0D01*
G01X1606858Y253594D01*
G03X1606635Y253635I-141J-142D01*
G01X1606294Y253481D01*
G03X1606176Y253287I82J-182D01*
G02X1606179Y253198I-1499J-95D01*
G02X1604677Y254700I-1502J0D01*
G02X1604766Y254697I-6J-1502D01*
G01X1604767D01*
X1604829Y254693D01*
X1604935Y254757D01*
X1605114Y255156D01*
G03X1605073Y255379I-183J82D01*
G01X1588019Y272433D01*
G02X1587636Y273357I923J924D01*
G01Y372169D01*
G02X1588019Y373093I1306J0D01*
G01X1595051Y380125D01*
G03X1595100Y380205I-141J142D01*
G01Y380206D01*
G02X1596534Y381262I1434J-446D01*
G37*
G36*
G01X1170465Y679838D02*
G02X1172466Y677836I-1J-2002D01*
G02X1171880Y676421I-2001J0D01*
G01X1169925Y674465D01*
G03X1169866Y674323I141J-142D01*
G01Y637424D01*
G02X1169279Y636009I-2002J1D01*
G01X1163511Y630241D01*
G03X1163452Y630099I141J-142D01*
G01Y567270D01*
G02X1162866Y565855I-2001J0D01*
G01X1157113Y560101D01*
G03X1157054Y559959I141J-142D01*
G01Y450612D01*
G03X1157113Y450470I200J0D01*
G01X1159649Y447933D01*
G03X1159791Y447874I142J141D01*
G01X1168851D01*
G02X1170852Y445873I0J-2001D01*
G01Y445870D01*
G02X1170642Y444979I-2001J1D01*
G03X1170651Y444784I179J-89D01*
G01X1170829Y444495D01*
G03X1171000Y444400I170J105D01*
G01X1172056D01*
G03X1172198Y444459I0J200D01*
G01X1175965Y448226D01*
G02X1177596Y448902I1632J-1631D01*
G01X1179184D01*
G02X1181490Y446595I-1J-2307D01*
G02X1180251Y444550I-2307J0D01*
G01X1180249D01*
Y444549D01*
G03X1180151Y444430I93J-177D01*
G01X1180069Y444153D01*
G03X1180087Y443997I192J-57D01*
G02X1180390Y442856I-2004J-1143D01*
G01Y441733D01*
G03X1180535Y441541I200J0D01*
G02X1181620Y440098I-417J-1443D01*
G02X1180364Y438616I-1502J0D01*
G03X1180212Y438496I32J-197D01*
G02X1179714Y437753I-2129J888D01*
G01X1173430Y431469D01*
G02X1171800Y430794I-1630J1631D01*
G01X1170548D01*
G03X1170355Y430645I0J-200D01*
G02X1167449I-1453J385D01*
G03X1167256Y430794I-193J-51D01*
G01X1155136D01*
G02X1153506Y431469I0J2306D01*
G01X1143669Y441306D01*
G02X1142994Y442936I1631J1630D01*
G01Y564882D01*
G03X1142935Y565024I-200J0D01*
G01X1139850Y568108D01*
G03X1139641Y568155I-142J-141D01*
G01X1139245Y568012D01*
X1139174Y567920D01*
X1139169Y567862D01*
G02X1137673Y566498I-1496J138D01*
G02X1136171Y568000I0J1502D01*
G02X1137535Y569496I1502J0D01*
G01X1137593Y569501D01*
X1137685Y569572D01*
X1137828Y569968D01*
G03X1137781Y570177I-188J67D01*
G01X1121074Y586884D01*
G02X1120398Y588515I1631J1632D01*
G02X1120706Y589665I2307J-2D01*
G03Y589865I-173J100D01*
G02X1120398Y591015I1999J1152D01*
G02X1122705Y593322I2307J0D01*
G01X1123704D01*
G03X1123890Y593449I0J200D01*
G02X1125287Y594399I1397J-552D01*
G02X1126789Y592897I0J-1502D01*
G01Y592895D01*
G02X1126655Y592275I-1502J0D01*
G03X1126696Y592051I182J-82D01*
G01X1148961Y569786D01*
G02X1149636Y568156I-1631J-1630D01*
G01Y562800D01*
G03X1149836Y562600I200J0D01*
G01X1153867D01*
G03X1154009Y562659I0J200D01*
G01X1159391Y568040D01*
G03X1159450Y568182I-141J142D01*
G01Y631011D01*
G02X1160036Y632426I2001J0D01*
G01X1165803Y638194D01*
G03X1165862Y638336I-141J142D01*
G01Y654835D01*
G03X1165749Y655015I-200J0D01*
G01X1165371Y655197D01*
X1165259Y655184D01*
X1165213Y655148D01*
G02X1164275Y654819I-938J1173D01*
G02Y657823I0J1502D01*
G02X1165213Y657494I0J-1502D01*
G01X1165259Y657458D01*
X1165371Y657445D01*
X1165749Y657627D01*
G03X1165862Y657807I-87J180D01*
G01Y675235D01*
G02X1166449Y676650I2002J-1D01*
G01X1169050Y679251D01*
G02X1170465Y679838I1416J-1415D01*
G37*
G36*
G01X1562385Y608398D02*
G02X1560384Y610400I1J2002D01*
G02X1560970Y611815I2001J0D01*
G01X1565514Y616360D01*
G03X1565557Y616425I-142J141D01*
G01X1569359Y625603D01*
G03X1569374Y625680I-185J76D01*
G01Y638172D01*
G03X1569359Y638249I-200J1D01*
G01X1566295Y645644D01*
G03X1566252Y645709I-185J-76D01*
G01X1563255Y648707D01*
G02X1562668Y650122I1415J1416D01*
G02X1564670Y652124I2002J0D01*
G02X1566085Y651537I-1J-2002D01*
G01X1569392Y648230D01*
G02X1569826Y647581I-1415J-1416D01*
G01X1573225Y639376D01*
G02X1573378Y638610I-1849J-768D01*
G01Y625242D01*
G02X1573225Y624476I-2002J2D01*
G01X1569088Y614488D01*
G02X1568654Y613839I-1849J767D01*
G01X1563800Y608985D01*
G02X1562385Y608398I-1416J1415D01*
G37*
G36*
G01X415777Y306272D02*
X419177D01*
G02Y302668I0J-1802D01*
G01X415777D01*
G02Y306272I0J1802D01*
G37*
G36*
G01X423651Y309272D02*
X427051D01*
G02Y305668I0J-1802D01*
G01X423651D01*
G02Y309272I0J1802D01*
G37*
G36*
G01X431525Y306272D02*
X434925D01*
G02Y302668I0J-1802D01*
G01X431525D01*
G02Y306272I0J1802D01*
G37*
G36*
G01X919628Y334530D02*
X916228D01*
G02Y338136I0J1803D01*
G01X919628D01*
G02Y334530I0J-1803D01*
G37*
G36*
G01X942730Y322242D02*
X939330D01*
G02Y325846I0J1802D01*
G01X942730D01*
G02Y322242I0J-1802D01*
G37*
G36*
G01X942699Y344560D02*
X939299D01*
G02Y348166I0J1803D01*
G01X942699D01*
G02Y344560I0J-1803D01*
G37*
G36*
G01X919353Y342348D02*
X915953D01*
G02Y345952I0J1802D01*
G01X919353D01*
G02Y342348I0J-1802D01*
G37*
G36*
G01X905899Y304150D02*
X909299D01*
G02Y300544I0J-1803D01*
G01X905899D01*
G02Y304150I0J1803D01*
G37*
G36*
G01X1033891Y298096D02*
X1037291D01*
G02Y294490I0J-1803D01*
G01X1033891D01*
G02Y298096I0J1803D01*
G37*
G36*
G01X1318363Y312364D02*
X1321763D01*
G02Y308760I0J-1802D01*
G01X1318363D01*
G02Y312364I0J1802D01*
G37*
G36*
G01X1337508Y371598D02*
X1334108D01*
G02Y375204I0J1803D01*
G01X1337508D01*
G02Y371598I0J-1803D01*
G37*
G36*
G01X1326237Y309364D02*
X1329637D01*
G02Y305760I0J-1802D01*
G01X1326237D01*
G02Y309364I0J1802D01*
G37*
G36*
G01X1334111Y312364D02*
X1337511D01*
G02Y308760I0J-1802D01*
G01X1334111D01*
G02Y312364I0J1802D01*
G37*
G36*
G01X927963Y342238D02*
X924563D01*
G02Y345844I0J1803D01*
G01X927963D01*
G02Y342238I0J-1803D01*
G37*
G36*
G01X1769063Y921922D02*
X1765663D01*
G02Y925526I0J1802D01*
G01X1769063D01*
G02Y921922I0J-1802D01*
G37*
G36*
G01X205848Y59011D02*
G02Y62015I0J1502D01*
G02X207005Y61471I0J-1502D01*
G01X207032Y61439D01*
X207106Y61402D01*
X207442Y61384D01*
G03X207593Y61441I11J200D01*
G02X208645Y61871I1052J-1072D01*
G02Y58867I0J-1502D01*
G02X207488Y59411I0J1502D01*
G01X207461Y59443D01*
X207387Y59480D01*
X207051Y59498D01*
G03X206900Y59441I-11J-200D01*
G02X205848Y59011I-1052J1072D01*
G37*
G36*
G01X560573D02*
G02Y62015I0J1502D01*
G02X561728Y61473I0J-1502D01*
G01X561756Y61439D01*
X561833Y61402D01*
X562179Y61393D01*
G03X562329Y61456I4J200D01*
G01X562330Y61457D01*
G02X563433Y61940I1103J-1018D01*
G02Y58936I0J-1502D01*
G02X562278Y59478I0J1502D01*
G01X562250Y59512D01*
X562173Y59549D01*
X561827Y59558D01*
G03X561677Y59495I-4J-200D01*
G01X561676Y59494D01*
G02X560573Y59011I-1103J1018D01*
G37*
G36*
G01X662935D02*
G02Y62015I0J1502D01*
G02X664090Y61473I0J-1502D01*
G01X664118Y61439D01*
X664195Y61402D01*
X664541Y61393D01*
G03X664691Y61456I4J200D01*
G01X664692Y61457D01*
G02X665795Y61940I1103J-1018D01*
G02Y58936I0J-1502D01*
G02X664640Y59478I0J1502D01*
G01X664612Y59512D01*
X664535Y59549D01*
X664189Y59558D01*
G03X664039Y59495I-4J-200D01*
G01X664038Y59494D01*
G02X662935Y59011I-1103J1018D01*
G37*
G36*
G01X765297D02*
G02Y62015I0J1502D01*
G02X766452Y61473I0J-1502D01*
G01X766480Y61439D01*
X766557Y61402D01*
X766903Y61393D01*
G03X767053Y61456I4J200D01*
G01X767054Y61457D01*
G02X768157Y61940I1103J-1018D01*
G02Y58936I0J-1502D01*
G02X767002Y59478I0J1502D01*
G01X766974Y59512D01*
X766897Y59549D01*
X766551Y59558D01*
G03X766401Y59495I-4J-200D01*
G01X766400Y59494D01*
G02X765297Y59011I-1103J1018D01*
G37*
G36*
G01X867659D02*
G02Y62015I0J1502D01*
G02X868814Y61473I0J-1502D01*
G01X868842Y61439D01*
X868919Y61402D01*
X869265Y61393D01*
G03X869415Y61456I4J200D01*
G01X869416Y61457D01*
G02X870519Y61940I1103J-1018D01*
G02Y58936I0J-1502D01*
G02X869364Y59478I0J1502D01*
G01X869336Y59512D01*
X869259Y59549D01*
X868913Y59558D01*
G03X868763Y59495I-4J-200D01*
G01X868762Y59494D01*
G02X867659Y59011I-1103J1018D01*
G37*
G36*
G01X1017659D02*
G02Y62015I0J1502D01*
G02X1018814Y61473I0J-1502D01*
G01X1018842Y61439D01*
X1018919Y61402D01*
X1019265Y61393D01*
G03X1019415Y61456I4J200D01*
G01X1019416Y61457D01*
G02X1020519Y61940I1103J-1018D01*
G02Y58936I0J-1502D01*
G02X1019364Y59478I0J1502D01*
G01X1019336Y59512D01*
X1019259Y59549D01*
X1018913Y59558D01*
G03X1018763Y59495I-4J-200D01*
G01X1018762Y59494D01*
G02X1017659Y59011I-1103J1018D01*
G37*
G36*
G01X1120021D02*
G02Y62015I0J1502D01*
G02X1121176Y61473I0J-1502D01*
G01X1121204Y61439D01*
X1121281Y61402D01*
X1121627Y61393D01*
G03X1121777Y61456I4J200D01*
G01X1121778Y61457D01*
G02X1122881Y61940I1103J-1018D01*
G02Y58936I0J-1502D01*
G02X1121726Y59478I0J1502D01*
G01X1121698Y59512D01*
X1121621Y59549D01*
X1121275Y59558D01*
G03X1121125Y59495I-4J-200D01*
G01X1121124Y59494D01*
G02X1120021Y59011I-1103J1018D01*
G37*
G36*
G01X1222383D02*
G02Y62015I0J1502D01*
G02X1223538Y61473I0J-1502D01*
G01X1223566Y61439D01*
X1223643Y61402D01*
X1223989Y61393D01*
G03X1224139Y61456I4J200D01*
G01X1224140Y61457D01*
G02X1225243Y61940I1103J-1018D01*
G02Y58936I0J-1502D01*
G02X1224088Y59478I0J1502D01*
G01X1224060Y59512D01*
X1223983Y59549D01*
X1223637Y59558D01*
G03X1223487Y59495I-4J-200D01*
G01X1223486Y59494D01*
G02X1222383Y59011I-1103J1018D01*
G37*
G36*
G01X1474746D02*
G02Y62015I0J1502D01*
G02X1475901Y61473I0J-1502D01*
G01X1475929Y61439D01*
X1476006Y61402D01*
X1476352Y61393D01*
G03X1476502Y61456I4J200D01*
G01X1476503Y61457D01*
G02X1477606Y61940I1103J-1018D01*
G02Y58936I0J-1502D01*
G02X1476451Y59478I0J1502D01*
G01X1476423Y59512D01*
X1476346Y59549D01*
X1476000Y59558D01*
G03X1475850Y59495I-4J-200D01*
G01X1475849Y59494D01*
G02X1474746Y59011I-1103J1018D01*
G37*
G36*
G01X1577108D02*
G02Y62015I0J1502D01*
G02X1578263Y61473I0J-1502D01*
G01X1578291Y61439D01*
X1578368Y61402D01*
X1578714Y61393D01*
G03X1578864Y61456I4J200D01*
G01X1578865Y61457D01*
G02X1579968Y61940I1103J-1018D01*
G02Y58936I0J-1502D01*
G02X1578813Y59478I0J1502D01*
G01X1578785Y59512D01*
X1578708Y59549D01*
X1578362Y59558D01*
G03X1578212Y59495I-4J-200D01*
G01X1578211Y59494D01*
G02X1577108Y59011I-1103J1018D01*
G37*
G36*
G01X1679470D02*
G02Y62015I0J1502D01*
G02X1680625Y61473I0J-1502D01*
G01X1680653Y61439D01*
X1680730Y61402D01*
X1681076Y61393D01*
G03X1681226Y61456I4J200D01*
G01X1681227Y61457D01*
G02X1682330Y61940I1103J-1018D01*
G02Y58936I0J-1502D01*
G02X1681175Y59478I0J1502D01*
G01X1681147Y59512D01*
X1681070Y59549D01*
X1680724Y59558D01*
G03X1680574Y59495I-4J-200D01*
G01X1680573Y59494D01*
G02X1679470Y59011I-1103J1018D01*
G37*
G36*
G01X307916Y59027D02*
G02Y62031I0J1502D01*
G02X309107Y61444I0J-1502D01*
G01X309134Y61409D01*
X309211Y61369D01*
X309606Y61350D01*
X309687Y61383D01*
X309717Y61416D01*
G02X310817Y61895I1100J-1024D01*
G02Y58891I0J-1502D01*
G02X309626Y59478I0J1502D01*
G01X309599Y59513D01*
X309522Y59553D01*
X309127Y59572D01*
X309046Y59539D01*
X309016Y59506D01*
G02X307916Y59027I-1100J1024D01*
G37*
G36*
G01X63283Y85193D02*
G02X66287I1502J0D01*
G02X65881Y84166I-1502J0D01*
G01X65855Y84139D01*
X65827Y84068D01*
Y83718D01*
X65855Y83647D01*
X65881Y83620D01*
G02Y81566I-1096J-1027D01*
G01X65855Y81539D01*
X65827Y81468D01*
Y81118D01*
X65855Y81047D01*
X65881Y81020D01*
G02Y78966I-1096J-1027D01*
G01X65855Y78939D01*
X65827Y78868D01*
Y78518D01*
X65855Y78447D01*
X65881Y78420D01*
G02Y76366I-1096J-1027D01*
G01X65855Y76339D01*
X65827Y76268D01*
Y75918D01*
X65855Y75847D01*
X65881Y75820D01*
G02X66287Y74793I-1096J-1027D01*
G02X63283I-1502J0D01*
G02X63689Y75820I1502J0D01*
G01X63715Y75847D01*
X63743Y75918D01*
Y76268D01*
X63715Y76339D01*
X63689Y76366D01*
G02Y78420I1096J1027D01*
G01X63715Y78447D01*
X63743Y78518D01*
Y78868D01*
X63715Y78939D01*
X63689Y78966D01*
G02Y81020I1096J1027D01*
G01X63715Y81047D01*
X63743Y81118D01*
Y81468D01*
X63715Y81539D01*
X63689Y81566D01*
G02Y83620I1096J1027D01*
G01X63715Y83647D01*
X63743Y83718D01*
Y84068D01*
X63715Y84139D01*
X63689Y84166D01*
G02X63283Y85193I1096J1027D01*
G37*
G36*
G01X106518Y117937D02*
Y118251D01*
G03X106441Y118409I-200J0D01*
G02X105862Y119594I923J1185D01*
G02X108866I1502J0D01*
G02X108287Y118409I-1502J0D01*
G03X108210Y118251I123J-158D01*
G01Y117937D01*
G03X108287Y117779I200J0D01*
G02X108866Y116594I-923J-1185D01*
G02X105862I-1502J0D01*
G02X106441Y117779I1502J0D01*
G03X106518Y117937I-123J158D01*
G37*
G36*
G01X461243D02*
Y118251D01*
G03X461166Y118409I-200J0D01*
G02X460587Y119594I923J1185D01*
G02X463591I1502J0D01*
G02X463012Y118409I-1502J0D01*
G03X462935Y118251I123J-158D01*
G01Y117937D01*
G03X463012Y117779I200J0D01*
G02X463591Y116594I-923J-1185D01*
G02X460587I-1502J0D01*
G02X461166Y117779I1502J0D01*
G03X461243Y117937I-123J158D01*
G37*
G36*
G01X918329D02*
Y118251D01*
G03X918252Y118409I-200J0D01*
G02X917673Y119594I923J1185D01*
G02X920677I1502J0D01*
G02X920098Y118409I-1502J0D01*
G03X920021Y118251I123J-158D01*
G01Y117937D01*
G03X920098Y117779I200J0D01*
G02X920677Y116594I-923J-1185D01*
G02X917673I-1502J0D01*
G02X918252Y117779I1502J0D01*
G03X918329Y117937I-123J158D01*
G37*
G36*
G01X1020691D02*
Y118251D01*
G03X1020614Y118409I-200J0D01*
G02X1020035Y119594I923J1185D01*
G02X1023039I1502J0D01*
G02X1022460Y118409I-1502J0D01*
G03X1022383Y118251I123J-158D01*
G01Y117937D01*
G03X1022460Y117779I200J0D01*
G02X1023039Y116594I-923J-1185D01*
G02X1020035I-1502J0D01*
G02X1020614Y117779I1502J0D01*
G03X1020691Y117937I-123J158D01*
G37*
G36*
G01X1123053D02*
Y118251D01*
G03X1122976Y118409I-200J0D01*
G02X1122397Y119594I923J1185D01*
G02X1125401I1502J0D01*
G02X1124822Y118409I-1502J0D01*
G03X1124745Y118251I123J-158D01*
G01Y117937D01*
G03X1124822Y117779I200J0D01*
G02X1125401Y116594I-923J-1185D01*
G02X1122397I-1502J0D01*
G02X1122976Y117779I1502J0D01*
G03X1123053Y117937I-123J158D01*
G37*
G36*
G01X1225415D02*
Y118251D01*
G03X1225338Y118409I-200J0D01*
G02X1224759Y119594I923J1185D01*
G02X1227763I1502J0D01*
G02X1227184Y118409I-1502J0D01*
G03X1227107Y118251I123J-158D01*
G01Y117937D01*
G03X1227184Y117779I200J0D01*
G02X1227763Y116594I-923J-1185D01*
G02X1224759I-1502J0D01*
G02X1225338Y117779I1502J0D01*
G03X1225415Y117937I-123J158D01*
G37*
G36*
G01X1375416D02*
Y118251D01*
G03X1375339Y118409I-200J0D01*
G02X1374760Y119594I923J1185D01*
G02X1377764I1502J0D01*
G02X1377185Y118409I-1502J0D01*
G03X1377108Y118251I123J-158D01*
G01Y117937D01*
G03X1377185Y117779I200J0D01*
G02X1377764Y116594I-923J-1185D01*
G02X1374760I-1502J0D01*
G02X1375339Y117779I1502J0D01*
G03X1375416Y117937I-123J158D01*
G37*
G36*
G01X1477778D02*
Y118251D01*
G03X1477701Y118409I-200J0D01*
G02X1477122Y119594I923J1185D01*
G02X1480126I1502J0D01*
G02X1479547Y118409I-1502J0D01*
G03X1479470Y118251I123J-158D01*
G01Y117937D01*
G03X1479547Y117779I200J0D01*
G02X1480126Y116594I-923J-1185D01*
G02X1477122I-1502J0D01*
G02X1477701Y117779I1502J0D01*
G03X1477778Y117937I-123J158D01*
G37*
G36*
G01X1580140D02*
Y118251D01*
G03X1580063Y118409I-200J0D01*
G02X1579484Y119594I923J1185D01*
G02X1582488I1502J0D01*
G02X1581909Y118409I-1502J0D01*
G03X1581832Y118251I123J-158D01*
G01Y117937D01*
G03X1581909Y117779I200J0D01*
G02X1582488Y116594I-923J-1185D01*
G02X1579484I-1502J0D01*
G02X1580063Y117779I1502J0D01*
G03X1580140Y117937I-123J158D01*
G37*
G36*
G01X1682502D02*
Y118251D01*
G03X1682425Y118409I-200J0D01*
G02X1681846Y119594I923J1185D01*
G02X1684850I1502J0D01*
G02X1684271Y118409I-1502J0D01*
G03X1684194Y118251I123J-158D01*
G01Y117937D01*
G03X1684271Y117779I200J0D01*
G02X1684850Y116594I-923J-1185D01*
G02X1681846I-1502J0D01*
G02X1682425Y117779I1502J0D01*
G03X1682502Y117937I-123J158D01*
G37*
G36*
G01X166240Y160866D02*
G02Y163870I0J1502D01*
G02X167267Y163464I0J-1502D01*
G01X167294Y163438D01*
X167365Y163410D01*
X167715D01*
X167786Y163438D01*
X167813Y163464D01*
G02X168840Y163870I1027J-1096D01*
G02Y160866I0J-1502D01*
G02X167813Y161272I0J1502D01*
G01X167786Y161298D01*
X167715Y161326D01*
X167365D01*
X167294Y161298D01*
X167267Y161272D01*
G02X166240Y160866I-1027J1096D01*
G37*
G36*
G01X268602D02*
G02Y163870I0J1502D01*
G02X269629Y163464I0J-1502D01*
G01X269656Y163438D01*
X269727Y163410D01*
X270077D01*
X270148Y163438D01*
X270175Y163464D01*
G02X271202Y163870I1027J-1096D01*
G02Y160866I0J-1502D01*
G02X270175Y161272I0J1502D01*
G01X270148Y161298D01*
X270077Y161326D01*
X269727D01*
X269656Y161298D01*
X269629Y161272D01*
G02X268602Y160866I-1027J1096D01*
G37*
G36*
G01X370964D02*
G02Y163870I0J1502D01*
G02X371991Y163464I0J-1502D01*
G01X372018Y163438D01*
X372089Y163410D01*
X372439D01*
X372510Y163438D01*
X372537Y163464D01*
G02X373564Y163870I1027J-1096D01*
G02Y160866I0J-1502D01*
G02X372537Y161272I0J1502D01*
G01X372510Y161298D01*
X372439Y161326D01*
X372089D01*
X372018Y161298D01*
X371991Y161272D01*
G02X370964Y160866I-1027J1096D01*
G37*
G36*
G01X520965D02*
G02Y163870I0J1502D01*
G02X521992Y163464I0J-1502D01*
G01X522019Y163438D01*
X522090Y163410D01*
X522440D01*
X522511Y163438D01*
X522538Y163464D01*
G02X523565Y163870I1027J-1096D01*
G02Y160866I0J-1502D01*
G02X522538Y161272I0J1502D01*
G01X522511Y161298D01*
X522440Y161326D01*
X522090D01*
X522019Y161298D01*
X521992Y161272D01*
G02X520965Y160866I-1027J1096D01*
G37*
G36*
G01X624354Y163464D02*
X624381Y163438D01*
X624452Y163410D01*
X624802D01*
X624873Y163438D01*
X624900Y163464D01*
G02X625927Y163870I1027J-1096D01*
G02Y160866I0J-1502D01*
G02X624900Y161272I0J1502D01*
G01X624873Y161298D01*
X624802Y161326D01*
X624452D01*
X624381Y161298D01*
X624354Y161272D01*
G02X622300I-1027J1096D01*
G01X622273Y161298D01*
X622202Y161326D01*
X621852D01*
X621781Y161298D01*
X621754Y161272D01*
G02X620727Y160866I-1027J1096D01*
G02Y163870I0J1502D01*
G02X621754Y163464I0J-1502D01*
G01X621781Y163438D01*
X621852Y163410D01*
X622202D01*
X622273Y163438D01*
X622300Y163464D01*
G02X624354I1027J-1096D01*
G37*
G36*
G01X725689Y160866D02*
G02Y163870I0J1502D01*
G02X726716Y163464I0J-1502D01*
G01X726743Y163438D01*
X726814Y163410D01*
X727164D01*
X727235Y163438D01*
X727262Y163464D01*
G02X728289Y163870I1027J-1096D01*
G02Y160866I0J-1502D01*
G02X727262Y161272I0J1502D01*
G01X727235Y161298D01*
X727164Y161326D01*
X726814D01*
X726743Y161298D01*
X726716Y161272D01*
G02X725689Y160866I-1027J1096D01*
G37*
G36*
G01X828051D02*
G02Y163870I0J1502D01*
G02X829078Y163464I0J-1502D01*
G01X829105Y163438D01*
X829176Y163410D01*
X829526D01*
X829597Y163438D01*
X829624Y163464D01*
G02X830651Y163870I1027J-1096D01*
G02Y160866I0J-1502D01*
G02X829624Y161272I0J1502D01*
G01X829597Y161298D01*
X829526Y161326D01*
X829176D01*
X829105Y161298D01*
X829078Y161272D01*
G02X828051Y160866I-1027J1096D01*
G37*
G36*
G01X978051D02*
G02Y163870I0J1502D01*
G02X979078Y163464I0J-1502D01*
G01X979105Y163438D01*
X979176Y163410D01*
X979526D01*
X979597Y163438D01*
X979624Y163464D01*
G02X980651Y163870I1027J-1096D01*
G02Y160866I0J-1502D01*
G02X979624Y161272I0J1502D01*
G01X979597Y161298D01*
X979526Y161326D01*
X979176D01*
X979105Y161298D01*
X979078Y161272D01*
G02X978051Y160866I-1027J1096D01*
G37*
G36*
G01X1080413D02*
G02Y163870I0J1502D01*
G02X1081440Y163464I0J-1502D01*
G01X1081467Y163438D01*
X1081538Y163410D01*
X1081888D01*
X1081959Y163438D01*
X1081986Y163464D01*
G02X1083013Y163870I1027J-1096D01*
G02Y160866I0J-1502D01*
G02X1081986Y161272I0J1502D01*
G01X1081959Y161298D01*
X1081888Y161326D01*
X1081538D01*
X1081467Y161298D01*
X1081440Y161272D01*
G02X1080413Y160866I-1027J1096D01*
G37*
G36*
G01X1182775D02*
G02Y163870I0J1502D01*
G02X1183802Y163464I0J-1502D01*
G01X1183829Y163438D01*
X1183900Y163410D01*
X1184250D01*
X1184321Y163438D01*
X1184348Y163464D01*
G02X1185375Y163870I1027J-1096D01*
G02Y160866I0J-1502D01*
G02X1184348Y161272I0J1502D01*
G01X1184321Y161298D01*
X1184250Y161326D01*
X1183900D01*
X1183829Y161298D01*
X1183802Y161272D01*
G02X1182775Y160866I-1027J1096D01*
G37*
G36*
G01X1285137D02*
G02Y163870I0J1502D01*
G02X1286164Y163464I0J-1502D01*
G01X1286191Y163438D01*
X1286262Y163410D01*
X1286612D01*
X1286683Y163438D01*
X1286710Y163464D01*
G02X1287737Y163870I1027J-1096D01*
G02Y160866I0J-1502D01*
G02X1286710Y161272I0J1502D01*
G01X1286683Y161298D01*
X1286612Y161326D01*
X1286262D01*
X1286191Y161298D01*
X1286164Y161272D01*
G02X1285137Y160866I-1027J1096D01*
G37*
G36*
G01X1435138D02*
G02Y163870I0J1502D01*
G02X1436165Y163464I0J-1502D01*
G01X1436192Y163438D01*
X1436263Y163410D01*
X1436613D01*
X1436684Y163438D01*
X1436711Y163464D01*
G02X1437738Y163870I1027J-1096D01*
G02Y160866I0J-1502D01*
G02X1436711Y161272I0J1502D01*
G01X1436684Y161298D01*
X1436613Y161326D01*
X1436263D01*
X1436192Y161298D01*
X1436165Y161272D01*
G02X1435138Y160866I-1027J1096D01*
G37*
G36*
G01X1537500D02*
G02Y163870I0J1502D01*
G02X1538527Y163464I0J-1502D01*
G01X1538554Y163438D01*
X1538625Y163410D01*
X1538975D01*
X1539046Y163438D01*
X1539073Y163464D01*
G02X1540100Y163870I1027J-1096D01*
G02Y160866I0J-1502D01*
G02X1539073Y161272I0J1502D01*
G01X1539046Y161298D01*
X1538975Y161326D01*
X1538625D01*
X1538554Y161298D01*
X1538527Y161272D01*
G02X1537500Y160866I-1027J1096D01*
G37*
G36*
G01X1639862D02*
G02Y163870I0J1502D01*
G02X1640889Y163464I0J-1502D01*
G01X1640916Y163438D01*
X1640987Y163410D01*
X1641337D01*
X1641408Y163438D01*
X1641435Y163464D01*
G02X1642462Y163870I1027J-1096D01*
G02Y160866I0J-1502D01*
G02X1641435Y161272I0J1502D01*
G01X1641408Y161298D01*
X1641337Y161326D01*
X1640987D01*
X1640916Y161298D01*
X1640889Y161272D01*
G02X1639862Y160866I-1027J1096D01*
G37*
G36*
G01X1742224D02*
G02Y163870I0J1502D01*
G02X1743251Y163464I0J-1502D01*
G01X1743278Y163438D01*
X1743349Y163410D01*
X1743699D01*
X1743770Y163438D01*
X1743797Y163464D01*
G02X1744824Y163870I1027J-1096D01*
G02Y160866I0J-1502D01*
G02X1743797Y161272I0J1502D01*
G01X1743770Y161298D01*
X1743699Y161326D01*
X1743349D01*
X1743278Y161298D01*
X1743251Y161272D01*
G02X1742224Y160866I-1027J1096D01*
G37*
G36*
G01X174438Y170493D02*
G02X177442I1502J0D01*
G02X177072Y169506I-1501J0D01*
G01Y169505D01*
X177071D01*
G03X177023Y169375I152J-130D01*
G01Y169111D01*
G03X177071Y168981I200J0D01*
G01X177072Y168980D01*
G02X177442Y167993I-1131J-987D01*
G02X177036Y166966I-1502J0D01*
G01X177010Y166939D01*
X176982Y166868D01*
Y166518D01*
X177010Y166447D01*
X177036Y166420D01*
G02Y164366I-1096J-1027D01*
G01X177010Y164339D01*
X176982Y164268D01*
Y163918D01*
X177010Y163847D01*
X177036Y163820D01*
G02X177442Y162793I-1096J-1027D01*
G02X174438I-1502J0D01*
G02X174844Y163820I1502J0D01*
G01X174870Y163847D01*
X174898Y163918D01*
Y164268D01*
X174870Y164339D01*
X174844Y164366D01*
G02Y166420I1096J1027D01*
G01X174870Y166447D01*
X174898Y166518D01*
Y166868D01*
X174870Y166939D01*
X174844Y166966D01*
G02X174438Y167993I1096J1027D01*
G02X174808Y168980I1501J0D01*
G01Y168981D01*
X174809D01*
G03X174857Y169111I-152J130D01*
G01Y169375D01*
G03X174809Y169505I-200J0D01*
G01X174808Y169506D01*
G02X174438Y170493I1131J987D01*
G37*
G36*
G01X276800D02*
G02X279804I1502J0D01*
G02X279434Y169506I-1501J0D01*
G01Y169505D01*
X279433D01*
G03X279385Y169375I152J-130D01*
G01Y169111D01*
G03X279433Y168981I200J0D01*
G01X279434Y168980D01*
G02X279804Y167993I-1131J-987D01*
G02X279398Y166966I-1502J0D01*
G01X279372Y166939D01*
X279344Y166868D01*
Y166518D01*
X279372Y166447D01*
X279398Y166420D01*
G02Y164366I-1096J-1027D01*
G01X279372Y164339D01*
X279344Y164268D01*
Y163918D01*
X279372Y163847D01*
X279398Y163820D01*
G02X279804Y162793I-1096J-1027D01*
G02X276800I-1502J0D01*
G02X277206Y163820I1502J0D01*
G01X277232Y163847D01*
X277260Y163918D01*
Y164268D01*
X277232Y164339D01*
X277206Y164366D01*
G02Y166420I1096J1027D01*
G01X277232Y166447D01*
X277260Y166518D01*
Y166868D01*
X277232Y166939D01*
X277206Y166966D01*
G02X276800Y167993I1096J1027D01*
G02X277170Y168980I1501J0D01*
G01Y168981D01*
X277171D01*
G03X277219Y169111I-152J130D01*
G01Y169375D01*
G03X277171Y169505I-200J0D01*
G01X277170Y169506D01*
G02X276800Y170493I1131J987D01*
G37*
G36*
G01X379162D02*
G02X382166I1502J0D01*
G02X381796Y169506I-1501J0D01*
G01Y169505D01*
X381795D01*
G03X381747Y169375I152J-130D01*
G01Y169111D01*
G03X381795Y168981I200J0D01*
G01X381796Y168980D01*
G02X382166Y167993I-1131J-987D01*
G02X381760Y166966I-1502J0D01*
G01X381734Y166939D01*
X381706Y166868D01*
Y166518D01*
X381734Y166447D01*
X381760Y166420D01*
G02Y164366I-1096J-1027D01*
G01X381734Y164339D01*
X381706Y164268D01*
Y163918D01*
X381734Y163847D01*
X381760Y163820D01*
G02X382166Y162793I-1096J-1027D01*
G02X379162I-1502J0D01*
G02X379568Y163820I1502J0D01*
G01X379594Y163847D01*
X379622Y163918D01*
Y164268D01*
X379594Y164339D01*
X379568Y164366D01*
G02Y166420I1096J1027D01*
G01X379594Y166447D01*
X379622Y166518D01*
Y166868D01*
X379594Y166939D01*
X379568Y166966D01*
G02X379162Y167993I1096J1027D01*
G02X379532Y168980I1501J0D01*
G01Y168981D01*
X379533D01*
G03X379581Y169111I-152J130D01*
G01Y169375D01*
G03X379533Y169505I-200J0D01*
G01X379532Y169506D01*
G02X379162Y170493I1131J987D01*
G37*
G36*
G01X529163D02*
G02X532167I1502J0D01*
G02X531797Y169506I-1501J0D01*
G01Y169505D01*
X531796D01*
G03X531748Y169375I152J-130D01*
G01Y169111D01*
G03X531796Y168981I200J0D01*
G01X531797Y168980D01*
G02X532167Y167993I-1131J-987D01*
G02X531761Y166966I-1502J0D01*
G01X531735Y166939D01*
X531707Y166868D01*
Y166518D01*
X531735Y166447D01*
X531761Y166420D01*
G02Y164366I-1096J-1027D01*
G01X531735Y164339D01*
X531707Y164268D01*
Y163918D01*
X531735Y163847D01*
X531761Y163820D01*
G02X532167Y162793I-1096J-1027D01*
G02X529163I-1502J0D01*
G02X529569Y163820I1502J0D01*
G01X529595Y163847D01*
X529623Y163918D01*
Y164268D01*
X529595Y164339D01*
X529569Y164366D01*
G02Y166420I1096J1027D01*
G01X529595Y166447D01*
X529623Y166518D01*
Y166868D01*
X529595Y166939D01*
X529569Y166966D01*
G02X529163Y167993I1096J1027D01*
G02X529533Y168980I1501J0D01*
G01Y168981D01*
X529534D01*
G03X529582Y169111I-152J130D01*
G01Y169375D01*
G03X529534Y169505I-200J0D01*
G01X529533Y169506D01*
G02X529163Y170493I1131J987D01*
G37*
G36*
G01X631525D02*
G02X634529I1502J0D01*
G02X634159Y169506I-1501J0D01*
G01Y169505D01*
X634158D01*
G03X634110Y169375I152J-130D01*
G01Y169111D01*
G03X634158Y168981I200J0D01*
G01X634159Y168980D01*
G02X634529Y167993I-1131J-987D01*
G02X634123Y166966I-1502J0D01*
G01X634097Y166939D01*
X634069Y166868D01*
Y166518D01*
X634097Y166447D01*
X634123Y166420D01*
G02Y164366I-1096J-1027D01*
G01X634097Y164339D01*
X634069Y164268D01*
Y163918D01*
X634097Y163847D01*
X634123Y163820D01*
G02X634529Y162793I-1096J-1027D01*
G02X631525I-1502J0D01*
G02X631931Y163820I1502J0D01*
G01X631957Y163847D01*
X631985Y163918D01*
Y164268D01*
X631957Y164339D01*
X631931Y164366D01*
G02Y166420I1096J1027D01*
G01X631957Y166447D01*
X631985Y166518D01*
Y166868D01*
X631957Y166939D01*
X631931Y166966D01*
G02X631525Y167993I1096J1027D01*
G02X631895Y168980I1501J0D01*
G01Y168981D01*
X631896D01*
G03X631944Y169111I-152J130D01*
G01Y169375D01*
G03X631896Y169505I-200J0D01*
G01X631895Y169506D01*
G02X631525Y170493I1131J987D01*
G37*
G36*
G01X733887D02*
G02X736891I1502J0D01*
G02X736521Y169506I-1501J0D01*
G01Y169505D01*
X736520D01*
G03X736472Y169375I152J-130D01*
G01Y169111D01*
G03X736520Y168981I200J0D01*
G01X736521Y168980D01*
G02X736891Y167993I-1131J-987D01*
G02X736485Y166966I-1502J0D01*
G01X736459Y166939D01*
X736431Y166868D01*
Y166518D01*
X736459Y166447D01*
X736485Y166420D01*
G02Y164366I-1096J-1027D01*
G01X736459Y164339D01*
X736431Y164268D01*
Y163918D01*
X736459Y163847D01*
X736485Y163820D01*
G02X736891Y162793I-1096J-1027D01*
G02X733887I-1502J0D01*
G02X734293Y163820I1502J0D01*
G01X734319Y163847D01*
X734347Y163918D01*
Y164268D01*
X734319Y164339D01*
X734293Y164366D01*
G02Y166420I1096J1027D01*
G01X734319Y166447D01*
X734347Y166518D01*
Y166868D01*
X734319Y166939D01*
X734293Y166966D01*
G02X733887Y167993I1096J1027D01*
G02X734257Y168980I1501J0D01*
G01Y168981D01*
X734258D01*
G03X734306Y169111I-152J130D01*
G01Y169375D01*
G03X734258Y169505I-200J0D01*
G01X734257Y169506D01*
G02X733887Y170493I1131J987D01*
G37*
G36*
G01X836249D02*
G02X839253I1502J0D01*
G02X838883Y169506I-1501J0D01*
G01Y169505D01*
X838882D01*
G03X838834Y169375I152J-130D01*
G01Y169111D01*
G03X838882Y168981I200J0D01*
G01X838883Y168980D01*
G02X839253Y167993I-1131J-987D01*
G02X838847Y166966I-1502J0D01*
G01X838821Y166939D01*
X838793Y166868D01*
Y166518D01*
X838821Y166447D01*
X838847Y166420D01*
G02Y164366I-1096J-1027D01*
G01X838821Y164339D01*
X838793Y164268D01*
Y163918D01*
X838821Y163847D01*
X838847Y163820D01*
G02X839253Y162793I-1096J-1027D01*
G02X836249I-1502J0D01*
G02X836655Y163820I1502J0D01*
G01X836681Y163847D01*
X836709Y163918D01*
Y164268D01*
X836681Y164339D01*
X836655Y164366D01*
G02Y166420I1096J1027D01*
G01X836681Y166447D01*
X836709Y166518D01*
Y166868D01*
X836681Y166939D01*
X836655Y166966D01*
G02X836249Y167993I1096J1027D01*
G02X836619Y168980I1501J0D01*
G01Y168981D01*
X836620D01*
G03X836668Y169111I-152J130D01*
G01Y169375D01*
G03X836620Y169505I-200J0D01*
G01X836619Y169506D01*
G02X836249Y170493I1131J987D01*
G37*
G36*
G01X986249D02*
G02X989253I1502J0D01*
G02X988883Y169506I-1501J0D01*
G01Y169505D01*
X988882D01*
G03X988834Y169375I152J-130D01*
G01Y169111D01*
G03X988882Y168981I200J0D01*
G01X988883Y168980D01*
G02X989253Y167993I-1131J-987D01*
G02X988847Y166966I-1502J0D01*
G01X988821Y166939D01*
X988793Y166868D01*
Y166518D01*
X988821Y166447D01*
X988847Y166420D01*
G02Y164366I-1096J-1027D01*
G01X988821Y164339D01*
X988793Y164268D01*
Y163918D01*
X988821Y163847D01*
X988847Y163820D01*
G02X989253Y162793I-1096J-1027D01*
G02X986249I-1502J0D01*
G02X986655Y163820I1502J0D01*
G01X986681Y163847D01*
X986709Y163918D01*
Y164268D01*
X986681Y164339D01*
X986655Y164366D01*
G02Y166420I1096J1027D01*
G01X986681Y166447D01*
X986709Y166518D01*
Y166868D01*
X986681Y166939D01*
X986655Y166966D01*
G02X986249Y167993I1096J1027D01*
G02X986619Y168980I1501J0D01*
G01Y168981D01*
X986620D01*
G03X986668Y169111I-152J130D01*
G01Y169375D01*
G03X986620Y169505I-200J0D01*
G01X986619Y169506D01*
G02X986249Y170493I1131J987D01*
G37*
G36*
G01X1088611D02*
G02X1091615I1502J0D01*
G02X1091245Y169506I-1501J0D01*
G01Y169505D01*
X1091244D01*
G03X1091196Y169375I152J-130D01*
G01Y169111D01*
G03X1091244Y168981I200J0D01*
G01X1091245Y168980D01*
G02X1091615Y167993I-1131J-987D01*
G02X1091209Y166966I-1502J0D01*
G01X1091183Y166939D01*
X1091155Y166868D01*
Y166518D01*
X1091183Y166447D01*
X1091209Y166420D01*
G02Y164366I-1096J-1027D01*
G01X1091183Y164339D01*
X1091155Y164268D01*
Y163918D01*
X1091183Y163847D01*
X1091209Y163820D01*
G02X1091615Y162793I-1096J-1027D01*
G02X1088611I-1502J0D01*
G02X1089017Y163820I1502J0D01*
G01X1089043Y163847D01*
X1089071Y163918D01*
Y164268D01*
X1089043Y164339D01*
X1089017Y164366D01*
G02Y166420I1096J1027D01*
G01X1089043Y166447D01*
X1089071Y166518D01*
Y166868D01*
X1089043Y166939D01*
X1089017Y166966D01*
G02X1088611Y167993I1096J1027D01*
G02X1088981Y168980I1501J0D01*
G01Y168981D01*
X1088982D01*
G03X1089030Y169111I-152J130D01*
G01Y169375D01*
G03X1088982Y169505I-200J0D01*
G01X1088981Y169506D01*
G02X1088611Y170493I1131J987D01*
G37*
G36*
G01X1190973D02*
G02X1193977I1502J0D01*
G02X1193607Y169506I-1501J0D01*
G01Y169505D01*
X1193606D01*
G03X1193558Y169375I152J-130D01*
G01Y169111D01*
G03X1193606Y168981I200J0D01*
G01X1193607Y168980D01*
G02X1193977Y167993I-1131J-987D01*
G02X1193571Y166966I-1502J0D01*
G01X1193545Y166939D01*
X1193517Y166868D01*
Y166518D01*
X1193545Y166447D01*
X1193571Y166420D01*
G02Y164366I-1096J-1027D01*
G01X1193545Y164339D01*
X1193517Y164268D01*
Y163918D01*
X1193545Y163847D01*
X1193571Y163820D01*
G02X1193977Y162793I-1096J-1027D01*
G02X1190973I-1502J0D01*
G02X1191379Y163820I1502J0D01*
G01X1191405Y163847D01*
X1191433Y163918D01*
Y164268D01*
X1191405Y164339D01*
X1191379Y164366D01*
G02Y166420I1096J1027D01*
G01X1191405Y166447D01*
X1191433Y166518D01*
Y166868D01*
X1191405Y166939D01*
X1191379Y166966D01*
G02X1190973Y167993I1096J1027D01*
G02X1191343Y168980I1501J0D01*
G01Y168981D01*
X1191344D01*
G03X1191392Y169111I-152J130D01*
G01Y169375D01*
G03X1191344Y169505I-200J0D01*
G01X1191343Y169506D01*
G02X1190973Y170493I1131J987D01*
G37*
G36*
G01X1293335D02*
G02X1296339I1502J0D01*
G02X1295969Y169506I-1501J0D01*
G01Y169505D01*
X1295968D01*
G03X1295920Y169375I152J-130D01*
G01Y169111D01*
G03X1295968Y168981I200J0D01*
G01X1295969Y168980D01*
G02X1296339Y167993I-1131J-987D01*
G02X1295933Y166966I-1502J0D01*
G01X1295907Y166939D01*
X1295879Y166868D01*
Y166518D01*
X1295907Y166447D01*
X1295933Y166420D01*
G02Y164366I-1096J-1027D01*
G01X1295907Y164339D01*
X1295879Y164268D01*
Y163918D01*
X1295907Y163847D01*
X1295933Y163820D01*
G02X1296339Y162793I-1096J-1027D01*
G02X1293335I-1502J0D01*
G02X1293741Y163820I1502J0D01*
G01X1293767Y163847D01*
X1293795Y163918D01*
Y164268D01*
X1293767Y164339D01*
X1293741Y164366D01*
G02Y166420I1096J1027D01*
G01X1293767Y166447D01*
X1293795Y166518D01*
Y166868D01*
X1293767Y166939D01*
X1293741Y166966D01*
G02X1293335Y167993I1096J1027D01*
G02X1293705Y168980I1501J0D01*
G01Y168981D01*
X1293706D01*
G03X1293754Y169111I-152J130D01*
G01Y169375D01*
G03X1293706Y169505I-200J0D01*
G01X1293705Y169506D01*
G02X1293335Y170493I1131J987D01*
G37*
G36*
G01X1443336D02*
G02X1446340I1502J0D01*
G02X1445970Y169506I-1501J0D01*
G01Y169505D01*
X1445969D01*
G03X1445921Y169375I152J-130D01*
G01Y169111D01*
G03X1445969Y168981I200J0D01*
G01X1445970Y168980D01*
G02X1446340Y167993I-1131J-987D01*
G02X1445934Y166966I-1502J0D01*
G01X1445908Y166939D01*
X1445880Y166868D01*
Y166518D01*
X1445908Y166447D01*
X1445934Y166420D01*
G02Y164366I-1096J-1027D01*
G01X1445908Y164339D01*
X1445880Y164268D01*
Y163918D01*
X1445908Y163847D01*
X1445934Y163820D01*
G02X1446340Y162793I-1096J-1027D01*
G02X1443336I-1502J0D01*
G02X1443742Y163820I1502J0D01*
G01X1443768Y163847D01*
X1443796Y163918D01*
Y164268D01*
X1443768Y164339D01*
X1443742Y164366D01*
G02Y166420I1096J1027D01*
G01X1443768Y166447D01*
X1443796Y166518D01*
Y166868D01*
X1443768Y166939D01*
X1443742Y166966D01*
G02X1443336Y167993I1096J1027D01*
G02X1443706Y168980I1501J0D01*
G01Y168981D01*
X1443707D01*
G03X1443755Y169111I-152J130D01*
G01Y169375D01*
G03X1443707Y169505I-200J0D01*
G01X1443706Y169506D01*
G02X1443336Y170493I1131J987D01*
G37*
G36*
G01X1545698D02*
G02X1548702I1502J0D01*
G02X1548332Y169506I-1501J0D01*
G01Y169505D01*
X1548331D01*
G03X1548283Y169375I152J-130D01*
G01Y169111D01*
G03X1548331Y168981I200J0D01*
G01X1548332Y168980D01*
G02X1548702Y167993I-1131J-987D01*
G02X1548296Y166966I-1502J0D01*
G01X1548270Y166939D01*
X1548242Y166868D01*
Y166518D01*
X1548270Y166447D01*
X1548296Y166420D01*
G02Y164366I-1096J-1027D01*
G01X1548270Y164339D01*
X1548242Y164268D01*
Y163918D01*
X1548270Y163847D01*
X1548296Y163820D01*
G02X1548702Y162793I-1096J-1027D01*
G02X1545698I-1502J0D01*
G02X1546104Y163820I1502J0D01*
G01X1546130Y163847D01*
X1546158Y163918D01*
Y164268D01*
X1546130Y164339D01*
X1546104Y164366D01*
G02Y166420I1096J1027D01*
G01X1546130Y166447D01*
X1546158Y166518D01*
Y166868D01*
X1546130Y166939D01*
X1546104Y166966D01*
G02X1545698Y167993I1096J1027D01*
G02X1546068Y168980I1501J0D01*
G01Y168981D01*
X1546069D01*
G03X1546117Y169111I-152J130D01*
G01Y169375D01*
G03X1546069Y169505I-200J0D01*
G01X1546068Y169506D01*
G02X1545698Y170493I1131J987D01*
G37*
G36*
G01X1648060D02*
G02X1651064I1502J0D01*
G02X1650694Y169506I-1501J0D01*
G01Y169505D01*
X1650693D01*
G03X1650645Y169375I152J-130D01*
G01Y169111D01*
G03X1650693Y168981I200J0D01*
G01X1650694Y168980D01*
G02X1651064Y167993I-1131J-987D01*
G02X1650658Y166966I-1502J0D01*
G01X1650632Y166939D01*
X1650604Y166868D01*
Y166518D01*
X1650632Y166447D01*
X1650658Y166420D01*
G02Y164366I-1096J-1027D01*
G01X1650632Y164339D01*
X1650604Y164268D01*
Y163918D01*
X1650632Y163847D01*
X1650658Y163820D01*
G02X1651064Y162793I-1096J-1027D01*
G02X1648060I-1502J0D01*
G02X1648466Y163820I1502J0D01*
G01X1648492Y163847D01*
X1648520Y163918D01*
Y164268D01*
X1648492Y164339D01*
X1648466Y164366D01*
G02Y166420I1096J1027D01*
G01X1648492Y166447D01*
X1648520Y166518D01*
Y166868D01*
X1648492Y166939D01*
X1648466Y166966D01*
G02X1648060Y167993I1096J1027D01*
G02X1648430Y168980I1501J0D01*
G01Y168981D01*
X1648431D01*
G03X1648479Y169111I-152J130D01*
G01Y169375D01*
G03X1648431Y169505I-200J0D01*
G01X1648430Y169506D01*
G02X1648060Y170493I1131J987D01*
G37*
G36*
G01X1750422D02*
G02X1753426I1502J0D01*
G02X1753056Y169506I-1501J0D01*
G01Y169505D01*
X1753055D01*
G03X1753007Y169375I152J-130D01*
G01Y169111D01*
G03X1753055Y168981I200J0D01*
G01X1753056Y168980D01*
G02X1753426Y167993I-1131J-987D01*
G02X1753020Y166966I-1502J0D01*
G01X1752994Y166939D01*
X1752966Y166868D01*
Y166518D01*
X1752994Y166447D01*
X1753020Y166420D01*
G02Y164366I-1096J-1027D01*
G01X1752994Y164339D01*
X1752966Y164268D01*
Y163918D01*
X1752994Y163847D01*
X1753020Y163820D01*
G02X1753426Y162793I-1096J-1027D01*
G02X1750422I-1502J0D01*
G02X1750828Y163820I1502J0D01*
G01X1750854Y163847D01*
X1750882Y163918D01*
Y164268D01*
X1750854Y164339D01*
X1750828Y164366D01*
G02Y166420I1096J1027D01*
G01X1750854Y166447D01*
X1750882Y166518D01*
Y166868D01*
X1750854Y166939D01*
X1750828Y166966D01*
G02X1750422Y167993I1096J1027D01*
G02X1750792Y168980I1501J0D01*
G01Y168981D01*
X1750793D01*
G03X1750841Y169111I-152J130D01*
G01Y169375D01*
G03X1750793Y169505I-200J0D01*
G01X1750792Y169506D01*
G02X1750422Y170493I1131J987D01*
G37*
G36*
G01X946393Y181479D02*
X946394Y181478D01*
G03X946524Y181430I130J152D01*
G01X946788D01*
G03X946918Y181478I0J200D01*
G01X946919Y181479D01*
G02X947906Y181849I987J-1131D01*
G02Y178845I0J-1502D01*
G02X946919Y179215I0J1501D01*
G01X946918D01*
Y179216D01*
G03X946788Y179264I-130J-152D01*
G01X946524D01*
G03X946394Y179216I0J-200D01*
G01X946393Y179215D01*
G02X944419I-987J1131D01*
G01X944418D01*
Y179216D01*
G03X944288Y179264I-130J-152D01*
G01X944024D01*
G03X943894Y179216I0J-200D01*
G01X943893Y179215D01*
G02X941919I-987J1131D01*
G01X941918D01*
Y179216D01*
G03X941788Y179264I-130J-152D01*
G01X941524D01*
G03X941394Y179216I0J-200D01*
G01X941393Y179215D01*
G02X940406Y178845I-987J1131D01*
G02Y181849I0J1502D01*
G02X941393Y181479I0J-1501D01*
G01X941394D01*
Y181478D01*
G03X941524Y181430I130J152D01*
G01X941788D01*
G03X941918Y181478I0J200D01*
G01X941919Y181479D01*
G02X943893I987J-1131D01*
G01X943894D01*
Y181478D01*
G03X944024Y181430I130J152D01*
G01X944288D01*
G03X944418Y181478I0J200D01*
G01X944419Y181479D01*
G02X946393I987J-1131D01*
G37*
G36*
G01X200499Y186629D02*
G02X203503I1502J0D01*
G02X202500Y185212I-1502J0D01*
G01X202499D01*
G03X202377Y185090I67J-189D01*
G01X202274Y184796D01*
G03X202291Y184625I188J-68D01*
G01X202292Y184624D01*
G02X202517Y183834I-1277J-791D01*
G02X199513I-1502J0D01*
G02X200516Y185251I1502J0D01*
G01X200517D01*
G03X200639Y185373I-67J189D01*
G01X200742Y185667D01*
G03X200725Y185838I-188J68D01*
G01X200724Y185839D01*
G02X200499Y186629I1277J791D01*
G37*
G36*
G01X302861D02*
G02X305865I1502J0D01*
G02X304862Y185212I-1502J0D01*
G01X304861D01*
G03X304739Y185090I67J-189D01*
G01X304636Y184796D01*
G03X304653Y184625I188J-68D01*
G01X304654Y184624D01*
G02X304879Y183834I-1277J-791D01*
G02X301875I-1502J0D01*
G02X302878Y185251I1502J0D01*
G01X302879D01*
G03X303001Y185373I-67J189D01*
G01X303104Y185667D01*
G03X303087Y185838I-188J68D01*
G01X303086Y185839D01*
G02X302861Y186629I1277J791D01*
G37*
G36*
G01X405223D02*
G02X408227I1502J0D01*
G02X407224Y185212I-1502J0D01*
G01X407223D01*
G03X407101Y185090I67J-189D01*
G01X406998Y184796D01*
G03X407015Y184625I188J-68D01*
G01X407016Y184624D01*
G02X407241Y183834I-1277J-791D01*
G02X404237I-1502J0D01*
G02X405240Y185251I1502J0D01*
G01X405241D01*
G03X405363Y185373I-67J189D01*
G01X405466Y185667D01*
G03X405449Y185838I-188J68D01*
G01X405448Y185839D01*
G02X405223Y186629I1277J791D01*
G37*
G36*
G01X555224D02*
G02X558228I1502J0D01*
G02X557225Y185212I-1502J0D01*
G01X557224D01*
G03X557102Y185090I67J-189D01*
G01X556999Y184796D01*
G03X557016Y184625I188J-68D01*
G01X557017Y184624D01*
G02X557242Y183834I-1277J-791D01*
G02X554238I-1502J0D01*
G02X555241Y185251I1502J0D01*
G01X555242D01*
G03X555364Y185373I-67J189D01*
G01X555467Y185667D01*
G03X555450Y185838I-188J68D01*
G01X555449Y185839D01*
G02X555224Y186629I1277J791D01*
G37*
G36*
G01X657586D02*
G02X660590I1502J0D01*
G02X659587Y185212I-1502J0D01*
G01X659586D01*
G03X659464Y185090I67J-189D01*
G01X659361Y184796D01*
G03X659378Y184625I188J-68D01*
G01X659379Y184624D01*
G02X659604Y183834I-1277J-791D01*
G02X656600I-1502J0D01*
G02X657603Y185251I1502J0D01*
G01X657604D01*
G03X657726Y185373I-67J189D01*
G01X657829Y185667D01*
G03X657812Y185838I-188J68D01*
G01X657811Y185839D01*
G02X657586Y186629I1277J791D01*
G37*
G36*
G01X759948D02*
G02X762952I1502J0D01*
G02X761949Y185212I-1502J0D01*
G01X761948D01*
G03X761826Y185090I67J-189D01*
G01X761723Y184796D01*
G03X761740Y184625I188J-68D01*
G01X761741Y184624D01*
G02X761966Y183834I-1277J-791D01*
G02X758962I-1502J0D01*
G02X759965Y185251I1502J0D01*
G01X759966D01*
G03X760088Y185373I-67J189D01*
G01X760191Y185667D01*
G03X760174Y185838I-188J68D01*
G01X760173Y185839D01*
G02X759948Y186629I1277J791D01*
G37*
G36*
G01X862310D02*
G02X865314I1502J0D01*
G02X864311Y185212I-1502J0D01*
G01X864310D01*
G03X864188Y185090I67J-189D01*
G01X864085Y184796D01*
G03X864102Y184625I188J-68D01*
G01X864103Y184624D01*
G02X864328Y183834I-1277J-791D01*
G02X861324I-1502J0D01*
G02X862327Y185251I1502J0D01*
G01X862328D01*
G03X862450Y185373I-67J189D01*
G01X862553Y185667D01*
G03X862536Y185838I-188J68D01*
G01X862535Y185839D01*
G02X862310Y186629I1277J791D01*
G37*
G36*
G01X1110250Y175214D02*
Y188034D01*
G02X1110925Y189664I2306J0D01*
G01X1113077Y191816D01*
G02X1114708Y192492I1632J-1631D01*
G02X1117014Y190185I-1J-2307D01*
G01Y190184D01*
G02X1116339Y188554I-2306J0D01*
G01X1116244Y188459D01*
G03Y188177I142J-141D01*
G01X1116245Y188176D01*
G03X1116360Y188119I142J141D01*
G01X1116361D01*
G02X1117676Y186629I-187J-1490D01*
G02X1116673Y185212I-1502J0D01*
G01X1116672D01*
G03X1116550Y185090I67J-189D01*
G01X1116447Y184796D01*
G03X1116464Y184625I188J-68D01*
G01X1116465Y184624D01*
G02X1116690Y183834I-1277J-791D01*
G02X1115247Y182333I-1502J0D01*
G03X1115110Y182272I7J-200D01*
G01X1114918Y182072D01*
G03X1114862Y181933I144J-139D01*
G01Y180462D01*
G03X1114922Y180319I200J0D01*
G01X1115155Y180091D01*
X1115230Y180061D01*
X1115270Y180062D01*
X1115298D01*
G02Y177058I0J-1502D01*
G01X1115270D01*
X1115230Y177059D01*
X1115155Y177029D01*
X1114922Y176801D01*
G03X1114862Y176658I140J-143D01*
G01Y174565D01*
G03X1114924Y174420I200J0D01*
G01X1115135Y174220D01*
G03X1115282Y174165I138J145D01*
G01X1115283D01*
G02X1115360Y174167I77J-1500D01*
G01X1115361D01*
G02Y171163I0J-1502D01*
G02X1114124Y171813I0J1502D01*
G01X1114099Y171850D01*
X1114022Y171895D01*
X1113671Y171927D01*
G03X1113512Y171870I-18J-199D01*
G01X1111534Y169892D01*
G02X1109903Y169216I-1632J1631D01*
G02X1107596Y171523I0J2307D01*
G02X1108272Y173154I2307J-1D01*
G01X1110191Y175072D01*
G03X1110250Y175214I-141J142D01*
G37*
G36*
G01X1212612D02*
Y188034D01*
G02X1213287Y189664I2306J0D01*
G01X1215439Y191816D01*
G02X1217070Y192492I1632J-1631D01*
G02X1219376Y190185I-1J-2307D01*
G01Y190184D01*
G02X1218701Y188554I-2306J0D01*
G01X1218606Y188459D01*
G03Y188177I142J-141D01*
G01X1218607Y188176D01*
G03X1218722Y188119I142J141D01*
G01X1218723D01*
G02X1220038Y186629I-187J-1490D01*
G02X1219035Y185212I-1502J0D01*
G01X1219034D01*
G03X1218912Y185090I67J-189D01*
G01X1218809Y184796D01*
G03X1218826Y184625I188J-68D01*
G01X1218827Y184624D01*
G02X1219052Y183834I-1277J-791D01*
G02X1217609Y182333I-1502J0D01*
G03X1217472Y182272I7J-200D01*
G01X1217280Y182072D01*
G03X1217224Y181933I144J-139D01*
G01Y180462D01*
G03X1217284Y180319I200J0D01*
G01X1217517Y180091D01*
X1217592Y180061D01*
X1217632Y180062D01*
X1217660D01*
G02Y177058I0J-1502D01*
G01X1217632D01*
X1217592Y177059D01*
X1217517Y177029D01*
X1217284Y176801D01*
G03X1217224Y176658I140J-143D01*
G01Y174565D01*
G03X1217286Y174420I200J0D01*
G01X1217497Y174220D01*
G03X1217644Y174165I138J145D01*
G01X1217645D01*
G02X1217722Y174167I77J-1500D01*
G01X1217723D01*
G02Y171163I0J-1502D01*
G02X1216486Y171813I0J1502D01*
G01X1216461Y171850D01*
X1216384Y171895D01*
X1216033Y171927D01*
G03X1215874Y171870I-18J-199D01*
G01X1213896Y169892D01*
G02X1212265Y169216I-1632J1631D01*
G02X1209958Y171523I0J2307D01*
G02X1210634Y173154I2307J-1D01*
G01X1212553Y175072D01*
G03X1212612Y175214I-141J142D01*
G37*
G36*
G01X1314974D02*
Y188034D01*
G02X1315649Y189664I2306J0D01*
G01X1317801Y191816D01*
G02X1319432Y192492I1632J-1631D01*
G02X1321738Y190185I-1J-2307D01*
G01Y190184D01*
G02X1321063Y188554I-2306J0D01*
G01X1320968Y188459D01*
G03Y188177I142J-141D01*
G01X1320969Y188176D01*
G03X1321084Y188119I142J141D01*
G01X1321085D01*
G02X1322400Y186629I-187J-1490D01*
G02X1321397Y185212I-1502J0D01*
G01X1321396D01*
G03X1321274Y185090I67J-189D01*
G01X1321171Y184796D01*
G03X1321188Y184625I188J-68D01*
G01X1321189Y184624D01*
G02X1321414Y183834I-1277J-791D01*
G02X1319971Y182333I-1502J0D01*
G03X1319834Y182272I7J-200D01*
G01X1319642Y182072D01*
G03X1319586Y181933I144J-139D01*
G01Y180462D01*
G03X1319646Y180319I200J0D01*
G01X1319879Y180091D01*
X1319954Y180061D01*
X1319994Y180062D01*
X1320022D01*
G02Y177058I0J-1502D01*
G01X1319994D01*
X1319954Y177059D01*
X1319879Y177029D01*
X1319646Y176801D01*
G03X1319586Y176658I140J-143D01*
G01Y174565D01*
G03X1319648Y174420I200J0D01*
G01X1319859Y174220D01*
G03X1320006Y174165I138J145D01*
G01X1320007D01*
G02X1320084Y174167I77J-1500D01*
G01X1320085D01*
G02Y171163I0J-1502D01*
G02X1318848Y171813I0J1502D01*
G01X1318823Y171850D01*
X1318746Y171895D01*
X1318395Y171927D01*
G03X1318236Y171870I-18J-199D01*
G01X1316258Y169892D01*
G02X1314627Y169216I-1632J1631D01*
G02X1312320Y171523I0J2307D01*
G02X1312996Y173154I2307J-1D01*
G01X1314915Y175072D01*
G03X1314974Y175214I-141J142D01*
G37*
G36*
G01X942260Y190475D02*
G02Y193479I0J1502D01*
G02X943247Y193109I0J-1501D01*
G01X943248D01*
Y193108D01*
G03X943378Y193060I130J152D01*
G01X943642D01*
G03X943772Y193108I0J200D01*
G01X943773Y193109D01*
G02X944760Y193479I987J-1131D01*
G02Y190475I0J-1502D01*
G02X943773Y190845I0J1501D01*
G01X943772D01*
Y190846D01*
G03X943642Y190894I-130J-152D01*
G01X943378D01*
G03X943248Y190846I0J-200D01*
G01X943247Y190845D01*
G02X942260Y190475I-987J1131D01*
G37*
G36*
G01X236278Y196308D02*
X236279Y196307D01*
G03X236409Y196259I130J152D01*
G01X236673D01*
G03X236803Y196307I0J200D01*
G01X236804Y196308D01*
G02X237791Y196678I987J-1131D01*
G02Y193674I0J-1502D01*
G02X236804Y194044I0J1501D01*
G01X236803D01*
Y194045D01*
G03X236673Y194093I-130J-152D01*
G01X236409D01*
G03X236279Y194045I0J-200D01*
G01X236278Y194044D01*
G02X234304I-987J1131D01*
G01X234303D01*
Y194045D01*
G03X234173Y194093I-130J-152D01*
G01X233909D01*
G03X233779Y194045I0J-200D01*
G01X233778Y194044D01*
G02X231804I-987J1131D01*
G01X231803D01*
Y194045D01*
G03X231673Y194093I-130J-152D01*
G01X231409D01*
G03X231279Y194045I0J-200D01*
G01X231278Y194044D01*
G02X230291Y193674I-987J1131D01*
G02Y196678I0J1502D01*
G02X231278Y196308I0J-1501D01*
G01X231279D01*
Y196307D01*
G03X231409Y196259I130J152D01*
G01X231673D01*
G03X231803Y196307I0J200D01*
G01X231804Y196308D01*
G02X233778I987J-1131D01*
G01X233779D01*
Y196307D01*
G03X233909Y196259I130J152D01*
G01X234173D01*
G03X234303Y196307I0J200D01*
G01X234304Y196308D01*
G02X236278I987J-1131D01*
G37*
G36*
G01X338640D02*
X338641Y196307D01*
G03X338771Y196259I130J152D01*
G01X339035D01*
G03X339165Y196307I0J200D01*
G01X339166Y196308D01*
G02X340153Y196678I987J-1131D01*
G02Y193674I0J-1502D01*
G02X339166Y194044I0J1501D01*
G01X339165D01*
Y194045D01*
G03X339035Y194093I-130J-152D01*
G01X338771D01*
G03X338641Y194045I0J-200D01*
G01X338640Y194044D01*
G02X336666I-987J1131D01*
G01X336665D01*
Y194045D01*
G03X336535Y194093I-130J-152D01*
G01X336271D01*
G03X336141Y194045I0J-200D01*
G01X336140Y194044D01*
G02X334166I-987J1131D01*
G01X334165D01*
Y194045D01*
G03X334035Y194093I-130J-152D01*
G01X333771D01*
G03X333641Y194045I0J-200D01*
G01X333640Y194044D01*
G02X332653Y193674I-987J1131D01*
G02Y196678I0J1502D01*
G02X333640Y196308I0J-1501D01*
G01X333641D01*
Y196307D01*
G03X333771Y196259I130J152D01*
G01X334035D01*
G03X334165Y196307I0J200D01*
G01X334166Y196308D01*
G02X336140I987J-1131D01*
G01X336141D01*
Y196307D01*
G03X336271Y196259I130J152D01*
G01X336535D01*
G03X336665Y196307I0J200D01*
G01X336666Y196308D01*
G02X338640I987J-1131D01*
G37*
G36*
G01X488641D02*
X488642Y196307D01*
G03X488772Y196259I130J152D01*
G01X489036D01*
G03X489166Y196307I0J200D01*
G01X489167Y196308D01*
G02X490154Y196678I987J-1131D01*
G02Y193674I0J-1502D01*
G02X489167Y194044I0J1501D01*
G01X489166D01*
Y194045D01*
G03X489036Y194093I-130J-152D01*
G01X488772D01*
G03X488642Y194045I0J-200D01*
G01X488641Y194044D01*
G02X486667I-987J1131D01*
G01X486666D01*
Y194045D01*
G03X486536Y194093I-130J-152D01*
G01X486272D01*
G03X486142Y194045I0J-200D01*
G01X486141Y194044D01*
G02X484167I-987J1131D01*
G01X484166D01*
Y194045D01*
G03X484036Y194093I-130J-152D01*
G01X483772D01*
G03X483642Y194045I0J-200D01*
G01X483641Y194044D01*
G02X482654Y193674I-987J1131D01*
G02Y196678I0J1502D01*
G02X483641Y196308I0J-1501D01*
G01X483642D01*
Y196307D01*
G03X483772Y196259I130J152D01*
G01X484036D01*
G03X484166Y196307I0J200D01*
G01X484167Y196308D01*
G02X486141I987J-1131D01*
G01X486142D01*
Y196307D01*
G03X486272Y196259I130J152D01*
G01X486536D01*
G03X486666Y196307I0J200D01*
G01X486667Y196308D01*
G02X488641I987J-1131D01*
G37*
G36*
G01X591003D02*
X591004Y196307D01*
G03X591134Y196259I130J152D01*
G01X591398D01*
G03X591528Y196307I0J200D01*
G01X591529Y196308D01*
G02X592516Y196678I987J-1131D01*
G02Y193674I0J-1502D01*
G02X591529Y194044I0J1501D01*
G01X591528D01*
Y194045D01*
G03X591398Y194093I-130J-152D01*
G01X591134D01*
G03X591004Y194045I0J-200D01*
G01X591003Y194044D01*
G02X589029I-987J1131D01*
G01X589028D01*
Y194045D01*
G03X588898Y194093I-130J-152D01*
G01X588634D01*
G03X588504Y194045I0J-200D01*
G01X588503Y194044D01*
G02X586529I-987J1131D01*
G01X586528D01*
Y194045D01*
G03X586398Y194093I-130J-152D01*
G01X586134D01*
G03X586004Y194045I0J-200D01*
G01X586003Y194044D01*
G02X585016Y193674I-987J1131D01*
G02Y196678I0J1502D01*
G02X586003Y196308I0J-1501D01*
G01X586004D01*
Y196307D01*
G03X586134Y196259I130J152D01*
G01X586398D01*
G03X586528Y196307I0J200D01*
G01X586529Y196308D01*
G02X588503I987J-1131D01*
G01X588504D01*
Y196307D01*
G03X588634Y196259I130J152D01*
G01X588898D01*
G03X589028Y196307I0J200D01*
G01X589029Y196308D01*
G02X591003I987J-1131D01*
G37*
G36*
G01X693365D02*
X693366Y196307D01*
G03X693496Y196259I130J152D01*
G01X693760D01*
G03X693890Y196307I0J200D01*
G01X693891Y196308D01*
G02X694878Y196678I987J-1131D01*
G02Y193674I0J-1502D01*
G02X693891Y194044I0J1501D01*
G01X693890D01*
Y194045D01*
G03X693760Y194093I-130J-152D01*
G01X693496D01*
G03X693366Y194045I0J-200D01*
G01X693365Y194044D01*
G02X691391I-987J1131D01*
G01X691390D01*
Y194045D01*
G03X691260Y194093I-130J-152D01*
G01X690996D01*
G03X690866Y194045I0J-200D01*
G01X690865Y194044D01*
G02X688891I-987J1131D01*
G01X688890D01*
Y194045D01*
G03X688760Y194093I-130J-152D01*
G01X688496D01*
G03X688366Y194045I0J-200D01*
G01X688365Y194044D01*
G02X687378Y193674I-987J1131D01*
G02Y196678I0J1502D01*
G02X688365Y196308I0J-1501D01*
G01X688366D01*
Y196307D01*
G03X688496Y196259I130J152D01*
G01X688760D01*
G03X688890Y196307I0J200D01*
G01X688891Y196308D01*
G02X690865I987J-1131D01*
G01X690866D01*
Y196307D01*
G03X690996Y196259I130J152D01*
G01X691260D01*
G03X691390Y196307I0J200D01*
G01X691391Y196308D01*
G02X693365I987J-1131D01*
G37*
G36*
G01X795727D02*
X795728Y196307D01*
G03X795858Y196259I130J152D01*
G01X796122D01*
G03X796252Y196307I0J200D01*
G01X796253Y196308D01*
G02X797240Y196678I987J-1131D01*
G02Y193674I0J-1502D01*
G02X796253Y194044I0J1501D01*
G01X796252D01*
Y194045D01*
G03X796122Y194093I-130J-152D01*
G01X795858D01*
G03X795728Y194045I0J-200D01*
G01X795727Y194044D01*
G02X793753I-987J1131D01*
G01X793752D01*
Y194045D01*
G03X793622Y194093I-130J-152D01*
G01X793358D01*
G03X793228Y194045I0J-200D01*
G01X793227Y194044D01*
G02X791253I-987J1131D01*
G01X791252D01*
Y194045D01*
G03X791122Y194093I-130J-152D01*
G01X790858D01*
G03X790728Y194045I0J-200D01*
G01X790727Y194044D01*
G02X789740Y193674I-987J1131D01*
G02Y196678I0J1502D01*
G02X790727Y196308I0J-1501D01*
G01X790728D01*
Y196307D01*
G03X790858Y196259I130J152D01*
G01X791122D01*
G03X791252Y196307I0J200D01*
G01X791253Y196308D01*
G02X793227I987J-1131D01*
G01X793228D01*
Y196307D01*
G03X793358Y196259I130J152D01*
G01X793622D01*
G03X793752Y196307I0J200D01*
G01X793753Y196308D01*
G02X795727I987J-1131D01*
G37*
G36*
G01X1048089D02*
X1048090Y196307D01*
G03X1048220Y196259I130J152D01*
G01X1048484D01*
G03X1048614Y196307I0J200D01*
G01X1048615Y196308D01*
G02X1049602Y196678I987J-1131D01*
G02Y193674I0J-1502D01*
G02X1048615Y194044I0J1501D01*
G01X1048614D01*
Y194045D01*
G03X1048484Y194093I-130J-152D01*
G01X1048220D01*
G03X1048090Y194045I0J-200D01*
G01X1048089Y194044D01*
G02X1046115I-987J1131D01*
G01X1046114D01*
Y194045D01*
G03X1045984Y194093I-130J-152D01*
G01X1045720D01*
G03X1045590Y194045I0J-200D01*
G01X1045589Y194044D01*
G02X1043615I-987J1131D01*
G01X1043614D01*
Y194045D01*
G03X1043484Y194093I-130J-152D01*
G01X1043220D01*
G03X1043090Y194045I0J-200D01*
G01X1043089Y194044D01*
G02X1042102Y193674I-987J1131D01*
G02Y196678I0J1502D01*
G02X1043089Y196308I0J-1501D01*
G01X1043090D01*
Y196307D01*
G03X1043220Y196259I130J152D01*
G01X1043484D01*
G03X1043614Y196307I0J200D01*
G01X1043615Y196308D01*
G02X1045589I987J-1131D01*
G01X1045590D01*
Y196307D01*
G03X1045720Y196259I130J152D01*
G01X1045984D01*
G03X1046114Y196307I0J200D01*
G01X1046115Y196308D01*
G02X1048089I987J-1131D01*
G37*
G36*
G01X1150451D02*
X1150452Y196307D01*
G03X1150582Y196259I130J152D01*
G01X1150846D01*
G03X1150976Y196307I0J200D01*
G01X1150977Y196308D01*
G02X1151964Y196678I987J-1131D01*
G02Y193674I0J-1502D01*
G02X1150977Y194044I0J1501D01*
G01X1150976D01*
Y194045D01*
G03X1150846Y194093I-130J-152D01*
G01X1150582D01*
G03X1150452Y194045I0J-200D01*
G01X1150451Y194044D01*
G02X1148477I-987J1131D01*
G01X1148476D01*
Y194045D01*
G03X1148346Y194093I-130J-152D01*
G01X1148082D01*
G03X1147952Y194045I0J-200D01*
G01X1147951Y194044D01*
G02X1145977I-987J1131D01*
G01X1145976D01*
Y194045D01*
G03X1145846Y194093I-130J-152D01*
G01X1145582D01*
G03X1145452Y194045I0J-200D01*
G01X1145451Y194044D01*
G02X1144464Y193674I-987J1131D01*
G02Y196678I0J1502D01*
G02X1145451Y196308I0J-1501D01*
G01X1145452D01*
Y196307D01*
G03X1145582Y196259I130J152D01*
G01X1145846D01*
G03X1145976Y196307I0J200D01*
G01X1145977Y196308D01*
G02X1147951I987J-1131D01*
G01X1147952D01*
Y196307D01*
G03X1148082Y196259I130J152D01*
G01X1148346D01*
G03X1148476Y196307I0J200D01*
G01X1148477Y196308D01*
G02X1150451I987J-1131D01*
G37*
G36*
G01X1252813D02*
X1252814Y196307D01*
G03X1252944Y196259I130J152D01*
G01X1253208D01*
G03X1253338Y196307I0J200D01*
G01X1253339Y196308D01*
G02X1254326Y196678I987J-1131D01*
G02Y193674I0J-1502D01*
G02X1253339Y194044I0J1501D01*
G01X1253338D01*
Y194045D01*
G03X1253208Y194093I-130J-152D01*
G01X1252944D01*
G03X1252814Y194045I0J-200D01*
G01X1252813Y194044D01*
G02X1250839I-987J1131D01*
G01X1250838D01*
Y194045D01*
G03X1250708Y194093I-130J-152D01*
G01X1250444D01*
G03X1250314Y194045I0J-200D01*
G01X1250313Y194044D01*
G02X1248339I-987J1131D01*
G01X1248338D01*
Y194045D01*
G03X1248208Y194093I-130J-152D01*
G01X1247944D01*
G03X1247814Y194045I0J-200D01*
G01X1247813Y194044D01*
G02X1246826Y193674I-987J1131D01*
G02Y196678I0J1502D01*
G02X1247813Y196308I0J-1501D01*
G01X1247814D01*
Y196307D01*
G03X1247944Y196259I130J152D01*
G01X1248208D01*
G03X1248338Y196307I0J200D01*
G01X1248339Y196308D01*
G02X1250313I987J-1131D01*
G01X1250314D01*
Y196307D01*
G03X1250444Y196259I130J152D01*
G01X1250708D01*
G03X1250838Y196307I0J200D01*
G01X1250839Y196308D01*
G02X1252813I987J-1131D01*
G37*
G36*
G01X1402814D02*
X1402815Y196307D01*
G03X1402945Y196259I130J152D01*
G01X1403209D01*
G03X1403339Y196307I0J200D01*
G01X1403340Y196308D01*
G02X1404327Y196678I987J-1131D01*
G02Y193674I0J-1502D01*
G02X1403340Y194044I0J1501D01*
G01X1403339D01*
Y194045D01*
G03X1403209Y194093I-130J-152D01*
G01X1402945D01*
G03X1402815Y194045I0J-200D01*
G01X1402814Y194044D01*
G02X1400840I-987J1131D01*
G01X1400839D01*
Y194045D01*
G03X1400709Y194093I-130J-152D01*
G01X1400445D01*
G03X1400315Y194045I0J-200D01*
G01X1400314Y194044D01*
G02X1398340I-987J1131D01*
G01X1398339D01*
Y194045D01*
G03X1398209Y194093I-130J-152D01*
G01X1397945D01*
G03X1397815Y194045I0J-200D01*
G01X1397814Y194044D01*
G02X1396827Y193674I-987J1131D01*
G02Y196678I0J1502D01*
G02X1397814Y196308I0J-1501D01*
G01X1397815D01*
Y196307D01*
G03X1397945Y196259I130J152D01*
G01X1398209D01*
G03X1398339Y196307I0J200D01*
G01X1398340Y196308D01*
G02X1400314I987J-1131D01*
G01X1400315D01*
Y196307D01*
G03X1400445Y196259I130J152D01*
G01X1400709D01*
G03X1400839Y196307I0J200D01*
G01X1400840Y196308D01*
G02X1402814I987J-1131D01*
G37*
G36*
G01X1505176D02*
X1505177Y196307D01*
G03X1505307Y196259I130J152D01*
G01X1505571D01*
G03X1505701Y196307I0J200D01*
G01X1505702Y196308D01*
G02X1506689Y196678I987J-1131D01*
G02Y193674I0J-1502D01*
G02X1505702Y194044I0J1501D01*
G01X1505701D01*
Y194045D01*
G03X1505571Y194093I-130J-152D01*
G01X1505307D01*
G03X1505177Y194045I0J-200D01*
G01X1505176Y194044D01*
G02X1503202I-987J1131D01*
G01X1503201D01*
Y194045D01*
G03X1503071Y194093I-130J-152D01*
G01X1502807D01*
G03X1502677Y194045I0J-200D01*
G01X1502676Y194044D01*
G02X1500702I-987J1131D01*
G01X1500701D01*
Y194045D01*
G03X1500571Y194093I-130J-152D01*
G01X1500307D01*
G03X1500177Y194045I0J-200D01*
G01X1500176Y194044D01*
G02X1499189Y193674I-987J1131D01*
G02Y196678I0J1502D01*
G02X1500176Y196308I0J-1501D01*
G01X1500177D01*
Y196307D01*
G03X1500307Y196259I130J152D01*
G01X1500571D01*
G03X1500701Y196307I0J200D01*
G01X1500702Y196308D01*
G02X1502676I987J-1131D01*
G01X1502677D01*
Y196307D01*
G03X1502807Y196259I130J152D01*
G01X1503071D01*
G03X1503201Y196307I0J200D01*
G01X1503202Y196308D01*
G02X1505176I987J-1131D01*
G37*
G36*
G01X1607538D02*
X1607539Y196307D01*
G03X1607669Y196259I130J152D01*
G01X1607933D01*
G03X1608063Y196307I0J200D01*
G01X1608064Y196308D01*
G02X1609051Y196678I987J-1131D01*
G02Y193674I0J-1502D01*
G02X1608064Y194044I0J1501D01*
G01X1608063D01*
Y194045D01*
G03X1607933Y194093I-130J-152D01*
G01X1607669D01*
G03X1607539Y194045I0J-200D01*
G01X1607538Y194044D01*
G02X1605564I-987J1131D01*
G01X1605563D01*
Y194045D01*
G03X1605433Y194093I-130J-152D01*
G01X1605169D01*
G03X1605039Y194045I0J-200D01*
G01X1605038Y194044D01*
G02X1603064I-987J1131D01*
G01X1603063D01*
Y194045D01*
G03X1602933Y194093I-130J-152D01*
G01X1602669D01*
G03X1602539Y194045I0J-200D01*
G01X1602538Y194044D01*
G02X1601551Y193674I-987J1131D01*
G02Y196678I0J1502D01*
G02X1602538Y196308I0J-1501D01*
G01X1602539D01*
Y196307D01*
G03X1602669Y196259I130J152D01*
G01X1602933D01*
G03X1603063Y196307I0J200D01*
G01X1603064Y196308D01*
G02X1605038I987J-1131D01*
G01X1605039D01*
Y196307D01*
G03X1605169Y196259I130J152D01*
G01X1605433D01*
G03X1605563Y196307I0J200D01*
G01X1605564Y196308D01*
G02X1607538I987J-1131D01*
G37*
G36*
G01X1709900D02*
X1709901Y196307D01*
G03X1710031Y196259I130J152D01*
G01X1710295D01*
G03X1710425Y196307I0J200D01*
G01X1710426Y196308D01*
G02X1711413Y196678I987J-1131D01*
G02Y193674I0J-1502D01*
G02X1710426Y194044I0J1501D01*
G01X1710425D01*
Y194045D01*
G03X1710295Y194093I-130J-152D01*
G01X1710031D01*
G03X1709901Y194045I0J-200D01*
G01X1709900Y194044D01*
G02X1707926I-987J1131D01*
G01X1707925D01*
Y194045D01*
G03X1707795Y194093I-130J-152D01*
G01X1707531D01*
G03X1707401Y194045I0J-200D01*
G01X1707400Y194044D01*
G02X1705426I-987J1131D01*
G01X1705425D01*
Y194045D01*
G03X1705295Y194093I-130J-152D01*
G01X1705031D01*
G03X1704901Y194045I0J-200D01*
G01X1704900Y194044D01*
G02X1703913Y193674I-987J1131D01*
G02Y196678I0J1502D01*
G02X1704900Y196308I0J-1501D01*
G01X1704901D01*
Y196307D01*
G03X1705031Y196259I130J152D01*
G01X1705295D01*
G03X1705425Y196307I0J200D01*
G01X1705426Y196308D01*
G02X1707400I987J-1131D01*
G01X1707401D01*
Y196307D01*
G03X1707531Y196259I130J152D01*
G01X1707795D01*
G03X1707925Y196307I0J200D01*
G01X1707926Y196308D01*
G02X1709900I987J-1131D01*
G37*
G36*
G01X940487Y194178D02*
G02Y197182I0J1502D01*
G02X941474Y196812I0J-1501D01*
G01X941475D01*
Y196811D01*
G03X941605Y196763I130J152D01*
G01X941869D01*
G03X941999Y196811I0J200D01*
G01X942000Y196812D01*
G02X942987Y197182I987J-1131D01*
G02Y194178I0J-1502D01*
G02X942000Y194548I0J1501D01*
G01X941999D01*
Y194549D01*
G03X941869Y194597I-130J-152D01*
G01X941605D01*
G03X941475Y194549I0J-200D01*
G01X941474Y194548D01*
G02X940487Y194178I-987J1131D01*
G37*
G36*
G01X926645Y202304D02*
X926351D01*
G03X926204Y202239I1J-200D01*
G02X925098Y201754I-1106J1019D01*
G02Y204758I0J1502D01*
G02X926204Y204273I0J-1504D01*
G03X926351Y204208I148J135D01*
G01X926645D01*
G03X926792Y204273I-1J200D01*
G02X927898Y204758I1106J-1019D01*
G02Y201754I0J-1502D01*
G02X926792Y202239I0J1504D01*
G03X926645Y202304I-148J-135D01*
G37*
G36*
G01X192702Y207899D02*
X192703Y207898D01*
G03X192833Y207850I130J152D01*
G01X193097D01*
G03X193227Y207898I0J200D01*
G01X193228Y207899D01*
G02X194215Y208269I987J-1131D01*
G02Y205265I0J-1502D01*
G02X193228Y205635I0J1501D01*
G01X193227D01*
Y205636D01*
G03X193097Y205684I-130J-152D01*
G01X192833D01*
G03X192703Y205636I0J-200D01*
G01X192702Y205635D01*
G02X190728I-987J1131D01*
G01X190727D01*
Y205636D01*
G03X190597Y205684I-130J-152D01*
G01X190333D01*
G03X190203Y205636I0J-200D01*
G01X190202Y205635D01*
G02X189215Y205265I-987J1131D01*
G02Y208269I0J1502D01*
G02X190202Y207899I0J-1501D01*
G01X190203D01*
Y207898D01*
G03X190333Y207850I130J152D01*
G01X190597D01*
G03X190727Y207898I0J200D01*
G01X190728Y207899D01*
G02X192702I987J-1131D01*
G37*
G36*
G01X295064D02*
X295065Y207898D01*
G03X295195Y207850I130J152D01*
G01X295459D01*
G03X295589Y207898I0J200D01*
G01X295590Y207899D01*
G02X296577Y208269I987J-1131D01*
G02Y205265I0J-1502D01*
G02X295590Y205635I0J1501D01*
G01X295589D01*
Y205636D01*
G03X295459Y205684I-130J-152D01*
G01X295195D01*
G03X295065Y205636I0J-200D01*
G01X295064Y205635D01*
G02X293090I-987J1131D01*
G01X293089D01*
Y205636D01*
G03X292959Y205684I-130J-152D01*
G01X292695D01*
G03X292565Y205636I0J-200D01*
G01X292564Y205635D01*
G02X291577Y205265I-987J1131D01*
G02Y208269I0J1502D01*
G02X292564Y207899I0J-1501D01*
G01X292565D01*
Y207898D01*
G03X292695Y207850I130J152D01*
G01X292959D01*
G03X293089Y207898I0J200D01*
G01X293090Y207899D01*
G02X295064I987J-1131D01*
G37*
G36*
G01X397426D02*
X397427Y207898D01*
G03X397557Y207850I130J152D01*
G01X397821D01*
G03X397951Y207898I0J200D01*
G01X397952Y207899D01*
G02X398939Y208269I987J-1131D01*
G02Y205265I0J-1502D01*
G02X397952Y205635I0J1501D01*
G01X397951D01*
Y205636D01*
G03X397821Y205684I-130J-152D01*
G01X397557D01*
G03X397427Y205636I0J-200D01*
G01X397426Y205635D01*
G02X395452I-987J1131D01*
G01X395451D01*
Y205636D01*
G03X395321Y205684I-130J-152D01*
G01X395057D01*
G03X394927Y205636I0J-200D01*
G01X394926Y205635D01*
G02X393939Y205265I-987J1131D01*
G02Y208269I0J1502D01*
G02X394926Y207899I0J-1501D01*
G01X394927D01*
Y207898D01*
G03X395057Y207850I130J152D01*
G01X395321D01*
G03X395451Y207898I0J200D01*
G01X395452Y207899D01*
G02X397426I987J-1131D01*
G37*
G36*
G01X547427D02*
X547428Y207898D01*
G03X547558Y207850I130J152D01*
G01X547822D01*
G03X547952Y207898I0J200D01*
G01X547953Y207899D01*
G02X548940Y208269I987J-1131D01*
G02Y205265I0J-1502D01*
G02X547953Y205635I0J1501D01*
G01X547952D01*
Y205636D01*
G03X547822Y205684I-130J-152D01*
G01X547558D01*
G03X547428Y205636I0J-200D01*
G01X547427Y205635D01*
G02X545453I-987J1131D01*
G01X545452D01*
Y205636D01*
G03X545322Y205684I-130J-152D01*
G01X545058D01*
G03X544928Y205636I0J-200D01*
G01X544927Y205635D01*
G02X543940Y205265I-987J1131D01*
G02Y208269I0J1502D01*
G02X544927Y207899I0J-1501D01*
G01X544928D01*
Y207898D01*
G03X545058Y207850I130J152D01*
G01X545322D01*
G03X545452Y207898I0J200D01*
G01X545453Y207899D01*
G02X547427I987J-1131D01*
G37*
G36*
G01X649789D02*
X649790Y207898D01*
G03X649920Y207850I130J152D01*
G01X650184D01*
G03X650314Y207898I0J200D01*
G01X650315Y207899D01*
G02X651302Y208269I987J-1131D01*
G02Y205265I0J-1502D01*
G02X650315Y205635I0J1501D01*
G01X650314D01*
Y205636D01*
G03X650184Y205684I-130J-152D01*
G01X649920D01*
G03X649790Y205636I0J-200D01*
G01X649789Y205635D01*
G02X647815I-987J1131D01*
G01X647814D01*
Y205636D01*
G03X647684Y205684I-130J-152D01*
G01X647420D01*
G03X647290Y205636I0J-200D01*
G01X647289Y205635D01*
G02X646302Y205265I-987J1131D01*
G02Y208269I0J1502D01*
G02X647289Y207899I0J-1501D01*
G01X647290D01*
Y207898D01*
G03X647420Y207850I130J152D01*
G01X647684D01*
G03X647814Y207898I0J200D01*
G01X647815Y207899D01*
G02X649789I987J-1131D01*
G37*
G36*
G01X752151D02*
X752152Y207898D01*
G03X752282Y207850I130J152D01*
G01X752546D01*
G03X752676Y207898I0J200D01*
G01X752677Y207899D01*
G02X753664Y208269I987J-1131D01*
G02Y205265I0J-1502D01*
G02X752677Y205635I0J1501D01*
G01X752676D01*
Y205636D01*
G03X752546Y205684I-130J-152D01*
G01X752282D01*
G03X752152Y205636I0J-200D01*
G01X752151Y205635D01*
G02X750177I-987J1131D01*
G01X750176D01*
Y205636D01*
G03X750046Y205684I-130J-152D01*
G01X749782D01*
G03X749652Y205636I0J-200D01*
G01X749651Y205635D01*
G02X748664Y205265I-987J1131D01*
G02Y208269I0J1502D01*
G02X749651Y207899I0J-1501D01*
G01X749652D01*
Y207898D01*
G03X749782Y207850I130J152D01*
G01X750046D01*
G03X750176Y207898I0J200D01*
G01X750177Y207899D01*
G02X752151I987J-1131D01*
G37*
G36*
G01X854513D02*
X854514Y207898D01*
G03X854644Y207850I130J152D01*
G01X854908D01*
G03X855038Y207898I0J200D01*
G01X855039Y207899D01*
G02X856026Y208269I987J-1131D01*
G02Y205265I0J-1502D01*
G02X855039Y205635I0J1501D01*
G01X855038D01*
Y205636D01*
G03X854908Y205684I-130J-152D01*
G01X854644D01*
G03X854514Y205636I0J-200D01*
G01X854513Y205635D01*
G02X852539I-987J1131D01*
G01X852538D01*
Y205636D01*
G03X852408Y205684I-130J-152D01*
G01X852144D01*
G03X852014Y205636I0J-200D01*
G01X852013Y205635D01*
G02X851026Y205265I-987J1131D01*
G02Y208269I0J1502D01*
G02X852013Y207899I0J-1501D01*
G01X852014D01*
Y207898D01*
G03X852144Y207850I130J152D01*
G01X852408D01*
G03X852538Y207898I0J200D01*
G01X852539Y207899D01*
G02X854513I987J-1131D01*
G37*
G36*
G01X1004513D02*
X1004514Y207898D01*
G03X1004644Y207850I130J152D01*
G01X1004908D01*
G03X1005038Y207898I0J200D01*
G01X1005039Y207899D01*
G02X1006026Y208269I987J-1131D01*
G02Y205265I0J-1502D01*
G02X1005039Y205635I0J1501D01*
G01X1005038D01*
Y205636D01*
G03X1004908Y205684I-130J-152D01*
G01X1004644D01*
G03X1004514Y205636I0J-200D01*
G01X1004513Y205635D01*
G02X1002539I-987J1131D01*
G01X1002538D01*
Y205636D01*
G03X1002408Y205684I-130J-152D01*
G01X1002144D01*
G03X1002014Y205636I0J-200D01*
G01X1002013Y205635D01*
G02X1001026Y205265I-987J1131D01*
G02Y208269I0J1502D01*
G02X1002013Y207899I0J-1501D01*
G01X1002014D01*
Y207898D01*
G03X1002144Y207850I130J152D01*
G01X1002408D01*
G03X1002538Y207898I0J200D01*
G01X1002539Y207899D01*
G02X1004513I987J-1131D01*
G37*
G36*
G01X1106875D02*
X1106876Y207898D01*
G03X1107006Y207850I130J152D01*
G01X1107270D01*
G03X1107400Y207898I0J200D01*
G01X1107401Y207899D01*
G02X1108388Y208269I987J-1131D01*
G02Y205265I0J-1502D01*
G02X1107401Y205635I0J1501D01*
G01X1107400D01*
Y205636D01*
G03X1107270Y205684I-130J-152D01*
G01X1107006D01*
G03X1106876Y205636I0J-200D01*
G01X1106875Y205635D01*
G02X1104901I-987J1131D01*
G01X1104900D01*
Y205636D01*
G03X1104770Y205684I-130J-152D01*
G01X1104506D01*
G03X1104376Y205636I0J-200D01*
G01X1104375Y205635D01*
G02X1103388Y205265I-987J1131D01*
G02Y208269I0J1502D01*
G02X1104375Y207899I0J-1501D01*
G01X1104376D01*
Y207898D01*
G03X1104506Y207850I130J152D01*
G01X1104770D01*
G03X1104900Y207898I0J200D01*
G01X1104901Y207899D01*
G02X1106875I987J-1131D01*
G37*
G36*
G01X1209237D02*
X1209238Y207898D01*
G03X1209368Y207850I130J152D01*
G01X1209632D01*
G03X1209762Y207898I0J200D01*
G01X1209763Y207899D01*
G02X1210750Y208269I987J-1131D01*
G02Y205265I0J-1502D01*
G02X1209763Y205635I0J1501D01*
G01X1209762D01*
Y205636D01*
G03X1209632Y205684I-130J-152D01*
G01X1209368D01*
G03X1209238Y205636I0J-200D01*
G01X1209237Y205635D01*
G02X1207263I-987J1131D01*
G01X1207262D01*
Y205636D01*
G03X1207132Y205684I-130J-152D01*
G01X1206868D01*
G03X1206738Y205636I0J-200D01*
G01X1206737Y205635D01*
G02X1205750Y205265I-987J1131D01*
G02Y208269I0J1502D01*
G02X1206737Y207899I0J-1501D01*
G01X1206738D01*
Y207898D01*
G03X1206868Y207850I130J152D01*
G01X1207132D01*
G03X1207262Y207898I0J200D01*
G01X1207263Y207899D01*
G02X1209237I987J-1131D01*
G37*
G36*
G01X1311599D02*
X1311600Y207898D01*
G03X1311730Y207850I130J152D01*
G01X1311994D01*
G03X1312124Y207898I0J200D01*
G01X1312125Y207899D01*
G02X1313112Y208269I987J-1131D01*
G02Y205265I0J-1502D01*
G02X1312125Y205635I0J1501D01*
G01X1312124D01*
Y205636D01*
G03X1311994Y205684I-130J-152D01*
G01X1311730D01*
G03X1311600Y205636I0J-200D01*
G01X1311599Y205635D01*
G02X1309625I-987J1131D01*
G01X1309624D01*
Y205636D01*
G03X1309494Y205684I-130J-152D01*
G01X1309230D01*
G03X1309100Y205636I0J-200D01*
G01X1309099Y205635D01*
G02X1308112Y205265I-987J1131D01*
G02Y208269I0J1502D01*
G02X1309099Y207899I0J-1501D01*
G01X1309100D01*
Y207898D01*
G03X1309230Y207850I130J152D01*
G01X1309494D01*
G03X1309624Y207898I0J200D01*
G01X1309625Y207899D01*
G02X1311599I987J-1131D01*
G37*
G36*
G01X1461600D02*
X1461601Y207898D01*
G03X1461731Y207850I130J152D01*
G01X1461995D01*
G03X1462125Y207898I0J200D01*
G01X1462126Y207899D01*
G02X1463113Y208269I987J-1131D01*
G02Y205265I0J-1502D01*
G02X1462126Y205635I0J1501D01*
G01X1462125D01*
Y205636D01*
G03X1461995Y205684I-130J-152D01*
G01X1461731D01*
G03X1461601Y205636I0J-200D01*
G01X1461600Y205635D01*
G02X1459626I-987J1131D01*
G01X1459625D01*
Y205636D01*
G03X1459495Y205684I-130J-152D01*
G01X1459231D01*
G03X1459101Y205636I0J-200D01*
G01X1459100Y205635D01*
G02X1458113Y205265I-987J1131D01*
G02Y208269I0J1502D01*
G02X1459100Y207899I0J-1501D01*
G01X1459101D01*
Y207898D01*
G03X1459231Y207850I130J152D01*
G01X1459495D01*
G03X1459625Y207898I0J200D01*
G01X1459626Y207899D01*
G02X1461600I987J-1131D01*
G37*
G36*
G01X1563962D02*
X1563963Y207898D01*
G03X1564093Y207850I130J152D01*
G01X1564357D01*
G03X1564487Y207898I0J200D01*
G01X1564488Y207899D01*
G02X1565475Y208269I987J-1131D01*
G02Y205265I0J-1502D01*
G02X1564488Y205635I0J1501D01*
G01X1564487D01*
Y205636D01*
G03X1564357Y205684I-130J-152D01*
G01X1564093D01*
G03X1563963Y205636I0J-200D01*
G01X1563962Y205635D01*
G02X1561988I-987J1131D01*
G01X1561987D01*
Y205636D01*
G03X1561857Y205684I-130J-152D01*
G01X1561593D01*
G03X1561463Y205636I0J-200D01*
G01X1561462Y205635D01*
G02X1560475Y205265I-987J1131D01*
G02Y208269I0J1502D01*
G02X1561462Y207899I0J-1501D01*
G01X1561463D01*
Y207898D01*
G03X1561593Y207850I130J152D01*
G01X1561857D01*
G03X1561987Y207898I0J200D01*
G01X1561988Y207899D01*
G02X1563962I987J-1131D01*
G37*
G36*
G01X1666324D02*
X1666325Y207898D01*
G03X1666455Y207850I130J152D01*
G01X1666719D01*
G03X1666849Y207898I0J200D01*
G01X1666850Y207899D01*
G02X1667837Y208269I987J-1131D01*
G02Y205265I0J-1502D01*
G02X1666850Y205635I0J1501D01*
G01X1666849D01*
Y205636D01*
G03X1666719Y205684I-130J-152D01*
G01X1666455D01*
G03X1666325Y205636I0J-200D01*
G01X1666324Y205635D01*
G02X1664350I-987J1131D01*
G01X1664349D01*
Y205636D01*
G03X1664219Y205684I-130J-152D01*
G01X1663955D01*
G03X1663825Y205636I0J-200D01*
G01X1663824Y205635D01*
G02X1662837Y205265I-987J1131D01*
G02Y208269I0J1502D01*
G02X1663824Y207899I0J-1501D01*
G01X1663825D01*
Y207898D01*
G03X1663955Y207850I130J152D01*
G01X1664219D01*
G03X1664349Y207898I0J200D01*
G01X1664350Y207899D01*
G02X1666324I987J-1131D01*
G37*
G36*
G01X1768686D02*
X1768687Y207898D01*
G03X1768817Y207850I130J152D01*
G01X1769081D01*
G03X1769211Y207898I0J200D01*
G01X1769212Y207899D01*
G02X1770199Y208269I987J-1131D01*
G02Y205265I0J-1502D01*
G02X1769212Y205635I0J1501D01*
G01X1769211D01*
Y205636D01*
G03X1769081Y205684I-130J-152D01*
G01X1768817D01*
G03X1768687Y205636I0J-200D01*
G01X1768686Y205635D01*
G02X1766712I-987J1131D01*
G01X1766711D01*
Y205636D01*
G03X1766581Y205684I-130J-152D01*
G01X1766317D01*
G03X1766187Y205636I0J-200D01*
G01X1766186Y205635D01*
G02X1765199Y205265I-987J1131D01*
G02Y208269I0J1502D01*
G02X1766186Y207899I0J-1501D01*
G01X1766187D01*
Y207898D01*
G03X1766317Y207850I130J152D01*
G01X1766581D01*
G03X1766711Y207898I0J200D01*
G01X1766712Y207899D01*
G02X1768686I987J-1131D01*
G37*
G36*
G01X232145Y205304D02*
G02Y208308I0J1502D01*
G02X233132Y207938I0J-1501D01*
G01X233133D01*
Y207937D01*
G03X233263Y207889I130J152D01*
G01X233527D01*
G03X233657Y207937I0J200D01*
G01X233658Y207938D01*
G02X234645Y208308I987J-1131D01*
G02Y205304I0J-1502D01*
G02X233658Y205674I0J1501D01*
G01X233657D01*
Y205675D01*
G03X233527Y205723I-130J-152D01*
G01X233263D01*
G03X233133Y205675I0J-200D01*
G01X233132Y205674D01*
G02X232145Y205304I-987J1131D01*
G37*
G36*
G01X334507D02*
G02Y208308I0J1502D01*
G02X335494Y207938I0J-1501D01*
G01X335495D01*
Y207937D01*
G03X335625Y207889I130J152D01*
G01X335889D01*
G03X336019Y207937I0J200D01*
G01X336020Y207938D01*
G02X337007Y208308I987J-1131D01*
G02Y205304I0J-1502D01*
G02X336020Y205674I0J1501D01*
G01X336019D01*
Y205675D01*
G03X335889Y205723I-130J-152D01*
G01X335625D01*
G03X335495Y205675I0J-200D01*
G01X335494Y205674D01*
G02X334507Y205304I-987J1131D01*
G37*
G36*
G01X484508D02*
G02Y208308I0J1502D01*
G02X485495Y207938I0J-1501D01*
G01X485496D01*
Y207937D01*
G03X485626Y207889I130J152D01*
G01X485890D01*
G03X486020Y207937I0J200D01*
G01X486021Y207938D01*
G02X487008Y208308I987J-1131D01*
G02Y205304I0J-1502D01*
G02X486021Y205674I0J1501D01*
G01X486020D01*
Y205675D01*
G03X485890Y205723I-130J-152D01*
G01X485626D01*
G03X485496Y205675I0J-200D01*
G01X485495Y205674D01*
G02X484508Y205304I-987J1131D01*
G37*
G36*
G01X586870D02*
G02Y208308I0J1502D01*
G02X587857Y207938I0J-1501D01*
G01X587858D01*
Y207937D01*
G03X587988Y207889I130J152D01*
G01X588252D01*
G03X588382Y207937I0J200D01*
G01X588383Y207938D01*
G02X589370Y208308I987J-1131D01*
G02Y205304I0J-1502D01*
G02X588383Y205674I0J1501D01*
G01X588382D01*
Y205675D01*
G03X588252Y205723I-130J-152D01*
G01X587988D01*
G03X587858Y205675I0J-200D01*
G01X587857Y205674D01*
G02X586870Y205304I-987J1131D01*
G37*
G36*
G01X689232D02*
G02Y208308I0J1502D01*
G02X690219Y207938I0J-1501D01*
G01X690220D01*
Y207937D01*
G03X690350Y207889I130J152D01*
G01X690614D01*
G03X690744Y207937I0J200D01*
G01X690745Y207938D01*
G02X691732Y208308I987J-1131D01*
G02Y205304I0J-1502D01*
G02X690745Y205674I0J1501D01*
G01X690744D01*
Y205675D01*
G03X690614Y205723I-130J-152D01*
G01X690350D01*
G03X690220Y205675I0J-200D01*
G01X690219Y205674D01*
G02X689232Y205304I-987J1131D01*
G37*
G36*
G01X791594D02*
G02Y208308I0J1502D01*
G02X792581Y207938I0J-1501D01*
G01X792582D01*
Y207937D01*
G03X792712Y207889I130J152D01*
G01X792976D01*
G03X793106Y207937I0J200D01*
G01X793107Y207938D01*
G02X794094Y208308I987J-1131D01*
G02Y205304I0J-1502D01*
G02X793107Y205674I0J1501D01*
G01X793106D01*
Y205675D01*
G03X792976Y205723I-130J-152D01*
G01X792712D01*
G03X792582Y205675I0J-200D01*
G01X792581Y205674D01*
G02X791594Y205304I-987J1131D01*
G37*
G36*
G01X1043956D02*
G02Y208308I0J1502D01*
G02X1044943Y207938I0J-1501D01*
G01X1044944D01*
Y207937D01*
G03X1045074Y207889I130J152D01*
G01X1045338D01*
G03X1045468Y207937I0J200D01*
G01X1045469Y207938D01*
G02X1046456Y208308I987J-1131D01*
G02Y205304I0J-1502D01*
G02X1045469Y205674I0J1501D01*
G01X1045468D01*
Y205675D01*
G03X1045338Y205723I-130J-152D01*
G01X1045074D01*
G03X1044944Y205675I0J-200D01*
G01X1044943Y205674D01*
G02X1043956Y205304I-987J1131D01*
G37*
G36*
G01X1146318D02*
G02Y208308I0J1502D01*
G02X1147305Y207938I0J-1501D01*
G01X1147306D01*
Y207937D01*
G03X1147436Y207889I130J152D01*
G01X1147700D01*
G03X1147830Y207937I0J200D01*
G01X1147831Y207938D01*
G02X1148818Y208308I987J-1131D01*
G02Y205304I0J-1502D01*
G02X1147831Y205674I0J1501D01*
G01X1147830D01*
Y205675D01*
G03X1147700Y205723I-130J-152D01*
G01X1147436D01*
G03X1147306Y205675I0J-200D01*
G01X1147305Y205674D01*
G02X1146318Y205304I-987J1131D01*
G37*
G36*
G01X1248680D02*
G02Y208308I0J1502D01*
G02X1249667Y207938I0J-1501D01*
G01X1249668D01*
Y207937D01*
G03X1249798Y207889I130J152D01*
G01X1250062D01*
G03X1250192Y207937I0J200D01*
G01X1250193Y207938D01*
G02X1251180Y208308I987J-1131D01*
G02Y205304I0J-1502D01*
G02X1250193Y205674I0J1501D01*
G01X1250192D01*
Y205675D01*
G03X1250062Y205723I-130J-152D01*
G01X1249798D01*
G03X1249668Y205675I0J-200D01*
G01X1249667Y205674D01*
G02X1248680Y205304I-987J1131D01*
G37*
G36*
G01X1398681D02*
G02Y208308I0J1502D01*
G02X1399668Y207938I0J-1501D01*
G01X1399669D01*
Y207937D01*
G03X1399799Y207889I130J152D01*
G01X1400063D01*
G03X1400193Y207937I0J200D01*
G01X1400194Y207938D01*
G02X1401181Y208308I987J-1131D01*
G02Y205304I0J-1502D01*
G02X1400194Y205674I0J1501D01*
G01X1400193D01*
Y205675D01*
G03X1400063Y205723I-130J-152D01*
G01X1399799D01*
G03X1399669Y205675I0J-200D01*
G01X1399668Y205674D01*
G02X1398681Y205304I-987J1131D01*
G37*
G36*
G01X1501043D02*
G02Y208308I0J1502D01*
G02X1502030Y207938I0J-1501D01*
G01X1502031D01*
Y207937D01*
G03X1502161Y207889I130J152D01*
G01X1502425D01*
G03X1502555Y207937I0J200D01*
G01X1502556Y207938D01*
G02X1503543Y208308I987J-1131D01*
G02Y205304I0J-1502D01*
G02X1502556Y205674I0J1501D01*
G01X1502555D01*
Y205675D01*
G03X1502425Y205723I-130J-152D01*
G01X1502161D01*
G03X1502031Y205675I0J-200D01*
G01X1502030Y205674D01*
G02X1501043Y205304I-987J1131D01*
G37*
G36*
G01X1603405D02*
G02Y208308I0J1502D01*
G02X1604392Y207938I0J-1501D01*
G01X1604393D01*
Y207937D01*
G03X1604523Y207889I130J152D01*
G01X1604787D01*
G03X1604917Y207937I0J200D01*
G01X1604918Y207938D01*
G02X1605905Y208308I987J-1131D01*
G02Y205304I0J-1502D01*
G02X1604918Y205674I0J1501D01*
G01X1604917D01*
Y205675D01*
G03X1604787Y205723I-130J-152D01*
G01X1604523D01*
G03X1604393Y205675I0J-200D01*
G01X1604392Y205674D01*
G02X1603405Y205304I-987J1131D01*
G37*
G36*
G01X1705767D02*
G02Y208308I0J1502D01*
G02X1706754Y207938I0J-1501D01*
G01X1706755D01*
Y207937D01*
G03X1706885Y207889I130J152D01*
G01X1707149D01*
G03X1707279Y207937I0J200D01*
G01X1707280Y207938D01*
G02X1708267Y208308I987J-1131D01*
G02Y205304I0J-1502D01*
G02X1707280Y205674I0J1501D01*
G01X1707279D01*
Y205675D01*
G03X1707149Y205723I-130J-152D01*
G01X1706885D01*
G03X1706755Y205675I0J-200D01*
G01X1706754Y205674D01*
G02X1705767Y205304I-987J1131D01*
G37*
G36*
G01X932909Y207141D02*
G02X935913I1502J0D01*
G02X935543Y206154I-1501J0D01*
G01Y206153D01*
X935542D01*
G03X935494Y206023I152J-130D01*
G01Y205759D01*
G03X935542Y205629I200J0D01*
G01X935543Y205628D01*
G02Y203654I-1131J-987D01*
G01Y203653D01*
X935542D01*
G03X935494Y203523I152J-130D01*
G01Y203259D01*
G03X935542Y203129I200J0D01*
G01X935543Y203128D01*
G02X935913Y202141I-1131J-987D01*
G02X934411Y200639I-1502J0D01*
G02X933556Y200906I0J1502D01*
G01X933522Y200929D01*
X933441Y200946D01*
X933074Y200866D01*
X933007Y200818D01*
X932986Y200783D01*
G02X931698Y200054I-1288J773D01*
G02Y203058I0J1502D01*
G02X932553Y202791I0J-1502D01*
G01X932587Y202768D01*
X932668Y202751D01*
X933035Y202831D01*
X933102Y202879D01*
X933123Y202914D01*
G02X933279Y203127I1285J-777D01*
G03X933280Y203129I-173J88D01*
G03X933328Y203259I-152J130D01*
G01Y203523D01*
G03X933280Y203653I-200J0D01*
G01X933279Y203654D01*
G02Y205628I1131J987D01*
G01Y205629D01*
X933280D01*
G03X933328Y205759I-152J130D01*
G01Y206023D01*
G03X933280Y206153I-200J0D01*
G01X933279Y206154D01*
G02X932909Y207141I1131J987D01*
G37*
G36*
G01X230372Y209007D02*
G02Y212011I0J1502D01*
G02X231359Y211641I0J-1501D01*
G01X231360D01*
Y211640D01*
G03X231490Y211592I130J152D01*
G01X231754D01*
G03X231884Y211640I0J200D01*
G01X231885Y211641D01*
G02X232872Y212011I987J-1131D01*
G02Y209007I0J-1502D01*
G02X231885Y209377I0J1501D01*
G01X231884D01*
Y209378D01*
G03X231754Y209426I-130J-152D01*
G01X231490D01*
G03X231360Y209378I0J-200D01*
G01X231359Y209377D01*
G02X230372Y209007I-987J1131D01*
G37*
G36*
G01X332734D02*
G02Y212011I0J1502D01*
G02X333721Y211641I0J-1501D01*
G01X333722D01*
Y211640D01*
G03X333852Y211592I130J152D01*
G01X334116D01*
G03X334246Y211640I0J200D01*
G01X334247Y211641D01*
G02X335234Y212011I987J-1131D01*
G02Y209007I0J-1502D01*
G02X334247Y209377I0J1501D01*
G01X334246D01*
Y209378D01*
G03X334116Y209426I-130J-152D01*
G01X333852D01*
G03X333722Y209378I0J-200D01*
G01X333721Y209377D01*
G02X332734Y209007I-987J1131D01*
G37*
G36*
G01X482735D02*
G02Y212011I0J1502D01*
G02X483722Y211641I0J-1501D01*
G01X483723D01*
Y211640D01*
G03X483853Y211592I130J152D01*
G01X484117D01*
G03X484247Y211640I0J200D01*
G01X484248Y211641D01*
G02X485235Y212011I987J-1131D01*
G02Y209007I0J-1502D01*
G02X484248Y209377I0J1501D01*
G01X484247D01*
Y209378D01*
G03X484117Y209426I-130J-152D01*
G01X483853D01*
G03X483723Y209378I0J-200D01*
G01X483722Y209377D01*
G02X482735Y209007I-987J1131D01*
G37*
G36*
G01X585097D02*
G02Y212011I0J1502D01*
G02X586084Y211641I0J-1501D01*
G01X586085D01*
Y211640D01*
G03X586215Y211592I130J152D01*
G01X586479D01*
G03X586609Y211640I0J200D01*
G01X586610Y211641D01*
G02X587597Y212011I987J-1131D01*
G02Y209007I0J-1502D01*
G02X586610Y209377I0J1501D01*
G01X586609D01*
Y209378D01*
G03X586479Y209426I-130J-152D01*
G01X586215D01*
G03X586085Y209378I0J-200D01*
G01X586084Y209377D01*
G02X585097Y209007I-987J1131D01*
G37*
G36*
G01X687459D02*
G02Y212011I0J1502D01*
G02X688446Y211641I0J-1501D01*
G01X688447D01*
Y211640D01*
G03X688577Y211592I130J152D01*
G01X688841D01*
G03X688971Y211640I0J200D01*
G01X688972Y211641D01*
G02X689959Y212011I987J-1131D01*
G02Y209007I0J-1502D01*
G02X688972Y209377I0J1501D01*
G01X688971D01*
Y209378D01*
G03X688841Y209426I-130J-152D01*
G01X688577D01*
G03X688447Y209378I0J-200D01*
G01X688446Y209377D01*
G02X687459Y209007I-987J1131D01*
G37*
G36*
G01X789821D02*
G02Y212011I0J1502D01*
G02X790808Y211641I0J-1501D01*
G01X790809D01*
Y211640D01*
G03X790939Y211592I130J152D01*
G01X791203D01*
G03X791333Y211640I0J200D01*
G01X791334Y211641D01*
G02X792321Y212011I987J-1131D01*
G02Y209007I0J-1502D01*
G02X791334Y209377I0J1501D01*
G01X791333D01*
Y209378D01*
G03X791203Y209426I-130J-152D01*
G01X790939D01*
G03X790809Y209378I0J-200D01*
G01X790808Y209377D01*
G02X789821Y209007I-987J1131D01*
G37*
G36*
G01X1042183D02*
G02Y212011I0J1502D01*
G02X1043170Y211641I0J-1501D01*
G01X1043171D01*
Y211640D01*
G03X1043301Y211592I130J152D01*
G01X1043565D01*
G03X1043695Y211640I0J200D01*
G01X1043696Y211641D01*
G02X1044683Y212011I987J-1131D01*
G02Y209007I0J-1502D01*
G02X1043696Y209377I0J1501D01*
G01X1043695D01*
Y209378D01*
G03X1043565Y209426I-130J-152D01*
G01X1043301D01*
G03X1043171Y209378I0J-200D01*
G01X1043170Y209377D01*
G02X1042183Y209007I-987J1131D01*
G37*
G36*
G01X1144545D02*
G02Y212011I0J1502D01*
G02X1145532Y211641I0J-1501D01*
G01X1145533D01*
Y211640D01*
G03X1145663Y211592I130J152D01*
G01X1145927D01*
G03X1146057Y211640I0J200D01*
G01X1146058Y211641D01*
G02X1147045Y212011I987J-1131D01*
G02Y209007I0J-1502D01*
G02X1146058Y209377I0J1501D01*
G01X1146057D01*
Y209378D01*
G03X1145927Y209426I-130J-152D01*
G01X1145663D01*
G03X1145533Y209378I0J-200D01*
G01X1145532Y209377D01*
G02X1144545Y209007I-987J1131D01*
G37*
G36*
G01X1246907D02*
G02Y212011I0J1502D01*
G02X1247894Y211641I0J-1501D01*
G01X1247895D01*
Y211640D01*
G03X1248025Y211592I130J152D01*
G01X1248289D01*
G03X1248419Y211640I0J200D01*
G01X1248420Y211641D01*
G02X1249407Y212011I987J-1131D01*
G02Y209007I0J-1502D01*
G02X1248420Y209377I0J1501D01*
G01X1248419D01*
Y209378D01*
G03X1248289Y209426I-130J-152D01*
G01X1248025D01*
G03X1247895Y209378I0J-200D01*
G01X1247894Y209377D01*
G02X1246907Y209007I-987J1131D01*
G37*
G36*
G01X1396908D02*
G02Y212011I0J1502D01*
G02X1397895Y211641I0J-1501D01*
G01X1397896D01*
Y211640D01*
G03X1398026Y211592I130J152D01*
G01X1398290D01*
G03X1398420Y211640I0J200D01*
G01X1398421Y211641D01*
G02X1399408Y212011I987J-1131D01*
G02Y209007I0J-1502D01*
G02X1398421Y209377I0J1501D01*
G01X1398420D01*
Y209378D01*
G03X1398290Y209426I-130J-152D01*
G01X1398026D01*
G03X1397896Y209378I0J-200D01*
G01X1397895Y209377D01*
G02X1396908Y209007I-987J1131D01*
G37*
G36*
G01X1499270D02*
G02Y212011I0J1502D01*
G02X1500257Y211641I0J-1501D01*
G01X1500258D01*
Y211640D01*
G03X1500388Y211592I130J152D01*
G01X1500652D01*
G03X1500782Y211640I0J200D01*
G01X1500783Y211641D01*
G02X1501770Y212011I987J-1131D01*
G02Y209007I0J-1502D01*
G02X1500783Y209377I0J1501D01*
G01X1500782D01*
Y209378D01*
G03X1500652Y209426I-130J-152D01*
G01X1500388D01*
G03X1500258Y209378I0J-200D01*
G01X1500257Y209377D01*
G02X1499270Y209007I-987J1131D01*
G37*
G36*
G01X1601632D02*
G02Y212011I0J1502D01*
G02X1602619Y211641I0J-1501D01*
G01X1602620D01*
Y211640D01*
G03X1602750Y211592I130J152D01*
G01X1603014D01*
G03X1603144Y211640I0J200D01*
G01X1603145Y211641D01*
G02X1604132Y212011I987J-1131D01*
G02Y209007I0J-1502D01*
G02X1603145Y209377I0J1501D01*
G01X1603144D01*
Y209378D01*
G03X1603014Y209426I-130J-152D01*
G01X1602750D01*
G03X1602620Y209378I0J-200D01*
G01X1602619Y209377D01*
G02X1601632Y209007I-987J1131D01*
G37*
G36*
G01X1703994D02*
G02Y212011I0J1502D01*
G02X1704981Y211641I0J-1501D01*
G01X1704982D01*
Y211640D01*
G03X1705112Y211592I130J152D01*
G01X1705376D01*
G03X1705506Y211640I0J200D01*
G01X1705507Y211641D01*
G02X1706494Y212011I987J-1131D01*
G02Y209007I0J-1502D01*
G02X1705507Y209377I0J1501D01*
G01X1705506D01*
Y209378D01*
G03X1705376Y209426I-130J-152D01*
G01X1705112D01*
G03X1704982Y209378I0J-200D01*
G01X1704981Y209377D01*
G02X1703994Y209007I-987J1131D01*
G37*
G36*
G01X177679Y213859D02*
G02X180683I1502J0D01*
G02X180313Y212872I-1501J0D01*
G01Y212871D01*
X180312D01*
G03X180264Y212741I152J-130D01*
G01Y212477D01*
G03X180312Y212347I200J0D01*
G01X180313Y212346D01*
G02X180683Y211359I-1131J-987D01*
G02X177679I-1502J0D01*
G02X178049Y212346I1501J0D01*
G01Y212347D01*
X178050D01*
G03X178098Y212477I-152J130D01*
G01Y212741D01*
G03X178050Y212871I-200J0D01*
G01X178049Y212872D01*
G02X177679Y213859I1131J987D01*
G37*
G36*
G01X280041D02*
G02X283045I1502J0D01*
G02X282675Y212872I-1501J0D01*
G01Y212871D01*
X282674D01*
G03X282626Y212741I152J-130D01*
G01Y212477D01*
G03X282674Y212347I200J0D01*
G01X282675Y212346D01*
G02X283045Y211359I-1131J-987D01*
G02X280041I-1502J0D01*
G02X280411Y212346I1501J0D01*
G01Y212347D01*
X280412D01*
G03X280460Y212477I-152J130D01*
G01Y212741D01*
G03X280412Y212871I-200J0D01*
G01X280411Y212872D01*
G02X280041Y213859I1131J987D01*
G37*
G36*
G01X382403D02*
G02X385407I1502J0D01*
G02X385037Y212872I-1501J0D01*
G01Y212871D01*
X385036D01*
G03X384988Y212741I152J-130D01*
G01Y212477D01*
G03X385036Y212347I200J0D01*
G01X385037Y212346D01*
G02X385407Y211359I-1131J-987D01*
G02X382403I-1502J0D01*
G02X382773Y212346I1501J0D01*
G01Y212347D01*
X382774D01*
G03X382822Y212477I-152J130D01*
G01Y212741D01*
G03X382774Y212871I-200J0D01*
G01X382773Y212872D01*
G02X382403Y213859I1131J987D01*
G37*
G36*
G01X532404D02*
G02X535408I1502J0D01*
G02X535038Y212872I-1501J0D01*
G01Y212871D01*
X535037D01*
G03X534989Y212741I152J-130D01*
G01Y212477D01*
G03X535037Y212347I200J0D01*
G01X535038Y212346D01*
G02X535408Y211359I-1131J-987D01*
G02X532404I-1502J0D01*
G02X532774Y212346I1501J0D01*
G01Y212347D01*
X532775D01*
G03X532823Y212477I-152J130D01*
G01Y212741D01*
G03X532775Y212871I-200J0D01*
G01X532774Y212872D01*
G02X532404Y213859I1131J987D01*
G37*
G36*
G01X634766D02*
G02X637770I1502J0D01*
G02X637400Y212872I-1501J0D01*
G01Y212871D01*
X637399D01*
G03X637351Y212741I152J-130D01*
G01Y212477D01*
G03X637399Y212347I200J0D01*
G01X637400Y212346D01*
G02X637770Y211359I-1131J-987D01*
G02X634766I-1502J0D01*
G02X635136Y212346I1501J0D01*
G01Y212347D01*
X635137D01*
G03X635185Y212477I-152J130D01*
G01Y212741D01*
G03X635137Y212871I-200J0D01*
G01X635136Y212872D01*
G02X634766Y213859I1131J987D01*
G37*
G36*
G01X737128D02*
G02X740132I1502J0D01*
G02X739762Y212872I-1501J0D01*
G01Y212871D01*
X739761D01*
G03X739713Y212741I152J-130D01*
G01Y212477D01*
G03X739761Y212347I200J0D01*
G01X739762Y212346D01*
G02X740132Y211359I-1131J-987D01*
G02X737128I-1502J0D01*
G02X737498Y212346I1501J0D01*
G01Y212347D01*
X737499D01*
G03X737547Y212477I-152J130D01*
G01Y212741D01*
G03X737499Y212871I-200J0D01*
G01X737498Y212872D01*
G02X737128Y213859I1131J987D01*
G37*
G36*
G01X839490D02*
G02X842494I1502J0D01*
G02X842124Y212872I-1501J0D01*
G01Y212871D01*
X842123D01*
G03X842075Y212741I152J-130D01*
G01Y212477D01*
G03X842123Y212347I200J0D01*
G01X842124Y212346D01*
G02X842494Y211359I-1131J-987D01*
G02X839490I-1502J0D01*
G02X839860Y212346I1501J0D01*
G01Y212347D01*
X839861D01*
G03X839909Y212477I-152J130D01*
G01Y212741D01*
G03X839861Y212871I-200J0D01*
G01X839860Y212872D01*
G02X839490Y213859I1131J987D01*
G37*
G36*
G01X989490D02*
G02X992494I1502J0D01*
G02X992124Y212872I-1501J0D01*
G01Y212871D01*
X992123D01*
G03X992075Y212741I152J-130D01*
G01Y212477D01*
G03X992123Y212347I200J0D01*
G01X992124Y212346D01*
G02X992494Y211359I-1131J-987D01*
G02X989490I-1502J0D01*
G02X989860Y212346I1501J0D01*
G01Y212347D01*
X989861D01*
G03X989909Y212477I-152J130D01*
G01Y212741D01*
G03X989861Y212871I-200J0D01*
G01X989860Y212872D01*
G02X989490Y213859I1131J987D01*
G37*
G36*
G01X1091852D02*
G02X1094856I1502J0D01*
G02X1094486Y212872I-1501J0D01*
G01Y212871D01*
X1094485D01*
G03X1094437Y212741I152J-130D01*
G01Y212477D01*
G03X1094485Y212347I200J0D01*
G01X1094486Y212346D01*
G02X1094856Y211359I-1131J-987D01*
G02X1091852I-1502J0D01*
G02X1092222Y212346I1501J0D01*
G01Y212347D01*
X1092223D01*
G03X1092271Y212477I-152J130D01*
G01Y212741D01*
G03X1092223Y212871I-200J0D01*
G01X1092222Y212872D01*
G02X1091852Y213859I1131J987D01*
G37*
G36*
G01X1194214D02*
G02X1197218I1502J0D01*
G02X1196848Y212872I-1501J0D01*
G01Y212871D01*
X1196847D01*
G03X1196799Y212741I152J-130D01*
G01Y212477D01*
G03X1196847Y212347I200J0D01*
G01X1196848Y212346D01*
G02X1197218Y211359I-1131J-987D01*
G02X1194214I-1502J0D01*
G02X1194584Y212346I1501J0D01*
G01Y212347D01*
X1194585D01*
G03X1194633Y212477I-152J130D01*
G01Y212741D01*
G03X1194585Y212871I-200J0D01*
G01X1194584Y212872D01*
G02X1194214Y213859I1131J987D01*
G37*
G36*
G01X1296576D02*
G02X1299580I1502J0D01*
G02X1299210Y212872I-1501J0D01*
G01Y212871D01*
X1299209D01*
G03X1299161Y212741I152J-130D01*
G01Y212477D01*
G03X1299209Y212347I200J0D01*
G01X1299210Y212346D01*
G02X1299580Y211359I-1131J-987D01*
G02X1296576I-1502J0D01*
G02X1296946Y212346I1501J0D01*
G01Y212347D01*
X1296947D01*
G03X1296995Y212477I-152J130D01*
G01Y212741D01*
G03X1296947Y212871I-200J0D01*
G01X1296946Y212872D01*
G02X1296576Y213859I1131J987D01*
G37*
G36*
G01X1446577D02*
G02X1449581I1502J0D01*
G02X1449211Y212872I-1501J0D01*
G01Y212871D01*
X1449210D01*
G03X1449162Y212741I152J-130D01*
G01Y212477D01*
G03X1449210Y212347I200J0D01*
G01X1449211Y212346D01*
G02X1449581Y211359I-1131J-987D01*
G02X1446577I-1502J0D01*
G02X1446947Y212346I1501J0D01*
G01Y212347D01*
X1446948D01*
G03X1446996Y212477I-152J130D01*
G01Y212741D01*
G03X1446948Y212871I-200J0D01*
G01X1446947Y212872D01*
G02X1446577Y213859I1131J987D01*
G37*
G36*
G01X1548939D02*
G02X1551943I1502J0D01*
G02X1551573Y212872I-1501J0D01*
G01Y212871D01*
X1551572D01*
G03X1551524Y212741I152J-130D01*
G01Y212477D01*
G03X1551572Y212347I200J0D01*
G01X1551573Y212346D01*
G02X1551943Y211359I-1131J-987D01*
G02X1548939I-1502J0D01*
G02X1549309Y212346I1501J0D01*
G01Y212347D01*
X1549310D01*
G03X1549358Y212477I-152J130D01*
G01Y212741D01*
G03X1549310Y212871I-200J0D01*
G01X1549309Y212872D01*
G02X1548939Y213859I1131J987D01*
G37*
G36*
G01X1651301D02*
G02X1654305I1502J0D01*
G02X1653935Y212872I-1501J0D01*
G01Y212871D01*
X1653934D01*
G03X1653886Y212741I152J-130D01*
G01Y212477D01*
G03X1653934Y212347I200J0D01*
G01X1653935Y212346D01*
G02X1654305Y211359I-1131J-987D01*
G02X1651301I-1502J0D01*
G02X1651671Y212346I1501J0D01*
G01Y212347D01*
X1651672D01*
G03X1651720Y212477I-152J130D01*
G01Y212741D01*
G03X1651672Y212871I-200J0D01*
G01X1651671Y212872D01*
G02X1651301Y213859I1131J987D01*
G37*
G36*
G01X1753663D02*
G02X1756667I1502J0D01*
G02X1756297Y212872I-1501J0D01*
G01Y212871D01*
X1756296D01*
G03X1756248Y212741I152J-130D01*
G01Y212477D01*
G03X1756296Y212347I200J0D01*
G01X1756297Y212346D01*
G02X1756667Y211359I-1131J-987D01*
G02X1753663I-1502J0D01*
G02X1754033Y212346I1501J0D01*
G01Y212347D01*
X1754034D01*
G03X1754082Y212477I-152J130D01*
G01Y212741D01*
G03X1754034Y212871I-200J0D01*
G01X1754033Y212872D01*
G02X1753663Y213859I1131J987D01*
G37*
G36*
G01X155593Y215478D02*
G02X158597I1502J0D01*
G02X158227Y214491I-1501J0D01*
G01Y214490D01*
X158226D01*
G03X158178Y214360I152J-130D01*
G01Y214096D01*
G03X158226Y213966I200J0D01*
G01X158227Y213965D01*
G02Y211991I-1131J-987D01*
G01Y211990D01*
X158226D01*
G03X158178Y211860I152J-130D01*
G01Y211596D01*
G03X158226Y211466I200J0D01*
G01X158227Y211465D01*
G02Y209491I-1131J-987D01*
G01Y209490D01*
X158226D01*
G03X158178Y209360I152J-130D01*
G01Y209096D01*
G03X158226Y208966I200J0D01*
G01X158227Y208965D01*
G02X158597Y207978I-1131J-987D01*
G02X155593I-1502J0D01*
G02X155963Y208965I1501J0D01*
G01Y208966D01*
X155964D01*
G03X156012Y209096I-152J130D01*
G01Y209360D01*
G03X155964Y209490I-200J0D01*
G01X155963Y209491D01*
G02Y211465I1131J987D01*
G01Y211466D01*
X155964D01*
G03X156012Y211596I-152J130D01*
G01Y211860D01*
G03X155964Y211990I-200J0D01*
G01X155963Y211991D01*
G02Y213965I1131J987D01*
G01Y213966D01*
X155964D01*
G03X156012Y214096I-152J130D01*
G01Y214360D01*
G03X155964Y214490I-200J0D01*
G01X155963Y214491D01*
G02X155593Y215478I1131J987D01*
G37*
G36*
G01X257955D02*
G02X260959I1502J0D01*
G02X260589Y214491I-1501J0D01*
G01Y214490D01*
X260588D01*
G03X260540Y214360I152J-130D01*
G01Y214096D01*
G03X260588Y213966I200J0D01*
G01X260589Y213965D01*
G02Y211991I-1131J-987D01*
G01Y211990D01*
X260588D01*
G03X260540Y211860I152J-130D01*
G01Y211596D01*
G03X260588Y211466I200J0D01*
G01X260589Y211465D01*
G02Y209491I-1131J-987D01*
G01Y209490D01*
X260588D01*
G03X260540Y209360I152J-130D01*
G01Y209096D01*
G03X260588Y208966I200J0D01*
G01X260589Y208965D01*
G02X260959Y207978I-1131J-987D01*
G02X257955I-1502J0D01*
G02X258325Y208965I1501J0D01*
G01Y208966D01*
X258326D01*
G03X258374Y209096I-152J130D01*
G01Y209360D01*
G03X258326Y209490I-200J0D01*
G01X258325Y209491D01*
G02Y211465I1131J987D01*
G01Y211466D01*
X258326D01*
G03X258374Y211596I-152J130D01*
G01Y211860D01*
G03X258326Y211990I-200J0D01*
G01X258325Y211991D01*
G02Y213965I1131J987D01*
G01Y213966D01*
X258326D01*
G03X258374Y214096I-152J130D01*
G01Y214360D01*
G03X258326Y214490I-200J0D01*
G01X258325Y214491D01*
G02X257955Y215478I1131J987D01*
G37*
G36*
G01X510318D02*
G02X513322I1502J0D01*
G02X512952Y214491I-1501J0D01*
G01Y214490D01*
X512951D01*
G03X512903Y214360I152J-130D01*
G01Y214096D01*
G03X512951Y213966I200J0D01*
G01X512952Y213965D01*
G02Y211991I-1131J-987D01*
G01Y211990D01*
X512951D01*
G03X512903Y211860I152J-130D01*
G01Y211596D01*
G03X512951Y211466I200J0D01*
G01X512952Y211465D01*
G02Y209491I-1131J-987D01*
G01Y209490D01*
X512951D01*
G03X512903Y209360I152J-130D01*
G01Y209096D01*
G03X512951Y208966I200J0D01*
G01X512952Y208965D01*
G02X513322Y207978I-1131J-987D01*
G02X510318I-1502J0D01*
G02X510688Y208965I1501J0D01*
G01Y208966D01*
X510689D01*
G03X510737Y209096I-152J130D01*
G01Y209360D01*
G03X510689Y209490I-200J0D01*
G01X510688Y209491D01*
G02Y211465I1131J987D01*
G01Y211466D01*
X510689D01*
G03X510737Y211596I-152J130D01*
G01Y211860D01*
G03X510689Y211990I-200J0D01*
G01X510688Y211991D01*
G02Y213965I1131J987D01*
G01Y213966D01*
X510689D01*
G03X510737Y214096I-152J130D01*
G01Y214360D01*
G03X510689Y214490I-200J0D01*
G01X510688Y214491D01*
G02X510318Y215478I1131J987D01*
G37*
G36*
G01X612680D02*
G02X615684I1502J0D01*
G02X615314Y214491I-1501J0D01*
G01Y214490D01*
X615313D01*
G03X615265Y214360I152J-130D01*
G01Y214096D01*
G03X615313Y213966I200J0D01*
G01X615314Y213965D01*
G02Y211991I-1131J-987D01*
G01Y211990D01*
X615313D01*
G03X615265Y211860I152J-130D01*
G01Y211596D01*
G03X615313Y211466I200J0D01*
G01X615314Y211465D01*
G02Y209491I-1131J-987D01*
G01Y209490D01*
X615313D01*
G03X615265Y209360I152J-130D01*
G01Y209096D01*
G03X615313Y208966I200J0D01*
G01X615314Y208965D01*
G02X615684Y207978I-1131J-987D01*
G02X612680I-1502J0D01*
G02X613050Y208965I1501J0D01*
G01Y208966D01*
X613051D01*
G03X613099Y209096I-152J130D01*
G01Y209360D01*
G03X613051Y209490I-200J0D01*
G01X613050Y209491D01*
G02Y211465I1131J987D01*
G01Y211466D01*
X613051D01*
G03X613099Y211596I-152J130D01*
G01Y211860D01*
G03X613051Y211990I-200J0D01*
G01X613050Y211991D01*
G02Y213965I1131J987D01*
G01Y213966D01*
X613051D01*
G03X613099Y214096I-152J130D01*
G01Y214360D01*
G03X613051Y214490I-200J0D01*
G01X613050Y214491D01*
G02X612680Y215478I1131J987D01*
G37*
G36*
G01X715042D02*
G02X718046I1502J0D01*
G02X717676Y214491I-1501J0D01*
G01Y214490D01*
X717675D01*
G03X717627Y214360I152J-130D01*
G01Y214096D01*
G03X717675Y213966I200J0D01*
G01X717676Y213965D01*
G02Y211991I-1131J-987D01*
G01Y211990D01*
X717675D01*
G03X717627Y211860I152J-130D01*
G01Y211596D01*
G03X717675Y211466I200J0D01*
G01X717676Y211465D01*
G02Y209491I-1131J-987D01*
G01Y209490D01*
X717675D01*
G03X717627Y209360I152J-130D01*
G01Y209096D01*
G03X717675Y208966I200J0D01*
G01X717676Y208965D01*
G02X718046Y207978I-1131J-987D01*
G02X715042I-1502J0D01*
G02X715412Y208965I1501J0D01*
G01Y208966D01*
X715413D01*
G03X715461Y209096I-152J130D01*
G01Y209360D01*
G03X715413Y209490I-200J0D01*
G01X715412Y209491D01*
G02Y211465I1131J987D01*
G01Y211466D01*
X715413D01*
G03X715461Y211596I-152J130D01*
G01Y211860D01*
G03X715413Y211990I-200J0D01*
G01X715412Y211991D01*
G02Y213965I1131J987D01*
G01Y213966D01*
X715413D01*
G03X715461Y214096I-152J130D01*
G01Y214360D01*
G03X715413Y214490I-200J0D01*
G01X715412Y214491D01*
G02X715042Y215478I1131J987D01*
G37*
G36*
G01X817404D02*
G02X820408I1502J0D01*
G02X820038Y214491I-1501J0D01*
G01Y214490D01*
X820037D01*
G03X819989Y214360I152J-130D01*
G01Y214096D01*
G03X820037Y213966I200J0D01*
G01X820038Y213965D01*
G02Y211991I-1131J-987D01*
G01Y211990D01*
X820037D01*
G03X819989Y211860I152J-130D01*
G01Y211596D01*
G03X820037Y211466I200J0D01*
G01X820038Y211465D01*
G02Y209491I-1131J-987D01*
G01Y209490D01*
X820037D01*
G03X819989Y209360I152J-130D01*
G01Y209096D01*
G03X820037Y208966I200J0D01*
G01X820038Y208965D01*
G02X820408Y207978I-1131J-987D01*
G02X817404I-1502J0D01*
G02X817774Y208965I1501J0D01*
G01Y208966D01*
X817775D01*
G03X817823Y209096I-152J130D01*
G01Y209360D01*
G03X817775Y209490I-200J0D01*
G01X817774Y209491D01*
G02Y211465I1131J987D01*
G01Y211466D01*
X817775D01*
G03X817823Y211596I-152J130D01*
G01Y211860D01*
G03X817775Y211990I-200J0D01*
G01X817774Y211991D01*
G02Y213965I1131J987D01*
G01Y213966D01*
X817775D01*
G03X817823Y214096I-152J130D01*
G01Y214360D01*
G03X817775Y214490I-200J0D01*
G01X817774Y214491D01*
G02X817404Y215478I1131J987D01*
G37*
G36*
G01X967404D02*
G02X970408I1502J0D01*
G02X970038Y214491I-1501J0D01*
G01Y214490D01*
X970037D01*
G03X969989Y214360I152J-130D01*
G01Y214096D01*
G03X970037Y213966I200J0D01*
G01X970038Y213965D01*
G02Y211991I-1131J-987D01*
G01Y211990D01*
X970037D01*
G03X969989Y211860I152J-130D01*
G01Y211596D01*
G03X970037Y211466I200J0D01*
G01X970038Y211465D01*
G02Y209491I-1131J-987D01*
G01Y209490D01*
X970037D01*
G03X969989Y209360I152J-130D01*
G01Y209096D01*
G03X970037Y208966I200J0D01*
G01X970038Y208965D01*
G02X970408Y207978I-1131J-987D01*
G02X967404I-1502J0D01*
G02X967774Y208965I1501J0D01*
G01Y208966D01*
X967775D01*
G03X967823Y209096I-152J130D01*
G01Y209360D01*
G03X967775Y209490I-200J0D01*
G01X967774Y209491D01*
G02Y211465I1131J987D01*
G01Y211466D01*
X967775D01*
G03X967823Y211596I-152J130D01*
G01Y211860D01*
G03X967775Y211990I-200J0D01*
G01X967774Y211991D01*
G02Y213965I1131J987D01*
G01Y213966D01*
X967775D01*
G03X967823Y214096I-152J130D01*
G01Y214360D01*
G03X967775Y214490I-200J0D01*
G01X967774Y214491D01*
G02X967404Y215478I1131J987D01*
G37*
G36*
G01X1069766D02*
G02X1072770I1502J0D01*
G02X1072400Y214491I-1501J0D01*
G01Y214490D01*
X1072399D01*
G03X1072351Y214360I152J-130D01*
G01Y214096D01*
G03X1072399Y213966I200J0D01*
G01X1072400Y213965D01*
G02Y211991I-1131J-987D01*
G01Y211990D01*
X1072399D01*
G03X1072351Y211860I152J-130D01*
G01Y211596D01*
G03X1072399Y211466I200J0D01*
G01X1072400Y211465D01*
G02Y209491I-1131J-987D01*
G01Y209490D01*
X1072399D01*
G03X1072351Y209360I152J-130D01*
G01Y209096D01*
G03X1072399Y208966I200J0D01*
G01X1072400Y208965D01*
G02X1072770Y207978I-1131J-987D01*
G02X1069766I-1502J0D01*
G02X1070136Y208965I1501J0D01*
G01Y208966D01*
X1070137D01*
G03X1070185Y209096I-152J130D01*
G01Y209360D01*
G03X1070137Y209490I-200J0D01*
G01X1070136Y209491D01*
G02Y211465I1131J987D01*
G01Y211466D01*
X1070137D01*
G03X1070185Y211596I-152J130D01*
G01Y211860D01*
G03X1070137Y211990I-200J0D01*
G01X1070136Y211991D01*
G02Y213965I1131J987D01*
G01Y213966D01*
X1070137D01*
G03X1070185Y214096I-152J130D01*
G01Y214360D01*
G03X1070137Y214490I-200J0D01*
G01X1070136Y214491D01*
G02X1069766Y215478I1131J987D01*
G37*
G36*
G01X1172128D02*
G02X1175132I1502J0D01*
G02X1174762Y214491I-1501J0D01*
G01Y214490D01*
X1174761D01*
G03X1174713Y214360I152J-130D01*
G01Y214096D01*
G03X1174761Y213966I200J0D01*
G01X1174762Y213965D01*
G02Y211991I-1131J-987D01*
G01Y211990D01*
X1174761D01*
G03X1174713Y211860I152J-130D01*
G01Y211596D01*
G03X1174761Y211466I200J0D01*
G01X1174762Y211465D01*
G02Y209491I-1131J-987D01*
G01Y209490D01*
X1174761D01*
G03X1174713Y209360I152J-130D01*
G01Y209096D01*
G03X1174761Y208966I200J0D01*
G01X1174762Y208965D01*
G02X1175132Y207978I-1131J-987D01*
G02X1172128I-1502J0D01*
G02X1172498Y208965I1501J0D01*
G01Y208966D01*
X1172499D01*
G03X1172547Y209096I-152J130D01*
G01Y209360D01*
G03X1172499Y209490I-200J0D01*
G01X1172498Y209491D01*
G02Y211465I1131J987D01*
G01Y211466D01*
X1172499D01*
G03X1172547Y211596I-152J130D01*
G01Y211860D01*
G03X1172499Y211990I-200J0D01*
G01X1172498Y211991D01*
G02Y213965I1131J987D01*
G01Y213966D01*
X1172499D01*
G03X1172547Y214096I-152J130D01*
G01Y214360D01*
G03X1172499Y214490I-200J0D01*
G01X1172498Y214491D01*
G02X1172128Y215478I1131J987D01*
G37*
G36*
G01X1274490D02*
G02X1277494I1502J0D01*
G02X1277124Y214491I-1501J0D01*
G01Y214490D01*
X1277123D01*
G03X1277075Y214360I152J-130D01*
G01Y214096D01*
G03X1277123Y213966I200J0D01*
G01X1277124Y213965D01*
G02Y211991I-1131J-987D01*
G01Y211990D01*
X1277123D01*
G03X1277075Y211860I152J-130D01*
G01Y211596D01*
G03X1277123Y211466I200J0D01*
G01X1277124Y211465D01*
G02Y209491I-1131J-987D01*
G01Y209490D01*
X1277123D01*
G03X1277075Y209360I152J-130D01*
G01Y209096D01*
G03X1277123Y208966I200J0D01*
G01X1277124Y208965D01*
G02X1277494Y207978I-1131J-987D01*
G02X1274490I-1502J0D01*
G02X1274860Y208965I1501J0D01*
G01Y208966D01*
X1274861D01*
G03X1274909Y209096I-152J130D01*
G01Y209360D01*
G03X1274861Y209490I-200J0D01*
G01X1274860Y209491D01*
G02Y211465I1131J987D01*
G01Y211466D01*
X1274861D01*
G03X1274909Y211596I-152J130D01*
G01Y211860D01*
G03X1274861Y211990I-200J0D01*
G01X1274860Y211991D01*
G02Y213965I1131J987D01*
G01Y213966D01*
X1274861D01*
G03X1274909Y214096I-152J130D01*
G01Y214360D01*
G03X1274861Y214490I-200J0D01*
G01X1274860Y214491D01*
G02X1274490Y215478I1131J987D01*
G37*
G36*
G01X1424491D02*
G02X1427495I1502J0D01*
G02X1427125Y214491I-1501J0D01*
G01Y214490D01*
X1427124D01*
G03X1427076Y214360I152J-130D01*
G01Y214096D01*
G03X1427124Y213966I200J0D01*
G01X1427125Y213965D01*
G02Y211991I-1131J-987D01*
G01Y211990D01*
X1427124D01*
G03X1427076Y211860I152J-130D01*
G01Y211596D01*
G03X1427124Y211466I200J0D01*
G01X1427125Y211465D01*
G02Y209491I-1131J-987D01*
G01Y209490D01*
X1427124D01*
G03X1427076Y209360I152J-130D01*
G01Y209096D01*
G03X1427124Y208966I200J0D01*
G01X1427125Y208965D01*
G02X1427495Y207978I-1131J-987D01*
G02X1424491I-1502J0D01*
G02X1424861Y208965I1501J0D01*
G01Y208966D01*
X1424862D01*
G03X1424910Y209096I-152J130D01*
G01Y209360D01*
G03X1424862Y209490I-200J0D01*
G01X1424861Y209491D01*
G02Y211465I1131J987D01*
G01Y211466D01*
X1424862D01*
G03X1424910Y211596I-152J130D01*
G01Y211860D01*
G03X1424862Y211990I-200J0D01*
G01X1424861Y211991D01*
G02Y213965I1131J987D01*
G01Y213966D01*
X1424862D01*
G03X1424910Y214096I-152J130D01*
G01Y214360D01*
G03X1424862Y214490I-200J0D01*
G01X1424861Y214491D01*
G02X1424491Y215478I1131J987D01*
G37*
G36*
G01X1526853D02*
G02X1529857I1502J0D01*
G02X1529487Y214491I-1501J0D01*
G01Y214490D01*
X1529486D01*
G03X1529438Y214360I152J-130D01*
G01Y214096D01*
G03X1529486Y213966I200J0D01*
G01X1529487Y213965D01*
G02Y211991I-1131J-987D01*
G01Y211990D01*
X1529486D01*
G03X1529438Y211860I152J-130D01*
G01Y211596D01*
G03X1529486Y211466I200J0D01*
G01X1529487Y211465D01*
G02Y209491I-1131J-987D01*
G01Y209490D01*
X1529486D01*
G03X1529438Y209360I152J-130D01*
G01Y209096D01*
G03X1529486Y208966I200J0D01*
G01X1529487Y208965D01*
G02X1529857Y207978I-1131J-987D01*
G02X1526853I-1502J0D01*
G02X1527223Y208965I1501J0D01*
G01Y208966D01*
X1527224D01*
G03X1527272Y209096I-152J130D01*
G01Y209360D01*
G03X1527224Y209490I-200J0D01*
G01X1527223Y209491D01*
G02Y211465I1131J987D01*
G01Y211466D01*
X1527224D01*
G03X1527272Y211596I-152J130D01*
G01Y211860D01*
G03X1527224Y211990I-200J0D01*
G01X1527223Y211991D01*
G02Y213965I1131J987D01*
G01Y213966D01*
X1527224D01*
G03X1527272Y214096I-152J130D01*
G01Y214360D01*
G03X1527224Y214490I-200J0D01*
G01X1527223Y214491D01*
G02X1526853Y215478I1131J987D01*
G37*
G36*
G01X1629215D02*
G02X1632219I1502J0D01*
G02X1631849Y214491I-1501J0D01*
G01Y214490D01*
X1631848D01*
G03X1631800Y214360I152J-130D01*
G01Y214096D01*
G03X1631848Y213966I200J0D01*
G01X1631849Y213965D01*
G02Y211991I-1131J-987D01*
G01Y211990D01*
X1631848D01*
G03X1631800Y211860I152J-130D01*
G01Y211596D01*
G03X1631848Y211466I200J0D01*
G01X1631849Y211465D01*
G02Y209491I-1131J-987D01*
G01Y209490D01*
X1631848D01*
G03X1631800Y209360I152J-130D01*
G01Y209096D01*
G03X1631848Y208966I200J0D01*
G01X1631849Y208965D01*
G02X1632219Y207978I-1131J-987D01*
G02X1629215I-1502J0D01*
G02X1629585Y208965I1501J0D01*
G01Y208966D01*
X1629586D01*
G03X1629634Y209096I-152J130D01*
G01Y209360D01*
G03X1629586Y209490I-200J0D01*
G01X1629585Y209491D01*
G02Y211465I1131J987D01*
G01Y211466D01*
X1629586D01*
G03X1629634Y211596I-152J130D01*
G01Y211860D01*
G03X1629586Y211990I-200J0D01*
G01X1629585Y211991D01*
G02Y213965I1131J987D01*
G01Y213966D01*
X1629586D01*
G03X1629634Y214096I-152J130D01*
G01Y214360D01*
G03X1629586Y214490I-200J0D01*
G01X1629585Y214491D01*
G02X1629215Y215478I1131J987D01*
G37*
G36*
G01X1731577D02*
G02X1734581I1502J0D01*
G02X1734211Y214491I-1501J0D01*
G01Y214490D01*
X1734210D01*
G03X1734162Y214360I152J-130D01*
G01Y214096D01*
G03X1734210Y213966I200J0D01*
G01X1734211Y213965D01*
G02Y211991I-1131J-987D01*
G01Y211990D01*
X1734210D01*
G03X1734162Y211860I152J-130D01*
G01Y211596D01*
G03X1734210Y211466I200J0D01*
G01X1734211Y211465D01*
G02Y209491I-1131J-987D01*
G01Y209490D01*
X1734210D01*
G03X1734162Y209360I152J-130D01*
G01Y209096D01*
G03X1734210Y208966I200J0D01*
G01X1734211Y208965D01*
G02X1734581Y207978I-1131J-987D01*
G02X1731577I-1502J0D01*
G02X1731947Y208965I1501J0D01*
G01Y208966D01*
X1731948D01*
G03X1731996Y209096I-152J130D01*
G01Y209360D01*
G03X1731948Y209490I-200J0D01*
G01X1731947Y209491D01*
G02Y211465I1131J987D01*
G01Y211466D01*
X1731948D01*
G03X1731996Y211596I-152J130D01*
G01Y211860D01*
G03X1731948Y211990I-200J0D01*
G01X1731947Y211991D01*
G02Y213965I1131J987D01*
G01Y213966D01*
X1731948D01*
G03X1731996Y214096I-152J130D01*
G01Y214360D01*
G03X1731948Y214490I-200J0D01*
G01X1731947Y214491D01*
G02X1731577Y215478I1131J987D01*
G37*
G36*
G01X181382Y215632D02*
G02X184386I1502J0D01*
G02X184016Y214645I-1501J0D01*
G01Y214644D01*
X184015D01*
G03X183967Y214514I152J-130D01*
G01Y214250D01*
G03X184015Y214120I200J0D01*
G01X184016Y214119D01*
G02X184386Y213132I-1131J-987D01*
G02X181382I-1502J0D01*
G02X181752Y214119I1501J0D01*
G01Y214120D01*
X181753D01*
G03X181801Y214250I-152J130D01*
G01Y214514D01*
G03X181753Y214644I-200J0D01*
G01X181752Y214645D01*
G02X181382Y215632I1131J987D01*
G37*
G36*
G01X283744D02*
G02X286748I1502J0D01*
G02X286378Y214645I-1501J0D01*
G01Y214644D01*
X286377D01*
G03X286329Y214514I152J-130D01*
G01Y214250D01*
G03X286377Y214120I200J0D01*
G01X286378Y214119D01*
G02X286748Y213132I-1131J-987D01*
G02X283744I-1502J0D01*
G02X284114Y214119I1501J0D01*
G01Y214120D01*
X284115D01*
G03X284163Y214250I-152J130D01*
G01Y214514D01*
G03X284115Y214644I-200J0D01*
G01X284114Y214645D01*
G02X283744Y215632I1131J987D01*
G37*
G36*
G01X386106D02*
G02X389110I1502J0D01*
G02X388740Y214645I-1501J0D01*
G01Y214644D01*
X388739D01*
G03X388691Y214514I152J-130D01*
G01Y214250D01*
G03X388739Y214120I200J0D01*
G01X388740Y214119D01*
G02X389110Y213132I-1131J-987D01*
G02X386106I-1502J0D01*
G02X386476Y214119I1501J0D01*
G01Y214120D01*
X386477D01*
G03X386525Y214250I-152J130D01*
G01Y214514D01*
G03X386477Y214644I-200J0D01*
G01X386476Y214645D01*
G02X386106Y215632I1131J987D01*
G37*
G36*
G01X536107D02*
G02X539111I1502J0D01*
G02X538741Y214645I-1501J0D01*
G01Y214644D01*
X538740D01*
G03X538692Y214514I152J-130D01*
G01Y214250D01*
G03X538740Y214120I200J0D01*
G01X538741Y214119D01*
G02X539111Y213132I-1131J-987D01*
G02X536107I-1502J0D01*
G02X536477Y214119I1501J0D01*
G01Y214120D01*
X536478D01*
G03X536526Y214250I-152J130D01*
G01Y214514D01*
G03X536478Y214644I-200J0D01*
G01X536477Y214645D01*
G02X536107Y215632I1131J987D01*
G37*
G36*
G01X638469D02*
G02X641473I1502J0D01*
G02X641103Y214645I-1501J0D01*
G01Y214644D01*
X641102D01*
G03X641054Y214514I152J-130D01*
G01Y214250D01*
G03X641102Y214120I200J0D01*
G01X641103Y214119D01*
G02X641473Y213132I-1131J-987D01*
G02X638469I-1502J0D01*
G02X638839Y214119I1501J0D01*
G01Y214120D01*
X638840D01*
G03X638888Y214250I-152J130D01*
G01Y214514D01*
G03X638840Y214644I-200J0D01*
G01X638839Y214645D01*
G02X638469Y215632I1131J987D01*
G37*
G36*
G01X740831D02*
G02X743835I1502J0D01*
G02X743465Y214645I-1501J0D01*
G01Y214644D01*
X743464D01*
G03X743416Y214514I152J-130D01*
G01Y214250D01*
G03X743464Y214120I200J0D01*
G01X743465Y214119D01*
G02X743835Y213132I-1131J-987D01*
G02X740831I-1502J0D01*
G02X741201Y214119I1501J0D01*
G01Y214120D01*
X741202D01*
G03X741250Y214250I-152J130D01*
G01Y214514D01*
G03X741202Y214644I-200J0D01*
G01X741201Y214645D01*
G02X740831Y215632I1131J987D01*
G37*
G36*
G01X843193D02*
G02X846197I1502J0D01*
G02X845827Y214645I-1501J0D01*
G01Y214644D01*
X845826D01*
G03X845778Y214514I152J-130D01*
G01Y214250D01*
G03X845826Y214120I200J0D01*
G01X845827Y214119D01*
G02X846197Y213132I-1131J-987D01*
G02X843193I-1502J0D01*
G02X843563Y214119I1501J0D01*
G01Y214120D01*
X843564D01*
G03X843612Y214250I-152J130D01*
G01Y214514D01*
G03X843564Y214644I-200J0D01*
G01X843563Y214645D01*
G02X843193Y215632I1131J987D01*
G37*
G36*
G01X993193D02*
G02X996197I1502J0D01*
G02X995827Y214645I-1501J0D01*
G01Y214644D01*
X995826D01*
G03X995778Y214514I152J-130D01*
G01Y214250D01*
G03X995826Y214120I200J0D01*
G01X995827Y214119D01*
G02X996197Y213132I-1131J-987D01*
G02X993193I-1502J0D01*
G02X993563Y214119I1501J0D01*
G01Y214120D01*
X993564D01*
G03X993612Y214250I-152J130D01*
G01Y214514D01*
G03X993564Y214644I-200J0D01*
G01X993563Y214645D01*
G02X993193Y215632I1131J987D01*
G37*
G36*
G01X1095555D02*
G02X1098559I1502J0D01*
G02X1098189Y214645I-1501J0D01*
G01Y214644D01*
X1098188D01*
G03X1098140Y214514I152J-130D01*
G01Y214250D01*
G03X1098188Y214120I200J0D01*
G01X1098189Y214119D01*
G02X1098559Y213132I-1131J-987D01*
G02X1095555I-1502J0D01*
G02X1095925Y214119I1501J0D01*
G01Y214120D01*
X1095926D01*
G03X1095974Y214250I-152J130D01*
G01Y214514D01*
G03X1095926Y214644I-200J0D01*
G01X1095925Y214645D01*
G02X1095555Y215632I1131J987D01*
G37*
G36*
G01X1197917D02*
G02X1200921I1502J0D01*
G02X1200551Y214645I-1501J0D01*
G01Y214644D01*
X1200550D01*
G03X1200502Y214514I152J-130D01*
G01Y214250D01*
G03X1200550Y214120I200J0D01*
G01X1200551Y214119D01*
G02X1200921Y213132I-1131J-987D01*
G02X1197917I-1502J0D01*
G02X1198287Y214119I1501J0D01*
G01Y214120D01*
X1198288D01*
G03X1198336Y214250I-152J130D01*
G01Y214514D01*
G03X1198288Y214644I-200J0D01*
G01X1198287Y214645D01*
G02X1197917Y215632I1131J987D01*
G37*
G36*
G01X1300279D02*
G02X1303283I1502J0D01*
G02X1302913Y214645I-1501J0D01*
G01Y214644D01*
X1302912D01*
G03X1302864Y214514I152J-130D01*
G01Y214250D01*
G03X1302912Y214120I200J0D01*
G01X1302913Y214119D01*
G02X1303283Y213132I-1131J-987D01*
G02X1300279I-1502J0D01*
G02X1300649Y214119I1501J0D01*
G01Y214120D01*
X1300650D01*
G03X1300698Y214250I-152J130D01*
G01Y214514D01*
G03X1300650Y214644I-200J0D01*
G01X1300649Y214645D01*
G02X1300279Y215632I1131J987D01*
G37*
G36*
G01X1450280D02*
G02X1453284I1502J0D01*
G02X1452914Y214645I-1501J0D01*
G01Y214644D01*
X1452913D01*
G03X1452865Y214514I152J-130D01*
G01Y214250D01*
G03X1452913Y214120I200J0D01*
G01X1452914Y214119D01*
G02X1453284Y213132I-1131J-987D01*
G02X1450280I-1502J0D01*
G02X1450650Y214119I1501J0D01*
G01Y214120D01*
X1450651D01*
G03X1450699Y214250I-152J130D01*
G01Y214514D01*
G03X1450651Y214644I-200J0D01*
G01X1450650Y214645D01*
G02X1450280Y215632I1131J987D01*
G37*
G36*
G01X1552642D02*
G02X1555646I1502J0D01*
G02X1555276Y214645I-1501J0D01*
G01Y214644D01*
X1555275D01*
G03X1555227Y214514I152J-130D01*
G01Y214250D01*
G03X1555275Y214120I200J0D01*
G01X1555276Y214119D01*
G02X1555646Y213132I-1131J-987D01*
G02X1552642I-1502J0D01*
G02X1553012Y214119I1501J0D01*
G01Y214120D01*
X1553013D01*
G03X1553061Y214250I-152J130D01*
G01Y214514D01*
G03X1553013Y214644I-200J0D01*
G01X1553012Y214645D01*
G02X1552642Y215632I1131J987D01*
G37*
G36*
G01X1655004D02*
G02X1658008I1502J0D01*
G02X1657638Y214645I-1501J0D01*
G01Y214644D01*
X1657637D01*
G03X1657589Y214514I152J-130D01*
G01Y214250D01*
G03X1657637Y214120I200J0D01*
G01X1657638Y214119D01*
G02X1658008Y213132I-1131J-987D01*
G02X1655004I-1502J0D01*
G02X1655374Y214119I1501J0D01*
G01Y214120D01*
X1655375D01*
G03X1655423Y214250I-152J130D01*
G01Y214514D01*
G03X1655375Y214644I-200J0D01*
G01X1655374Y214645D01*
G02X1655004Y215632I1131J987D01*
G37*
G36*
G01X1757366D02*
G02X1760370I1502J0D01*
G02X1760000Y214645I-1501J0D01*
G01Y214644D01*
X1759999D01*
G03X1759951Y214514I152J-130D01*
G01Y214250D01*
G03X1759999Y214120I200J0D01*
G01X1760000Y214119D01*
G02X1760370Y213132I-1131J-987D01*
G02X1757366I-1502J0D01*
G02X1757736Y214119I1501J0D01*
G01Y214120D01*
X1757737D01*
G03X1757785Y214250I-152J130D01*
G01Y214514D01*
G03X1757737Y214644I-200J0D01*
G01X1757736Y214645D01*
G02X1757366Y215632I1131J987D01*
G37*
G36*
G01X166049Y215713D02*
G02X169053I1502J0D01*
G02X168683Y214726I-1501J0D01*
G01Y214725D01*
X168682D01*
G03X168634Y214595I152J-130D01*
G01Y214331D01*
G03X168682Y214201I200J0D01*
G01X168683Y214200D01*
G02Y212226I-1131J-987D01*
G01Y212225D01*
X168682D01*
G03X168634Y212095I152J-130D01*
G01Y211831D01*
G03X168682Y211701I200J0D01*
G01X168683Y211700D01*
G02Y209726I-1131J-987D01*
G01Y209725D01*
X168682D01*
G03X168634Y209595I152J-130D01*
G01Y209331D01*
G03X168682Y209201I200J0D01*
G01X168683Y209200D01*
G02X169053Y208213I-1131J-987D01*
G02X166049I-1502J0D01*
G02X166419Y209200I1501J0D01*
G01Y209201D01*
X166420D01*
G03X166468Y209331I-152J130D01*
G01Y209595D01*
G03X166420Y209725I-200J0D01*
G01X166419Y209726D01*
G02Y211700I1131J987D01*
G01Y211701D01*
X166420D01*
G03X166468Y211831I-152J130D01*
G01Y212095D01*
G03X166420Y212225I-200J0D01*
G01X166419Y212226D01*
G02Y214200I1131J987D01*
G01Y214201D01*
X166420D01*
G03X166468Y214331I-152J130D01*
G01Y214595D01*
G03X166420Y214725I-200J0D01*
G01X166419Y214726D01*
G02X166049Y215713I1131J987D01*
G37*
G36*
G01X268411D02*
G02X271415I1502J0D01*
G02X271045Y214726I-1501J0D01*
G01Y214725D01*
X271044D01*
G03X270996Y214595I152J-130D01*
G01Y214331D01*
G03X271044Y214201I200J0D01*
G01X271045Y214200D01*
G02Y212226I-1131J-987D01*
G01Y212225D01*
X271044D01*
G03X270996Y212095I152J-130D01*
G01Y211831D01*
G03X271044Y211701I200J0D01*
G01X271045Y211700D01*
G02Y209726I-1131J-987D01*
G01Y209725D01*
X271044D01*
G03X270996Y209595I152J-130D01*
G01Y209331D01*
G03X271044Y209201I200J0D01*
G01X271045Y209200D01*
G02X271415Y208213I-1131J-987D01*
G02X268411I-1502J0D01*
G02X268781Y209200I1501J0D01*
G01Y209201D01*
X268782D01*
G03X268830Y209331I-152J130D01*
G01Y209595D01*
G03X268782Y209725I-200J0D01*
G01X268781Y209726D01*
G02Y211700I1131J987D01*
G01Y211701D01*
X268782D01*
G03X268830Y211831I-152J130D01*
G01Y212095D01*
G03X268782Y212225I-200J0D01*
G01X268781Y212226D01*
G02Y214200I1131J987D01*
G01Y214201D01*
X268782D01*
G03X268830Y214331I-152J130D01*
G01Y214595D01*
G03X268782Y214725I-200J0D01*
G01X268781Y214726D01*
G02X268411Y215713I1131J987D01*
G37*
G36*
G01X370773D02*
G02X373777I1502J0D01*
G02X373407Y214726I-1501J0D01*
G01Y214725D01*
X373406D01*
G03X373358Y214595I152J-130D01*
G01Y214331D01*
G03X373406Y214201I200J0D01*
G01X373407Y214200D01*
G02Y212226I-1131J-987D01*
G01Y212225D01*
X373406D01*
G03X373358Y212095I152J-130D01*
G01Y211831D01*
G03X373406Y211701I200J0D01*
G01X373407Y211700D01*
G02Y209726I-1131J-987D01*
G01Y209725D01*
X373406D01*
G03X373358Y209595I152J-130D01*
G01Y209331D01*
G03X373406Y209201I200J0D01*
G01X373407Y209200D01*
G02X373777Y208213I-1131J-987D01*
G02X370773I-1502J0D01*
G02X371143Y209200I1501J0D01*
G01Y209201D01*
X371144D01*
G03X371192Y209331I-152J130D01*
G01Y209595D01*
G03X371144Y209725I-200J0D01*
G01X371143Y209726D01*
G02Y211700I1131J987D01*
G01Y211701D01*
X371144D01*
G03X371192Y211831I-152J130D01*
G01Y212095D01*
G03X371144Y212225I-200J0D01*
G01X371143Y212226D01*
G02Y214200I1131J987D01*
G01Y214201D01*
X371144D01*
G03X371192Y214331I-152J130D01*
G01Y214595D01*
G03X371144Y214725I-200J0D01*
G01X371143Y214726D01*
G02X370773Y215713I1131J987D01*
G37*
G36*
G01X520774D02*
G02X523778I1502J0D01*
G02X523408Y214726I-1501J0D01*
G01Y214725D01*
X523407D01*
G03X523359Y214595I152J-130D01*
G01Y214331D01*
G03X523407Y214201I200J0D01*
G01X523408Y214200D01*
G02Y212226I-1131J-987D01*
G01Y212225D01*
X523407D01*
G03X523359Y212095I152J-130D01*
G01Y211831D01*
G03X523407Y211701I200J0D01*
G01X523408Y211700D01*
G02Y209726I-1131J-987D01*
G01Y209725D01*
X523407D01*
G03X523359Y209595I152J-130D01*
G01Y209331D01*
G03X523407Y209201I200J0D01*
G01X523408Y209200D01*
G02X523778Y208213I-1131J-987D01*
G02X520774I-1502J0D01*
G02X521144Y209200I1501J0D01*
G01Y209201D01*
X521145D01*
G03X521193Y209331I-152J130D01*
G01Y209595D01*
G03X521145Y209725I-200J0D01*
G01X521144Y209726D01*
G02Y211700I1131J987D01*
G01Y211701D01*
X521145D01*
G03X521193Y211831I-152J130D01*
G01Y212095D01*
G03X521145Y212225I-200J0D01*
G01X521144Y212226D01*
G02Y214200I1131J987D01*
G01Y214201D01*
X521145D01*
G03X521193Y214331I-152J130D01*
G01Y214595D01*
G03X521145Y214725I-200J0D01*
G01X521144Y214726D01*
G02X520774Y215713I1131J987D01*
G37*
G36*
G01X623136D02*
G02X626140I1502J0D01*
G02X625770Y214726I-1501J0D01*
G01Y214725D01*
X625769D01*
G03X625721Y214595I152J-130D01*
G01Y214331D01*
G03X625769Y214201I200J0D01*
G01X625770Y214200D01*
G02Y212226I-1131J-987D01*
G01Y212225D01*
X625769D01*
G03X625721Y212095I152J-130D01*
G01Y211831D01*
G03X625769Y211701I200J0D01*
G01X625770Y211700D01*
G02Y209726I-1131J-987D01*
G01Y209725D01*
X625769D01*
G03X625721Y209595I152J-130D01*
G01Y209331D01*
G03X625769Y209201I200J0D01*
G01X625770Y209200D01*
G02X626140Y208213I-1131J-987D01*
G02X623136I-1502J0D01*
G02X623506Y209200I1501J0D01*
G01Y209201D01*
X623507D01*
G03X623555Y209331I-152J130D01*
G01Y209595D01*
G03X623507Y209725I-200J0D01*
G01X623506Y209726D01*
G02Y211700I1131J987D01*
G01Y211701D01*
X623507D01*
G03X623555Y211831I-152J130D01*
G01Y212095D01*
G03X623507Y212225I-200J0D01*
G01X623506Y212226D01*
G02Y214200I1131J987D01*
G01Y214201D01*
X623507D01*
G03X623555Y214331I-152J130D01*
G01Y214595D01*
G03X623507Y214725I-200J0D01*
G01X623506Y214726D01*
G02X623136Y215713I1131J987D01*
G37*
G36*
G01X725498D02*
G02X728502I1502J0D01*
G02X728132Y214726I-1501J0D01*
G01Y214725D01*
X728131D01*
G03X728083Y214595I152J-130D01*
G01Y214331D01*
G03X728131Y214201I200J0D01*
G01X728132Y214200D01*
G02Y212226I-1131J-987D01*
G01Y212225D01*
X728131D01*
G03X728083Y212095I152J-130D01*
G01Y211831D01*
G03X728131Y211701I200J0D01*
G01X728132Y211700D01*
G02Y209726I-1131J-987D01*
G01Y209725D01*
X728131D01*
G03X728083Y209595I152J-130D01*
G01Y209331D01*
G03X728131Y209201I200J0D01*
G01X728132Y209200D01*
G02X728502Y208213I-1131J-987D01*
G02X725498I-1502J0D01*
G02X725868Y209200I1501J0D01*
G01Y209201D01*
X725869D01*
G03X725917Y209331I-152J130D01*
G01Y209595D01*
G03X725869Y209725I-200J0D01*
G01X725868Y209726D01*
G02Y211700I1131J987D01*
G01Y211701D01*
X725869D01*
G03X725917Y211831I-152J130D01*
G01Y212095D01*
G03X725869Y212225I-200J0D01*
G01X725868Y212226D01*
G02Y214200I1131J987D01*
G01Y214201D01*
X725869D01*
G03X725917Y214331I-152J130D01*
G01Y214595D01*
G03X725869Y214725I-200J0D01*
G01X725868Y214726D01*
G02X725498Y215713I1131J987D01*
G37*
G36*
G01X827860D02*
G02X830864I1502J0D01*
G02X830494Y214726I-1501J0D01*
G01Y214725D01*
X830493D01*
G03X830445Y214595I152J-130D01*
G01Y214331D01*
G03X830493Y214201I200J0D01*
G01X830494Y214200D01*
G02Y212226I-1131J-987D01*
G01Y212225D01*
X830493D01*
G03X830445Y212095I152J-130D01*
G01Y211831D01*
G03X830493Y211701I200J0D01*
G01X830494Y211700D01*
G02Y209726I-1131J-987D01*
G01Y209725D01*
X830493D01*
G03X830445Y209595I152J-130D01*
G01Y209331D01*
G03X830493Y209201I200J0D01*
G01X830494Y209200D01*
G02X830864Y208213I-1131J-987D01*
G02X827860I-1502J0D01*
G02X828230Y209200I1501J0D01*
G01Y209201D01*
X828231D01*
G03X828279Y209331I-152J130D01*
G01Y209595D01*
G03X828231Y209725I-200J0D01*
G01X828230Y209726D01*
G02Y211700I1131J987D01*
G01Y211701D01*
X828231D01*
G03X828279Y211831I-152J130D01*
G01Y212095D01*
G03X828231Y212225I-200J0D01*
G01X828230Y212226D01*
G02Y214200I1131J987D01*
G01Y214201D01*
X828231D01*
G03X828279Y214331I-152J130D01*
G01Y214595D01*
G03X828231Y214725I-200J0D01*
G01X828230Y214726D01*
G02X827860Y215713I1131J987D01*
G37*
G36*
G01X977860D02*
G02X980864I1502J0D01*
G02X980494Y214726I-1501J0D01*
G01Y214725D01*
X980493D01*
G03X980445Y214595I152J-130D01*
G01Y214331D01*
G03X980493Y214201I200J0D01*
G01X980494Y214200D01*
G02Y212226I-1131J-987D01*
G01Y212225D01*
X980493D01*
G03X980445Y212095I152J-130D01*
G01Y211831D01*
G03X980493Y211701I200J0D01*
G01X980494Y211700D01*
G02Y209726I-1131J-987D01*
G01Y209725D01*
X980493D01*
G03X980445Y209595I152J-130D01*
G01Y209331D01*
G03X980493Y209201I200J0D01*
G01X980494Y209200D01*
G02X980864Y208213I-1131J-987D01*
G02X977860I-1502J0D01*
G02X978230Y209200I1501J0D01*
G01Y209201D01*
X978231D01*
G03X978279Y209331I-152J130D01*
G01Y209595D01*
G03X978231Y209725I-200J0D01*
G01X978230Y209726D01*
G02Y211700I1131J987D01*
G01Y211701D01*
X978231D01*
G03X978279Y211831I-152J130D01*
G01Y212095D01*
G03X978231Y212225I-200J0D01*
G01X978230Y212226D01*
G02Y214200I1131J987D01*
G01Y214201D01*
X978231D01*
G03X978279Y214331I-152J130D01*
G01Y214595D01*
G03X978231Y214725I-200J0D01*
G01X978230Y214726D01*
G02X977860Y215713I1131J987D01*
G37*
G36*
G01X1080222D02*
G02X1083226I1502J0D01*
G02X1082856Y214726I-1501J0D01*
G01Y214725D01*
X1082855D01*
G03X1082807Y214595I152J-130D01*
G01Y214331D01*
G03X1082855Y214201I200J0D01*
G01X1082856Y214200D01*
G02Y212226I-1131J-987D01*
G01Y212225D01*
X1082855D01*
G03X1082807Y212095I152J-130D01*
G01Y211831D01*
G03X1082855Y211701I200J0D01*
G01X1082856Y211700D01*
G02Y209726I-1131J-987D01*
G01Y209725D01*
X1082855D01*
G03X1082807Y209595I152J-130D01*
G01Y209331D01*
G03X1082855Y209201I200J0D01*
G01X1082856Y209200D01*
G02X1083226Y208213I-1131J-987D01*
G02X1080222I-1502J0D01*
G02X1080592Y209200I1501J0D01*
G01Y209201D01*
X1080593D01*
G03X1080641Y209331I-152J130D01*
G01Y209595D01*
G03X1080593Y209725I-200J0D01*
G01X1080592Y209726D01*
G02Y211700I1131J987D01*
G01Y211701D01*
X1080593D01*
G03X1080641Y211831I-152J130D01*
G01Y212095D01*
G03X1080593Y212225I-200J0D01*
G01X1080592Y212226D01*
G02Y214200I1131J987D01*
G01Y214201D01*
X1080593D01*
G03X1080641Y214331I-152J130D01*
G01Y214595D01*
G03X1080593Y214725I-200J0D01*
G01X1080592Y214726D01*
G02X1080222Y215713I1131J987D01*
G37*
G36*
G01X1182584D02*
G02X1185588I1502J0D01*
G02X1185218Y214726I-1501J0D01*
G01Y214725D01*
X1185217D01*
G03X1185169Y214595I152J-130D01*
G01Y214331D01*
G03X1185217Y214201I200J0D01*
G01X1185218Y214200D01*
G02Y212226I-1131J-987D01*
G01Y212225D01*
X1185217D01*
G03X1185169Y212095I152J-130D01*
G01Y211831D01*
G03X1185217Y211701I200J0D01*
G01X1185218Y211700D01*
G02Y209726I-1131J-987D01*
G01Y209725D01*
X1185217D01*
G03X1185169Y209595I152J-130D01*
G01Y209331D01*
G03X1185217Y209201I200J0D01*
G01X1185218Y209200D01*
G02X1185588Y208213I-1131J-987D01*
G02X1182584I-1502J0D01*
G02X1182954Y209200I1501J0D01*
G01Y209201D01*
X1182955D01*
G03X1183003Y209331I-152J130D01*
G01Y209595D01*
G03X1182955Y209725I-200J0D01*
G01X1182954Y209726D01*
G02Y211700I1131J987D01*
G01Y211701D01*
X1182955D01*
G03X1183003Y211831I-152J130D01*
G01Y212095D01*
G03X1182955Y212225I-200J0D01*
G01X1182954Y212226D01*
G02Y214200I1131J987D01*
G01Y214201D01*
X1182955D01*
G03X1183003Y214331I-152J130D01*
G01Y214595D01*
G03X1182955Y214725I-200J0D01*
G01X1182954Y214726D01*
G02X1182584Y215713I1131J987D01*
G37*
G36*
G01X1284946D02*
G02X1287950I1502J0D01*
G02X1287580Y214726I-1501J0D01*
G01Y214725D01*
X1287579D01*
G03X1287531Y214595I152J-130D01*
G01Y214331D01*
G03X1287579Y214201I200J0D01*
G01X1287580Y214200D01*
G02Y212226I-1131J-987D01*
G01Y212225D01*
X1287579D01*
G03X1287531Y212095I152J-130D01*
G01Y211831D01*
G03X1287579Y211701I200J0D01*
G01X1287580Y211700D01*
G02Y209726I-1131J-987D01*
G01Y209725D01*
X1287579D01*
G03X1287531Y209595I152J-130D01*
G01Y209331D01*
G03X1287579Y209201I200J0D01*
G01X1287580Y209200D01*
G02X1287950Y208213I-1131J-987D01*
G02X1284946I-1502J0D01*
G02X1285316Y209200I1501J0D01*
G01Y209201D01*
X1285317D01*
G03X1285365Y209331I-152J130D01*
G01Y209595D01*
G03X1285317Y209725I-200J0D01*
G01X1285316Y209726D01*
G02Y211700I1131J987D01*
G01Y211701D01*
X1285317D01*
G03X1285365Y211831I-152J130D01*
G01Y212095D01*
G03X1285317Y212225I-200J0D01*
G01X1285316Y212226D01*
G02Y214200I1131J987D01*
G01Y214201D01*
X1285317D01*
G03X1285365Y214331I-152J130D01*
G01Y214595D01*
G03X1285317Y214725I-200J0D01*
G01X1285316Y214726D01*
G02X1284946Y215713I1131J987D01*
G37*
G36*
G01X1434947D02*
G02X1437951I1502J0D01*
G02X1437581Y214726I-1501J0D01*
G01Y214725D01*
X1437580D01*
G03X1437532Y214595I152J-130D01*
G01Y214331D01*
G03X1437580Y214201I200J0D01*
G01X1437581Y214200D01*
G02Y212226I-1131J-987D01*
G01Y212225D01*
X1437580D01*
G03X1437532Y212095I152J-130D01*
G01Y211831D01*
G03X1437580Y211701I200J0D01*
G01X1437581Y211700D01*
G02Y209726I-1131J-987D01*
G01Y209725D01*
X1437580D01*
G03X1437532Y209595I152J-130D01*
G01Y209331D01*
G03X1437580Y209201I200J0D01*
G01X1437581Y209200D01*
G02X1437951Y208213I-1131J-987D01*
G02X1434947I-1502J0D01*
G02X1435317Y209200I1501J0D01*
G01Y209201D01*
X1435318D01*
G03X1435366Y209331I-152J130D01*
G01Y209595D01*
G03X1435318Y209725I-200J0D01*
G01X1435317Y209726D01*
G02Y211700I1131J987D01*
G01Y211701D01*
X1435318D01*
G03X1435366Y211831I-152J130D01*
G01Y212095D01*
G03X1435318Y212225I-200J0D01*
G01X1435317Y212226D01*
G02Y214200I1131J987D01*
G01Y214201D01*
X1435318D01*
G03X1435366Y214331I-152J130D01*
G01Y214595D01*
G03X1435318Y214725I-200J0D01*
G01X1435317Y214726D01*
G02X1434947Y215713I1131J987D01*
G37*
G36*
G01X1537309D02*
G02X1540313I1502J0D01*
G02X1539943Y214726I-1501J0D01*
G01Y214725D01*
X1539942D01*
G03X1539894Y214595I152J-130D01*
G01Y214331D01*
G03X1539942Y214201I200J0D01*
G01X1539943Y214200D01*
G02Y212226I-1131J-987D01*
G01Y212225D01*
X1539942D01*
G03X1539894Y212095I152J-130D01*
G01Y211831D01*
G03X1539942Y211701I200J0D01*
G01X1539943Y211700D01*
G02Y209726I-1131J-987D01*
G01Y209725D01*
X1539942D01*
G03X1539894Y209595I152J-130D01*
G01Y209331D01*
G03X1539942Y209201I200J0D01*
G01X1539943Y209200D01*
G02X1540313Y208213I-1131J-987D01*
G02X1537309I-1502J0D01*
G02X1537679Y209200I1501J0D01*
G01Y209201D01*
X1537680D01*
G03X1537728Y209331I-152J130D01*
G01Y209595D01*
G03X1537680Y209725I-200J0D01*
G01X1537679Y209726D01*
G02Y211700I1131J987D01*
G01Y211701D01*
X1537680D01*
G03X1537728Y211831I-152J130D01*
G01Y212095D01*
G03X1537680Y212225I-200J0D01*
G01X1537679Y212226D01*
G02Y214200I1131J987D01*
G01Y214201D01*
X1537680D01*
G03X1537728Y214331I-152J130D01*
G01Y214595D01*
G03X1537680Y214725I-200J0D01*
G01X1537679Y214726D01*
G02X1537309Y215713I1131J987D01*
G37*
G36*
G01X1639671D02*
G02X1642675I1502J0D01*
G02X1642305Y214726I-1501J0D01*
G01Y214725D01*
X1642304D01*
G03X1642256Y214595I152J-130D01*
G01Y214331D01*
G03X1642304Y214201I200J0D01*
G01X1642305Y214200D01*
G02Y212226I-1131J-987D01*
G01Y212225D01*
X1642304D01*
G03X1642256Y212095I152J-130D01*
G01Y211831D01*
G03X1642304Y211701I200J0D01*
G01X1642305Y211700D01*
G02Y209726I-1131J-987D01*
G01Y209725D01*
X1642304D01*
G03X1642256Y209595I152J-130D01*
G01Y209331D01*
G03X1642304Y209201I200J0D01*
G01X1642305Y209200D01*
G02X1642675Y208213I-1131J-987D01*
G02X1639671I-1502J0D01*
G02X1640041Y209200I1501J0D01*
G01Y209201D01*
X1640042D01*
G03X1640090Y209331I-152J130D01*
G01Y209595D01*
G03X1640042Y209725I-200J0D01*
G01X1640041Y209726D01*
G02Y211700I1131J987D01*
G01Y211701D01*
X1640042D01*
G03X1640090Y211831I-152J130D01*
G01Y212095D01*
G03X1640042Y212225I-200J0D01*
G01X1640041Y212226D01*
G02Y214200I1131J987D01*
G01Y214201D01*
X1640042D01*
G03X1640090Y214331I-152J130D01*
G01Y214595D01*
G03X1640042Y214725I-200J0D01*
G01X1640041Y214726D01*
G02X1639671Y215713I1131J987D01*
G37*
G36*
G01X1742033D02*
G02X1745037I1502J0D01*
G02X1744667Y214726I-1501J0D01*
G01Y214725D01*
X1744666D01*
G03X1744618Y214595I152J-130D01*
G01Y214331D01*
G03X1744666Y214201I200J0D01*
G01X1744667Y214200D01*
G02Y212226I-1131J-987D01*
G01Y212225D01*
X1744666D01*
G03X1744618Y212095I152J-130D01*
G01Y211831D01*
G03X1744666Y211701I200J0D01*
G01X1744667Y211700D01*
G02Y209726I-1131J-987D01*
G01Y209725D01*
X1744666D01*
G03X1744618Y209595I152J-130D01*
G01Y209331D01*
G03X1744666Y209201I200J0D01*
G01X1744667Y209200D01*
G02X1745037Y208213I-1131J-987D01*
G02X1742033I-1502J0D01*
G02X1742403Y209200I1501J0D01*
G01Y209201D01*
X1742404D01*
G03X1742452Y209331I-152J130D01*
G01Y209595D01*
G03X1742404Y209725I-200J0D01*
G01X1742403Y209726D01*
G02Y211700I1131J987D01*
G01Y211701D01*
X1742404D01*
G03X1742452Y211831I-152J130D01*
G01Y212095D01*
G03X1742404Y212225I-200J0D01*
G01X1742403Y212226D01*
G02Y214200I1131J987D01*
G01Y214201D01*
X1742404D01*
G03X1742452Y214331I-152J130D01*
G01Y214595D01*
G03X1742404Y214725I-200J0D01*
G01X1742403Y214726D01*
G02X1742033Y215713I1131J987D01*
G37*
G36*
G01X468893Y217133D02*
X468599D01*
G03X468452Y217068I1J-200D01*
G02X467346Y216583I-1106J1019D01*
G02Y219587I0J1502D01*
G02X468452Y219102I0J-1504D01*
G03X468599Y219037I148J135D01*
G01X468893D01*
G03X469040Y219102I-1J200D01*
G02X470146Y219587I1106J-1019D01*
G02Y216583I0J-1502D01*
G02X469040Y217068I0J1504D01*
G03X468893Y217133I-148J-135D01*
G37*
G36*
G01X673617D02*
X673323D01*
G03X673176Y217068I1J-200D01*
G02X672070Y216583I-1106J1019D01*
G02Y219587I0J1502D01*
G02X673176Y219102I0J-1504D01*
G03X673323Y219037I148J135D01*
G01X673617D01*
G03X673764Y219102I-1J200D01*
G02X674870Y219587I1106J-1019D01*
G02Y216583I0J-1502D01*
G02X673764Y217068I0J1504D01*
G03X673617Y217133I-148J-135D01*
G37*
G36*
G01X1383066D02*
X1382772D01*
G03X1382625Y217068I1J-200D01*
G02X1381519Y216583I-1106J1019D01*
G02Y219587I0J1502D01*
G02X1382625Y219102I0J-1504D01*
G03X1382772Y219037I148J135D01*
G01X1383066D01*
G03X1383213Y219102I-1J200D01*
G02X1384319Y219587I1106J-1019D01*
G02Y216583I0J-1502D01*
G02X1383213Y217068I0J1504D01*
G03X1383066Y217133I-148J-135D01*
G37*
G36*
G01X1485428D02*
X1485134D01*
G03X1484987Y217068I1J-200D01*
G02X1483881Y216583I-1106J1019D01*
G02Y219587I0J1502D01*
G02X1484987Y219102I0J-1504D01*
G03X1485134Y219037I148J135D01*
G01X1485428D01*
G03X1485575Y219102I-1J200D01*
G02X1486681Y219587I1106J-1019D01*
G02Y216583I0J-1502D01*
G02X1485575Y217068I0J1504D01*
G03X1485428Y217133I-148J-135D01*
G37*
G36*
G01X1587790D02*
X1587496D01*
G03X1587349Y217068I1J-200D01*
G02X1586243Y216583I-1106J1019D01*
G02Y219587I0J1502D01*
G02X1587349Y219102I0J-1504D01*
G03X1587496Y219037I148J135D01*
G01X1587790D01*
G03X1587937Y219102I-1J200D01*
G02X1589043Y219587I1106J-1019D01*
G02Y216583I0J-1502D01*
G02X1587937Y217068I0J1504D01*
G03X1587790Y217133I-148J-135D01*
G37*
G36*
G01X1690152D02*
X1689858D01*
G03X1689711Y217068I1J-200D01*
G02X1688605Y216583I-1106J1019D01*
G02Y219587I0J1502D01*
G02X1689711Y219102I0J-1504D01*
G03X1689858Y219037I148J135D01*
G01X1690152D01*
G03X1690299Y219102I-1J200D01*
G02X1691405Y219587I1106J-1019D01*
G02Y216583I0J-1502D01*
G02X1690299Y217068I0J1504D01*
G03X1690152Y217133I-148J-135D01*
G37*
G36*
G01X222794Y221970D02*
G02X225798I1502J0D01*
G02X225428Y220983I-1501J0D01*
G01Y220982D01*
X225427D01*
G03X225379Y220852I152J-130D01*
G01Y220588D01*
G03X225427Y220458I200J0D01*
G01X225428Y220457D01*
G02Y218483I-1131J-987D01*
G01Y218482D01*
X225427D01*
G03X225379Y218352I152J-130D01*
G01Y218088D01*
G03X225427Y217958I200J0D01*
G01X225428Y217957D01*
G02X225798Y216970I-1131J-987D01*
G02X224296Y215468I-1502J0D01*
G02X223441Y215735I0J1502D01*
G01X223407Y215758D01*
X223326Y215775D01*
X222959Y215695D01*
X222892Y215647D01*
X222871Y215612D01*
G02X221583Y214883I-1288J773D01*
G02Y217887I0J1502D01*
G02X222438Y217620I0J-1502D01*
G01X222472Y217597D01*
X222553Y217580D01*
X222920Y217660D01*
X222987Y217708D01*
X223008Y217743D01*
G02X223164Y217956I1285J-777D01*
G03X223165Y217958I-173J88D01*
G03X223213Y218088I-152J130D01*
G01Y218352D01*
G03X223165Y218482I-200J0D01*
G01X223164Y218483D01*
G02Y220457I1131J987D01*
G01Y220458D01*
X223165D01*
G03X223213Y220588I-152J130D01*
G01Y220852D01*
G03X223165Y220982I-200J0D01*
G01X223164Y220983D01*
G02X222794Y221970I1131J987D01*
G37*
G36*
G01X325156D02*
G02X328160I1502J0D01*
G02X327790Y220983I-1501J0D01*
G01Y220982D01*
X327789D01*
G03X327741Y220852I152J-130D01*
G01Y220588D01*
G03X327789Y220458I200J0D01*
G01X327790Y220457D01*
G02Y218483I-1131J-987D01*
G01Y218482D01*
X327789D01*
G03X327741Y218352I152J-130D01*
G01Y218088D01*
G03X327789Y217958I200J0D01*
G01X327790Y217957D01*
G02X328160Y216970I-1131J-987D01*
G02X326658Y215468I-1502J0D01*
G02X325803Y215735I0J1502D01*
G01X325769Y215758D01*
X325688Y215775D01*
X325321Y215695D01*
X325254Y215647D01*
X325233Y215612D01*
G02X323945Y214883I-1288J773D01*
G02Y217887I0J1502D01*
G02X324800Y217620I0J-1502D01*
G01X324834Y217597D01*
X324915Y217580D01*
X325282Y217660D01*
X325349Y217708D01*
X325370Y217743D01*
G02X325526Y217956I1285J-777D01*
G03X325527Y217958I-173J88D01*
G03X325575Y218088I-152J130D01*
G01Y218352D01*
G03X325527Y218482I-200J0D01*
G01X325526Y218483D01*
G02Y220457I1131J987D01*
G01Y220458D01*
X325527D01*
G03X325575Y220588I-152J130D01*
G01Y220852D01*
G03X325527Y220982I-200J0D01*
G01X325526Y220983D01*
G02X325156Y221970I1131J987D01*
G37*
G36*
G01X475157D02*
G02X478161I1502J0D01*
G02X477791Y220983I-1501J0D01*
G01Y220982D01*
X477790D01*
G03X477742Y220852I152J-130D01*
G01Y220588D01*
G03X477790Y220458I200J0D01*
G01X477791Y220457D01*
G02Y218483I-1131J-987D01*
G01Y218482D01*
X477790D01*
G03X477742Y218352I152J-130D01*
G01Y218088D01*
G03X477790Y217958I200J0D01*
G01X477791Y217957D01*
G02X478161Y216970I-1131J-987D01*
G02X476659Y215468I-1502J0D01*
G02X475804Y215735I0J1502D01*
G01X475770Y215758D01*
X475689Y215775D01*
X475322Y215695D01*
X475255Y215647D01*
X475234Y215612D01*
G02X473946Y214883I-1288J773D01*
G02Y217887I0J1502D01*
G02X474801Y217620I0J-1502D01*
G01X474835Y217597D01*
X474916Y217580D01*
X475283Y217660D01*
X475350Y217708D01*
X475371Y217743D01*
G02X475527Y217956I1285J-777D01*
G03X475528Y217958I-173J88D01*
G03X475576Y218088I-152J130D01*
G01Y218352D01*
G03X475528Y218482I-200J0D01*
G01X475527Y218483D01*
G02Y220457I1131J987D01*
G01Y220458D01*
X475528D01*
G03X475576Y220588I-152J130D01*
G01Y220852D01*
G03X475528Y220982I-200J0D01*
G01X475527Y220983D01*
G02X475157Y221970I1131J987D01*
G37*
G36*
G01X577519D02*
G02X580523I1502J0D01*
G02X580153Y220983I-1501J0D01*
G01Y220982D01*
X580152D01*
G03X580104Y220852I152J-130D01*
G01Y220588D01*
G03X580152Y220458I200J0D01*
G01X580153Y220457D01*
G02Y218483I-1131J-987D01*
G01Y218482D01*
X580152D01*
G03X580104Y218352I152J-130D01*
G01Y218088D01*
G03X580152Y217958I200J0D01*
G01X580153Y217957D01*
G02X580523Y216970I-1131J-987D01*
G02X579021Y215468I-1502J0D01*
G02X578166Y215735I0J1502D01*
G01X578132Y215758D01*
X578051Y215775D01*
X577684Y215695D01*
X577617Y215647D01*
X577596Y215612D01*
G02X576308Y214883I-1288J773D01*
G02Y217887I0J1502D01*
G02X577163Y217620I0J-1502D01*
G01X577197Y217597D01*
X577278Y217580D01*
X577645Y217660D01*
X577712Y217708D01*
X577733Y217743D01*
G02X577889Y217956I1285J-777D01*
G03X577890Y217958I-173J88D01*
G03X577938Y218088I-152J130D01*
G01Y218352D01*
G03X577890Y218482I-200J0D01*
G01X577889Y218483D01*
G02Y220457I1131J987D01*
G01Y220458D01*
X577890D01*
G03X577938Y220588I-152J130D01*
G01Y220852D01*
G03X577890Y220982I-200J0D01*
G01X577889Y220983D01*
G02X577519Y221970I1131J987D01*
G37*
G36*
G01X679881D02*
G02X682885I1502J0D01*
G02X682515Y220983I-1501J0D01*
G01Y220982D01*
X682514D01*
G03X682466Y220852I152J-130D01*
G01Y220588D01*
G03X682514Y220458I200J0D01*
G01X682515Y220457D01*
G02Y218483I-1131J-987D01*
G01Y218482D01*
X682514D01*
G03X682466Y218352I152J-130D01*
G01Y218088D01*
G03X682514Y217958I200J0D01*
G01X682515Y217957D01*
G02X682885Y216970I-1131J-987D01*
G02X681383Y215468I-1502J0D01*
G02X680528Y215735I0J1502D01*
G01X680494Y215758D01*
X680413Y215775D01*
X680046Y215695D01*
X679979Y215647D01*
X679958Y215612D01*
G02X678670Y214883I-1288J773D01*
G02Y217887I0J1502D01*
G02X679525Y217620I0J-1502D01*
G01X679559Y217597D01*
X679640Y217580D01*
X680007Y217660D01*
X680074Y217708D01*
X680095Y217743D01*
G02X680251Y217956I1285J-777D01*
G03X680252Y217958I-173J88D01*
G03X680300Y218088I-152J130D01*
G01Y218352D01*
G03X680252Y218482I-200J0D01*
G01X680251Y218483D01*
G02Y220457I1131J987D01*
G01Y220458D01*
X680252D01*
G03X680300Y220588I-152J130D01*
G01Y220852D01*
G03X680252Y220982I-200J0D01*
G01X680251Y220983D01*
G02X679881Y221970I1131J987D01*
G37*
G36*
G01X782243D02*
G02X785247I1502J0D01*
G02X784877Y220983I-1501J0D01*
G01Y220982D01*
X784876D01*
G03X784828Y220852I152J-130D01*
G01Y220588D01*
G03X784876Y220458I200J0D01*
G01X784877Y220457D01*
G02Y218483I-1131J-987D01*
G01Y218482D01*
X784876D01*
G03X784828Y218352I152J-130D01*
G01Y218088D01*
G03X784876Y217958I200J0D01*
G01X784877Y217957D01*
G02X785247Y216970I-1131J-987D01*
G02X783745Y215468I-1502J0D01*
G02X782890Y215735I0J1502D01*
G01X782856Y215758D01*
X782775Y215775D01*
X782408Y215695D01*
X782341Y215647D01*
X782320Y215612D01*
G02X781032Y214883I-1288J773D01*
G02Y217887I0J1502D01*
G02X781887Y217620I0J-1502D01*
G01X781921Y217597D01*
X782002Y217580D01*
X782369Y217660D01*
X782436Y217708D01*
X782457Y217743D01*
G02X782613Y217956I1285J-777D01*
G03X782614Y217958I-173J88D01*
G03X782662Y218088I-152J130D01*
G01Y218352D01*
G03X782614Y218482I-200J0D01*
G01X782613Y218483D01*
G02Y220457I1131J987D01*
G01Y220458D01*
X782614D01*
G03X782662Y220588I-152J130D01*
G01Y220852D01*
G03X782614Y220982I-200J0D01*
G01X782613Y220983D01*
G02X782243Y221970I1131J987D01*
G37*
G36*
G01X1034605D02*
G02X1037609I1502J0D01*
G02X1037239Y220983I-1501J0D01*
G01Y220982D01*
X1037238D01*
G03X1037190Y220852I152J-130D01*
G01Y220588D01*
G03X1037238Y220458I200J0D01*
G01X1037239Y220457D01*
G02Y218483I-1131J-987D01*
G01Y218482D01*
X1037238D01*
G03X1037190Y218352I152J-130D01*
G01Y218088D01*
G03X1037238Y217958I200J0D01*
G01X1037239Y217957D01*
G02X1037609Y216970I-1131J-987D01*
G02X1036107Y215468I-1502J0D01*
G02X1035252Y215735I0J1502D01*
G01X1035218Y215758D01*
X1035137Y215775D01*
X1034770Y215695D01*
X1034703Y215647D01*
X1034682Y215612D01*
G02X1033394Y214883I-1288J773D01*
G02Y217887I0J1502D01*
G02X1034249Y217620I0J-1502D01*
G01X1034283Y217597D01*
X1034364Y217580D01*
X1034731Y217660D01*
X1034798Y217708D01*
X1034819Y217743D01*
G02X1034975Y217956I1285J-777D01*
G03X1034976Y217958I-173J88D01*
G03X1035024Y218088I-152J130D01*
G01Y218352D01*
G03X1034976Y218482I-200J0D01*
G01X1034975Y218483D01*
G02Y220457I1131J987D01*
G01Y220458D01*
X1034976D01*
G03X1035024Y220588I-152J130D01*
G01Y220852D01*
G03X1034976Y220982I-200J0D01*
G01X1034975Y220983D01*
G02X1034605Y221970I1131J987D01*
G37*
G36*
G01X1136967D02*
G02X1139971I1502J0D01*
G02X1139601Y220983I-1501J0D01*
G01Y220982D01*
X1139600D01*
G03X1139552Y220852I152J-130D01*
G01Y220588D01*
G03X1139600Y220458I200J0D01*
G01X1139601Y220457D01*
G02Y218483I-1131J-987D01*
G01Y218482D01*
X1139600D01*
G03X1139552Y218352I152J-130D01*
G01Y218088D01*
G03X1139600Y217958I200J0D01*
G01X1139601Y217957D01*
G02X1139971Y216970I-1131J-987D01*
G02X1138469Y215468I-1502J0D01*
G02X1137614Y215735I0J1502D01*
G01X1137580Y215758D01*
X1137499Y215775D01*
X1137132Y215695D01*
X1137065Y215647D01*
X1137044Y215612D01*
G02X1135756Y214883I-1288J773D01*
G02Y217887I0J1502D01*
G02X1136611Y217620I0J-1502D01*
G01X1136645Y217597D01*
X1136726Y217580D01*
X1137093Y217660D01*
X1137160Y217708D01*
X1137181Y217743D01*
G02X1137337Y217956I1285J-777D01*
G03X1137338Y217958I-173J88D01*
G03X1137386Y218088I-152J130D01*
G01Y218352D01*
G03X1137338Y218482I-200J0D01*
G01X1137337Y218483D01*
G02Y220457I1131J987D01*
G01Y220458D01*
X1137338D01*
G03X1137386Y220588I-152J130D01*
G01Y220852D01*
G03X1137338Y220982I-200J0D01*
G01X1137337Y220983D01*
G02X1136967Y221970I1131J987D01*
G37*
G36*
G01X1239329D02*
G02X1242333I1502J0D01*
G02X1241963Y220983I-1501J0D01*
G01Y220982D01*
X1241962D01*
G03X1241914Y220852I152J-130D01*
G01Y220588D01*
G03X1241962Y220458I200J0D01*
G01X1241963Y220457D01*
G02Y218483I-1131J-987D01*
G01Y218482D01*
X1241962D01*
G03X1241914Y218352I152J-130D01*
G01Y218088D01*
G03X1241962Y217958I200J0D01*
G01X1241963Y217957D01*
G02X1242333Y216970I-1131J-987D01*
G02X1240831Y215468I-1502J0D01*
G02X1239976Y215735I0J1502D01*
G01X1239942Y215758D01*
X1239861Y215775D01*
X1239494Y215695D01*
X1239427Y215647D01*
X1239406Y215612D01*
G02X1238118Y214883I-1288J773D01*
G02Y217887I0J1502D01*
G02X1238973Y217620I0J-1502D01*
G01X1239007Y217597D01*
X1239088Y217580D01*
X1239455Y217660D01*
X1239522Y217708D01*
X1239543Y217743D01*
G02X1239699Y217956I1285J-777D01*
G03X1239700Y217958I-173J88D01*
G03X1239748Y218088I-152J130D01*
G01Y218352D01*
G03X1239700Y218482I-200J0D01*
G01X1239699Y218483D01*
G02Y220457I1131J987D01*
G01Y220458D01*
X1239700D01*
G03X1239748Y220588I-152J130D01*
G01Y220852D01*
G03X1239700Y220982I-200J0D01*
G01X1239699Y220983D01*
G02X1239329Y221970I1131J987D01*
G37*
G36*
G01X1389330D02*
G02X1392334I1502J0D01*
G02X1391964Y220983I-1501J0D01*
G01Y220982D01*
X1391963D01*
G03X1391915Y220852I152J-130D01*
G01Y220588D01*
G03X1391963Y220458I200J0D01*
G01X1391964Y220457D01*
G02Y218483I-1131J-987D01*
G01Y218482D01*
X1391963D01*
G03X1391915Y218352I152J-130D01*
G01Y218088D01*
G03X1391963Y217958I200J0D01*
G01X1391964Y217957D01*
G02X1392334Y216970I-1131J-987D01*
G02X1390832Y215468I-1502J0D01*
G02X1389977Y215735I0J1502D01*
G01X1389943Y215758D01*
X1389862Y215775D01*
X1389495Y215695D01*
X1389428Y215647D01*
X1389407Y215612D01*
G02X1388119Y214883I-1288J773D01*
G02Y217887I0J1502D01*
G02X1388974Y217620I0J-1502D01*
G01X1389008Y217597D01*
X1389089Y217580D01*
X1389456Y217660D01*
X1389523Y217708D01*
X1389544Y217743D01*
G02X1389700Y217956I1285J-777D01*
G03X1389701Y217958I-173J88D01*
G03X1389749Y218088I-152J130D01*
G01Y218352D01*
G03X1389701Y218482I-200J0D01*
G01X1389700Y218483D01*
G02Y220457I1131J987D01*
G01Y220458D01*
X1389701D01*
G03X1389749Y220588I-152J130D01*
G01Y220852D01*
G03X1389701Y220982I-200J0D01*
G01X1389700Y220983D01*
G02X1389330Y221970I1131J987D01*
G37*
G36*
G01X1491692D02*
G02X1494696I1502J0D01*
G02X1494326Y220983I-1501J0D01*
G01Y220982D01*
X1494325D01*
G03X1494277Y220852I152J-130D01*
G01Y220588D01*
G03X1494325Y220458I200J0D01*
G01X1494326Y220457D01*
G02Y218483I-1131J-987D01*
G01Y218482D01*
X1494325D01*
G03X1494277Y218352I152J-130D01*
G01Y218088D01*
G03X1494325Y217958I200J0D01*
G01X1494326Y217957D01*
G02X1494696Y216970I-1131J-987D01*
G02X1493194Y215468I-1502J0D01*
G02X1492339Y215735I0J1502D01*
G01X1492305Y215758D01*
X1492224Y215775D01*
X1491857Y215695D01*
X1491790Y215647D01*
X1491769Y215612D01*
G02X1490481Y214883I-1288J773D01*
G02Y217887I0J1502D01*
G02X1491336Y217620I0J-1502D01*
G01X1491370Y217597D01*
X1491451Y217580D01*
X1491818Y217660D01*
X1491885Y217708D01*
X1491906Y217743D01*
G02X1492062Y217956I1285J-777D01*
G03X1492063Y217958I-173J88D01*
G03X1492111Y218088I-152J130D01*
G01Y218352D01*
G03X1492063Y218482I-200J0D01*
G01X1492062Y218483D01*
G02Y220457I1131J987D01*
G01Y220458D01*
X1492063D01*
G03X1492111Y220588I-152J130D01*
G01Y220852D01*
G03X1492063Y220982I-200J0D01*
G01X1492062Y220983D01*
G02X1491692Y221970I1131J987D01*
G37*
G36*
G01X1594054D02*
G02X1597058I1502J0D01*
G02X1596688Y220983I-1501J0D01*
G01Y220982D01*
X1596687D01*
G03X1596639Y220852I152J-130D01*
G01Y220588D01*
G03X1596687Y220458I200J0D01*
G01X1596688Y220457D01*
G02Y218483I-1131J-987D01*
G01Y218482D01*
X1596687D01*
G03X1596639Y218352I152J-130D01*
G01Y218088D01*
G03X1596687Y217958I200J0D01*
G01X1596688Y217957D01*
G02X1597058Y216970I-1131J-987D01*
G02X1595556Y215468I-1502J0D01*
G02X1594701Y215735I0J1502D01*
G01X1594667Y215758D01*
X1594586Y215775D01*
X1594219Y215695D01*
X1594152Y215647D01*
X1594131Y215612D01*
G02X1592843Y214883I-1288J773D01*
G02Y217887I0J1502D01*
G02X1593698Y217620I0J-1502D01*
G01X1593732Y217597D01*
X1593813Y217580D01*
X1594180Y217660D01*
X1594247Y217708D01*
X1594268Y217743D01*
G02X1594424Y217956I1285J-777D01*
G03X1594425Y217958I-173J88D01*
G03X1594473Y218088I-152J130D01*
G01Y218352D01*
G03X1594425Y218482I-200J0D01*
G01X1594424Y218483D01*
G02Y220457I1131J987D01*
G01Y220458D01*
X1594425D01*
G03X1594473Y220588I-152J130D01*
G01Y220852D01*
G03X1594425Y220982I-200J0D01*
G01X1594424Y220983D01*
G02X1594054Y221970I1131J987D01*
G37*
G36*
G01X1696416D02*
G02X1699420I1502J0D01*
G02X1699050Y220983I-1501J0D01*
G01Y220982D01*
X1699049D01*
G03X1699001Y220852I152J-130D01*
G01Y220588D01*
G03X1699049Y220458I200J0D01*
G01X1699050Y220457D01*
G02Y218483I-1131J-987D01*
G01Y218482D01*
X1699049D01*
G03X1699001Y218352I152J-130D01*
G01Y218088D01*
G03X1699049Y217958I200J0D01*
G01X1699050Y217957D01*
G02X1699420Y216970I-1131J-987D01*
G02X1697918Y215468I-1502J0D01*
G02X1697063Y215735I0J1502D01*
G01X1697029Y215758D01*
X1696948Y215775D01*
X1696581Y215695D01*
X1696514Y215647D01*
X1696493Y215612D01*
G02X1695205Y214883I-1288J773D01*
G02Y217887I0J1502D01*
G02X1696060Y217620I0J-1502D01*
G01X1696094Y217597D01*
X1696175Y217580D01*
X1696542Y217660D01*
X1696609Y217708D01*
X1696630Y217743D01*
G02X1696786Y217956I1285J-777D01*
G03X1696787Y217958I-173J88D01*
G03X1696835Y218088I-152J130D01*
G01Y218352D01*
G03X1696787Y218482I-200J0D01*
G01X1696786Y218483D01*
G02Y220457I1131J987D01*
G01Y220458D01*
X1696787D01*
G03X1696835Y220588I-152J130D01*
G01Y220852D01*
G03X1696787Y220982I-200J0D01*
G01X1696786Y220983D01*
G02X1696416Y221970I1131J987D01*
G37*
G36*
G01X187258Y224421D02*
G02X190262I1502J0D01*
G02X189995Y223566I-1502J0D01*
G01X189972Y223532D01*
X189955Y223451D01*
X190035Y223084D01*
X190083Y223017D01*
X190118Y222996D01*
G02X190331Y222840I-777J-1285D01*
G03X190333Y222839I88J173D01*
G03X190463Y222791I130J152D01*
G01X190727D01*
G03X190857Y222839I0J200D01*
G01X190858Y222840D01*
G02X192832I987J-1131D01*
G01X192833D01*
Y222839D01*
G03X192963Y222791I130J152D01*
G01X193227D01*
G03X193357Y222839I0J200D01*
G01X193358Y222840D01*
G02X194345Y223210I987J-1131D01*
G02Y220206I0J-1502D01*
G02X193358Y220576I0J1501D01*
G01X193357D01*
Y220577D01*
G03X193227Y220625I-130J-152D01*
G01X192963D01*
G03X192833Y220577I0J-200D01*
G01X192832Y220576D01*
G02X190858I-987J1131D01*
G01X190857D01*
Y220577D01*
G03X190727Y220625I-130J-152D01*
G01X190463D01*
G03X190333Y220577I0J-200D01*
G01X190332Y220576D01*
G02X189345Y220206I-987J1131D01*
G02X187843Y221708I0J1502D01*
G02X188110Y222563I1502J0D01*
G01X188133Y222597D01*
X188150Y222678D01*
X188070Y223045D01*
X188022Y223112D01*
X187987Y223133D01*
G02X187258Y224421I773J1288D01*
G37*
G36*
G01X289620D02*
G02X292624I1502J0D01*
G02X292357Y223566I-1502J0D01*
G01X292334Y223532D01*
X292317Y223451D01*
X292397Y223084D01*
X292445Y223017D01*
X292480Y222996D01*
G02X292693Y222840I-777J-1285D01*
G03X292695Y222839I88J173D01*
G03X292825Y222791I130J152D01*
G01X293089D01*
G03X293219Y222839I0J200D01*
G01X293220Y222840D01*
G02X295194I987J-1131D01*
G01X295195D01*
Y222839D01*
G03X295325Y222791I130J152D01*
G01X295589D01*
G03X295719Y222839I0J200D01*
G01X295720Y222840D01*
G02X296707Y223210I987J-1131D01*
G02Y220206I0J-1502D01*
G02X295720Y220576I0J1501D01*
G01X295719D01*
Y220577D01*
G03X295589Y220625I-130J-152D01*
G01X295325D01*
G03X295195Y220577I0J-200D01*
G01X295194Y220576D01*
G02X293220I-987J1131D01*
G01X293219D01*
Y220577D01*
G03X293089Y220625I-130J-152D01*
G01X292825D01*
G03X292695Y220577I0J-200D01*
G01X292694Y220576D01*
G02X291707Y220206I-987J1131D01*
G02X290205Y221708I0J1502D01*
G02X290472Y222563I1502J0D01*
G01X290495Y222597D01*
X290512Y222678D01*
X290432Y223045D01*
X290384Y223112D01*
X290349Y223133D01*
G02X289620Y224421I773J1288D01*
G37*
G36*
G01X391982D02*
G02X394986I1502J0D01*
G02X394719Y223566I-1502J0D01*
G01X394696Y223532D01*
X394679Y223451D01*
X394759Y223084D01*
X394807Y223017D01*
X394842Y222996D01*
G02X395055Y222840I-777J-1285D01*
G03X395057Y222839I88J173D01*
G03X395187Y222791I130J152D01*
G01X395451D01*
G03X395581Y222839I0J200D01*
G01X395582Y222840D01*
G02X397556I987J-1131D01*
G01X397557D01*
Y222839D01*
G03X397687Y222791I130J152D01*
G01X397951D01*
G03X398081Y222839I0J200D01*
G01X398082Y222840D01*
G02X399069Y223210I987J-1131D01*
G02Y220206I0J-1502D01*
G02X398082Y220576I0J1501D01*
G01X398081D01*
Y220577D01*
G03X397951Y220625I-130J-152D01*
G01X397687D01*
G03X397557Y220577I0J-200D01*
G01X397556Y220576D01*
G02X395582I-987J1131D01*
G01X395581D01*
Y220577D01*
G03X395451Y220625I-130J-152D01*
G01X395187D01*
G03X395057Y220577I0J-200D01*
G01X395056Y220576D01*
G02X394069Y220206I-987J1131D01*
G02X392567Y221708I0J1502D01*
G02X392834Y222563I1502J0D01*
G01X392857Y222597D01*
X392874Y222678D01*
X392794Y223045D01*
X392746Y223112D01*
X392711Y223133D01*
G02X391982Y224421I773J1288D01*
G37*
G36*
G01X541983D02*
G02X544987I1502J0D01*
G02X544720Y223566I-1502J0D01*
G01X544697Y223532D01*
X544680Y223451D01*
X544760Y223084D01*
X544808Y223017D01*
X544843Y222996D01*
G02X545056Y222840I-777J-1285D01*
G03X545058Y222839I88J173D01*
G03X545188Y222791I130J152D01*
G01X545452D01*
G03X545582Y222839I0J200D01*
G01X545583Y222840D01*
G02X547557I987J-1131D01*
G01X547558D01*
Y222839D01*
G03X547688Y222791I130J152D01*
G01X547952D01*
G03X548082Y222839I0J200D01*
G01X548083Y222840D01*
G02X549070Y223210I987J-1131D01*
G02Y220206I0J-1502D01*
G02X548083Y220576I0J1501D01*
G01X548082D01*
Y220577D01*
G03X547952Y220625I-130J-152D01*
G01X547688D01*
G03X547558Y220577I0J-200D01*
G01X547557Y220576D01*
G02X545583I-987J1131D01*
G01X545582D01*
Y220577D01*
G03X545452Y220625I-130J-152D01*
G01X545188D01*
G03X545058Y220577I0J-200D01*
G01X545057Y220576D01*
G02X544070Y220206I-987J1131D01*
G02X542568Y221708I0J1502D01*
G02X542835Y222563I1502J0D01*
G01X542858Y222597D01*
X542875Y222678D01*
X542795Y223045D01*
X542747Y223112D01*
X542712Y223133D01*
G02X541983Y224421I773J1288D01*
G37*
G36*
G01X644345D02*
G02X647349I1502J0D01*
G02X647082Y223566I-1502J0D01*
G01X647059Y223532D01*
X647042Y223451D01*
X647122Y223084D01*
X647170Y223017D01*
X647205Y222996D01*
G02X647418Y222840I-777J-1285D01*
G03X647420Y222839I88J173D01*
G03X647550Y222791I130J152D01*
G01X647814D01*
G03X647944Y222839I0J200D01*
G01X647945Y222840D01*
G02X649919I987J-1131D01*
G01X649920D01*
Y222839D01*
G03X650050Y222791I130J152D01*
G01X650314D01*
G03X650444Y222839I0J200D01*
G01X650445Y222840D01*
G02X651432Y223210I987J-1131D01*
G02Y220206I0J-1502D01*
G02X650445Y220576I0J1501D01*
G01X650444D01*
Y220577D01*
G03X650314Y220625I-130J-152D01*
G01X650050D01*
G03X649920Y220577I0J-200D01*
G01X649919Y220576D01*
G02X647945I-987J1131D01*
G01X647944D01*
Y220577D01*
G03X647814Y220625I-130J-152D01*
G01X647550D01*
G03X647420Y220577I0J-200D01*
G01X647419Y220576D01*
G02X646432Y220206I-987J1131D01*
G02X644930Y221708I0J1502D01*
G02X645197Y222563I1502J0D01*
G01X645220Y222597D01*
X645237Y222678D01*
X645157Y223045D01*
X645109Y223112D01*
X645074Y223133D01*
G02X644345Y224421I773J1288D01*
G37*
G36*
G01X746707D02*
G02X749711I1502J0D01*
G02X749444Y223566I-1502J0D01*
G01X749421Y223532D01*
X749404Y223451D01*
X749484Y223084D01*
X749532Y223017D01*
X749567Y222996D01*
G02X749780Y222840I-777J-1285D01*
G03X749782Y222839I88J173D01*
G03X749912Y222791I130J152D01*
G01X750176D01*
G03X750306Y222839I0J200D01*
G01X750307Y222840D01*
G02X752281I987J-1131D01*
G01X752282D01*
Y222839D01*
G03X752412Y222791I130J152D01*
G01X752676D01*
G03X752806Y222839I0J200D01*
G01X752807Y222840D01*
G02X753794Y223210I987J-1131D01*
G02Y220206I0J-1502D01*
G02X752807Y220576I0J1501D01*
G01X752806D01*
Y220577D01*
G03X752676Y220625I-130J-152D01*
G01X752412D01*
G03X752282Y220577I0J-200D01*
G01X752281Y220576D01*
G02X750307I-987J1131D01*
G01X750306D01*
Y220577D01*
G03X750176Y220625I-130J-152D01*
G01X749912D01*
G03X749782Y220577I0J-200D01*
G01X749781Y220576D01*
G02X748794Y220206I-987J1131D01*
G02X747292Y221708I0J1502D01*
G02X747559Y222563I1502J0D01*
G01X747582Y222597D01*
X747599Y222678D01*
X747519Y223045D01*
X747471Y223112D01*
X747436Y223133D01*
G02X746707Y224421I773J1288D01*
G37*
G36*
G01X849069D02*
G02X852073I1502J0D01*
G02X851806Y223566I-1502J0D01*
G01X851783Y223532D01*
X851766Y223451D01*
X851846Y223084D01*
X851894Y223017D01*
X851929Y222996D01*
G02X852142Y222840I-777J-1285D01*
G03X852144Y222839I88J173D01*
G03X852274Y222791I130J152D01*
G01X852538D01*
G03X852668Y222839I0J200D01*
G01X852669Y222840D01*
G02X854643I987J-1131D01*
G01X854644D01*
Y222839D01*
G03X854774Y222791I130J152D01*
G01X855038D01*
G03X855168Y222839I0J200D01*
G01X855169Y222840D01*
G02X856156Y223210I987J-1131D01*
G02Y220206I0J-1502D01*
G02X855169Y220576I0J1501D01*
G01X855168D01*
Y220577D01*
G03X855038Y220625I-130J-152D01*
G01X854774D01*
G03X854644Y220577I0J-200D01*
G01X854643Y220576D01*
G02X852669I-987J1131D01*
G01X852668D01*
Y220577D01*
G03X852538Y220625I-130J-152D01*
G01X852274D01*
G03X852144Y220577I0J-200D01*
G01X852143Y220576D01*
G02X851156Y220206I-987J1131D01*
G02X849654Y221708I0J1502D01*
G02X849921Y222563I1502J0D01*
G01X849944Y222597D01*
X849961Y222678D01*
X849881Y223045D01*
X849833Y223112D01*
X849798Y223133D01*
G02X849069Y224421I773J1288D01*
G37*
G36*
G01X999069D02*
G02X1002073I1502J0D01*
G02X1001806Y223566I-1502J0D01*
G01X1001783Y223532D01*
X1001766Y223451D01*
X1001846Y223084D01*
X1001894Y223017D01*
X1001929Y222996D01*
G02X1002142Y222840I-777J-1285D01*
G03X1002144Y222839I88J173D01*
G03X1002274Y222791I130J152D01*
G01X1002538D01*
G03X1002668Y222839I0J200D01*
G01X1002669Y222840D01*
G02X1004643I987J-1131D01*
G01X1004644D01*
Y222839D01*
G03X1004774Y222791I130J152D01*
G01X1005038D01*
G03X1005168Y222839I0J200D01*
G01X1005169Y222840D01*
G02X1006156Y223210I987J-1131D01*
G02Y220206I0J-1502D01*
G02X1005169Y220576I0J1501D01*
G01X1005168D01*
Y220577D01*
G03X1005038Y220625I-130J-152D01*
G01X1004774D01*
G03X1004644Y220577I0J-200D01*
G01X1004643Y220576D01*
G02X1002669I-987J1131D01*
G01X1002668D01*
Y220577D01*
G03X1002538Y220625I-130J-152D01*
G01X1002274D01*
G03X1002144Y220577I0J-200D01*
G01X1002143Y220576D01*
G02X1001156Y220206I-987J1131D01*
G02X999654Y221708I0J1502D01*
G02X999921Y222563I1502J0D01*
G01X999944Y222597D01*
X999961Y222678D01*
X999881Y223045D01*
X999833Y223112D01*
X999798Y223133D01*
G02X999069Y224421I773J1288D01*
G37*
G36*
G01X1101431D02*
G02X1104435I1502J0D01*
G02X1104168Y223566I-1502J0D01*
G01X1104145Y223532D01*
X1104128Y223451D01*
X1104208Y223084D01*
X1104256Y223017D01*
X1104291Y222996D01*
G02X1104504Y222840I-777J-1285D01*
G03X1104506Y222839I88J173D01*
G03X1104636Y222791I130J152D01*
G01X1104900D01*
G03X1105030Y222839I0J200D01*
G01X1105031Y222840D01*
G02X1107005I987J-1131D01*
G01X1107006D01*
Y222839D01*
G03X1107136Y222791I130J152D01*
G01X1107400D01*
G03X1107530Y222839I0J200D01*
G01X1107531Y222840D01*
G02X1108518Y223210I987J-1131D01*
G02Y220206I0J-1502D01*
G02X1107531Y220576I0J1501D01*
G01X1107530D01*
Y220577D01*
G03X1107400Y220625I-130J-152D01*
G01X1107136D01*
G03X1107006Y220577I0J-200D01*
G01X1107005Y220576D01*
G02X1105031I-987J1131D01*
G01X1105030D01*
Y220577D01*
G03X1104900Y220625I-130J-152D01*
G01X1104636D01*
G03X1104506Y220577I0J-200D01*
G01X1104505Y220576D01*
G02X1103518Y220206I-987J1131D01*
G02X1102016Y221708I0J1502D01*
G02X1102283Y222563I1502J0D01*
G01X1102306Y222597D01*
X1102323Y222678D01*
X1102243Y223045D01*
X1102195Y223112D01*
X1102160Y223133D01*
G02X1101431Y224421I773J1288D01*
G37*
G36*
G01X1203793D02*
G02X1206797I1502J0D01*
G02X1206530Y223566I-1502J0D01*
G01X1206507Y223532D01*
X1206490Y223451D01*
X1206570Y223084D01*
X1206618Y223017D01*
X1206653Y222996D01*
G02X1206866Y222840I-777J-1285D01*
G03X1206868Y222839I88J173D01*
G03X1206998Y222791I130J152D01*
G01X1207262D01*
G03X1207392Y222839I0J200D01*
G01X1207393Y222840D01*
G02X1209367I987J-1131D01*
G01X1209368D01*
Y222839D01*
G03X1209498Y222791I130J152D01*
G01X1209762D01*
G03X1209892Y222839I0J200D01*
G01X1209893Y222840D01*
G02X1210880Y223210I987J-1131D01*
G02Y220206I0J-1502D01*
G02X1209893Y220576I0J1501D01*
G01X1209892D01*
Y220577D01*
G03X1209762Y220625I-130J-152D01*
G01X1209498D01*
G03X1209368Y220577I0J-200D01*
G01X1209367Y220576D01*
G02X1207393I-987J1131D01*
G01X1207392D01*
Y220577D01*
G03X1207262Y220625I-130J-152D01*
G01X1206998D01*
G03X1206868Y220577I0J-200D01*
G01X1206867Y220576D01*
G02X1205880Y220206I-987J1131D01*
G02X1204378Y221708I0J1502D01*
G02X1204645Y222563I1502J0D01*
G01X1204668Y222597D01*
X1204685Y222678D01*
X1204605Y223045D01*
X1204557Y223112D01*
X1204522Y223133D01*
G02X1203793Y224421I773J1288D01*
G37*
G36*
G01X1306155D02*
G02X1309159I1502J0D01*
G02X1308892Y223566I-1502J0D01*
G01X1308869Y223532D01*
X1308852Y223451D01*
X1308932Y223084D01*
X1308980Y223017D01*
X1309015Y222996D01*
G02X1309228Y222840I-777J-1285D01*
G03X1309230Y222839I88J173D01*
G03X1309360Y222791I130J152D01*
G01X1309624D01*
G03X1309754Y222839I0J200D01*
G01X1309755Y222840D01*
G02X1311729I987J-1131D01*
G01X1311730D01*
Y222839D01*
G03X1311860Y222791I130J152D01*
G01X1312124D01*
G03X1312254Y222839I0J200D01*
G01X1312255Y222840D01*
G02X1313242Y223210I987J-1131D01*
G02Y220206I0J-1502D01*
G02X1312255Y220576I0J1501D01*
G01X1312254D01*
Y220577D01*
G03X1312124Y220625I-130J-152D01*
G01X1311860D01*
G03X1311730Y220577I0J-200D01*
G01X1311729Y220576D01*
G02X1309755I-987J1131D01*
G01X1309754D01*
Y220577D01*
G03X1309624Y220625I-130J-152D01*
G01X1309360D01*
G03X1309230Y220577I0J-200D01*
G01X1309229Y220576D01*
G02X1308242Y220206I-987J1131D01*
G02X1306740Y221708I0J1502D01*
G02X1307007Y222563I1502J0D01*
G01X1307030Y222597D01*
X1307047Y222678D01*
X1306967Y223045D01*
X1306919Y223112D01*
X1306884Y223133D01*
G02X1306155Y224421I773J1288D01*
G37*
G36*
G01X1456156D02*
G02X1459160I1502J0D01*
G02X1458893Y223566I-1502J0D01*
G01X1458870Y223532D01*
X1458853Y223451D01*
X1458933Y223084D01*
X1458981Y223017D01*
X1459016Y222996D01*
G02X1459229Y222840I-777J-1285D01*
G03X1459231Y222839I88J173D01*
G03X1459361Y222791I130J152D01*
G01X1459625D01*
G03X1459755Y222839I0J200D01*
G01X1459756Y222840D01*
G02X1461730I987J-1131D01*
G01X1461731D01*
Y222839D01*
G03X1461861Y222791I130J152D01*
G01X1462125D01*
G03X1462255Y222839I0J200D01*
G01X1462256Y222840D01*
G02X1463243Y223210I987J-1131D01*
G02Y220206I0J-1502D01*
G02X1462256Y220576I0J1501D01*
G01X1462255D01*
Y220577D01*
G03X1462125Y220625I-130J-152D01*
G01X1461861D01*
G03X1461731Y220577I0J-200D01*
G01X1461730Y220576D01*
G02X1459756I-987J1131D01*
G01X1459755D01*
Y220577D01*
G03X1459625Y220625I-130J-152D01*
G01X1459361D01*
G03X1459231Y220577I0J-200D01*
G01X1459230Y220576D01*
G02X1458243Y220206I-987J1131D01*
G02X1456741Y221708I0J1502D01*
G02X1457008Y222563I1502J0D01*
G01X1457031Y222597D01*
X1457048Y222678D01*
X1456968Y223045D01*
X1456920Y223112D01*
X1456885Y223133D01*
G02X1456156Y224421I773J1288D01*
G37*
G36*
G01X1558518D02*
G02X1561522I1502J0D01*
G02X1561255Y223566I-1502J0D01*
G01X1561232Y223532D01*
X1561215Y223451D01*
X1561295Y223084D01*
X1561343Y223017D01*
X1561378Y222996D01*
G02X1561591Y222840I-777J-1285D01*
G03X1561593Y222839I88J173D01*
G03X1561723Y222791I130J152D01*
G01X1561987D01*
G03X1562117Y222839I0J200D01*
G01X1562118Y222840D01*
G02X1564092I987J-1131D01*
G01X1564093D01*
Y222839D01*
G03X1564223Y222791I130J152D01*
G01X1564487D01*
G03X1564617Y222839I0J200D01*
G01X1564618Y222840D01*
G02X1565605Y223210I987J-1131D01*
G02Y220206I0J-1502D01*
G02X1564618Y220576I0J1501D01*
G01X1564617D01*
Y220577D01*
G03X1564487Y220625I-130J-152D01*
G01X1564223D01*
G03X1564093Y220577I0J-200D01*
G01X1564092Y220576D01*
G02X1562118I-987J1131D01*
G01X1562117D01*
Y220577D01*
G03X1561987Y220625I-130J-152D01*
G01X1561723D01*
G03X1561593Y220577I0J-200D01*
G01X1561592Y220576D01*
G02X1560605Y220206I-987J1131D01*
G02X1559103Y221708I0J1502D01*
G02X1559370Y222563I1502J0D01*
G01X1559393Y222597D01*
X1559410Y222678D01*
X1559330Y223045D01*
X1559282Y223112D01*
X1559247Y223133D01*
G02X1558518Y224421I773J1288D01*
G37*
G36*
G01X1660880D02*
G02X1663884I1502J0D01*
G02X1663617Y223566I-1502J0D01*
G01X1663594Y223532D01*
X1663577Y223451D01*
X1663657Y223084D01*
X1663705Y223017D01*
X1663740Y222996D01*
G02X1663953Y222840I-777J-1285D01*
G03X1663955Y222839I88J173D01*
G03X1664085Y222791I130J152D01*
G01X1664349D01*
G03X1664479Y222839I0J200D01*
G01X1664480Y222840D01*
G02X1666454I987J-1131D01*
G01X1666455D01*
Y222839D01*
G03X1666585Y222791I130J152D01*
G01X1666849D01*
G03X1666979Y222839I0J200D01*
G01X1666980Y222840D01*
G02X1667967Y223210I987J-1131D01*
G02Y220206I0J-1502D01*
G02X1666980Y220576I0J1501D01*
G01X1666979D01*
Y220577D01*
G03X1666849Y220625I-130J-152D01*
G01X1666585D01*
G03X1666455Y220577I0J-200D01*
G01X1666454Y220576D01*
G02X1664480I-987J1131D01*
G01X1664479D01*
Y220577D01*
G03X1664349Y220625I-130J-152D01*
G01X1664085D01*
G03X1663955Y220577I0J-200D01*
G01X1663954Y220576D01*
G02X1662967Y220206I-987J1131D01*
G02X1661465Y221708I0J1502D01*
G02X1661732Y222563I1502J0D01*
G01X1661755Y222597D01*
X1661772Y222678D01*
X1661692Y223045D01*
X1661644Y223112D01*
X1661609Y223133D01*
G02X1660880Y224421I773J1288D01*
G37*
G36*
G01X1763242D02*
G02X1766246I1502J0D01*
G02X1765979Y223566I-1502J0D01*
G01X1765956Y223532D01*
X1765939Y223451D01*
X1766019Y223084D01*
X1766067Y223017D01*
X1766102Y222996D01*
G02X1766315Y222840I-777J-1285D01*
G03X1766317Y222839I88J173D01*
G03X1766447Y222791I130J152D01*
G01X1766711D01*
G03X1766841Y222839I0J200D01*
G01X1766842Y222840D01*
G02X1768816I987J-1131D01*
G01X1768817D01*
Y222839D01*
G03X1768947Y222791I130J152D01*
G01X1769211D01*
G03X1769341Y222839I0J200D01*
G01X1769342Y222840D01*
G02X1770329Y223210I987J-1131D01*
G02Y220206I0J-1502D01*
G02X1769342Y220576I0J1501D01*
G01X1769341D01*
Y220577D01*
G03X1769211Y220625I-130J-152D01*
G01X1768947D01*
G03X1768817Y220577I0J-200D01*
G01X1768816Y220576D01*
G02X1766842I-987J1131D01*
G01X1766841D01*
Y220577D01*
G03X1766711Y220625I-130J-152D01*
G01X1766447D01*
G03X1766317Y220577I0J-200D01*
G01X1766316Y220576D01*
G02X1765329Y220206I-987J1131D01*
G02X1763827Y221708I0J1502D01*
G02X1764094Y222563I1502J0D01*
G01X1764117Y222597D01*
X1764134Y222678D01*
X1764054Y223045D01*
X1764006Y223112D01*
X1763971Y223133D01*
G02X1763242Y224421I773J1288D01*
G37*
G36*
G01X466756Y229952D02*
X478894D01*
G03X478987Y229975I0J200D01*
G02X479686Y230148I700J-1329D01*
G02Y227144I0J-1502D01*
G02X478987Y227317I1J1502D01*
G03X478894Y227340I-93J-177D01*
G01X478523D01*
G03X478360Y227256I0J-200D01*
G01X478171Y226990D01*
G03X478145Y226810I163J-115D01*
G01Y226809D01*
G02X478227Y226320I-1420J-489D01*
G02X475223I-1502J0D01*
G02X475305Y226808I1502J-1D01*
G01Y226810D01*
G03X475279Y226990I-189J65D01*
G01X475090Y227256D01*
G03X474927Y227340I-163J-116D01*
G01X467382D01*
G03X467240Y227281I0J-200D01*
G01X459767Y219807D01*
G03X459708Y219665I141J-142D01*
G01Y163021D01*
G03X459802Y162851I200J0D01*
G01X460132Y162644D01*
X460233Y162638D01*
X460280Y162660D01*
G02X460930Y162808I650J-1353D01*
G02Y159804I0J-1502D01*
G02X460280Y159952I0J1501D01*
G01X460233Y159974D01*
X460132Y159968D01*
X459802Y159761D01*
G03X459708Y159591I106J-170D01*
G01Y157590D01*
G02X459686Y157351I-1307J0D01*
G03X459683Y157321I197J-35D01*
G02X458181Y155868I-1502J50D01*
G02X456679Y157370I0J1502D01*
G02X457045Y158353I1503J0D01*
G03X457094Y158484I-151J131D01*
G01Y220289D01*
G02X457477Y221213I1306J0D01*
G01X465834Y229570D01*
G02X466756Y229952I923J-924D01*
G37*
G36*
G01X189508Y229474D02*
Y229768D01*
G03X189443Y229915I-200J-1D01*
G02X188958Y231021I1019J1106D01*
G02X191962I1502J0D01*
G02X191477Y229915I-1504J0D01*
G03X191412Y229768I135J-148D01*
G01Y229474D01*
G03X191477Y229327I200J1D01*
G02X191962Y228221I-1019J-1106D01*
G02X188958I-1502J0D01*
G02X189443Y229327I1504J0D01*
G03X189508Y229474I-135J148D01*
G37*
G36*
G01X291870D02*
Y229768D01*
G03X291805Y229915I-200J-1D01*
G02X291320Y231021I1019J1106D01*
G02X294324I1502J0D01*
G02X293839Y229915I-1504J0D01*
G03X293774Y229768I135J-148D01*
G01Y229474D01*
G03X293839Y229327I200J1D01*
G02X294324Y228221I-1019J-1106D01*
G02X291320I-1502J0D01*
G02X291805Y229327I1504J0D01*
G03X291870Y229474I-135J148D01*
G37*
G36*
G01X394232D02*
Y229768D01*
G03X394167Y229915I-200J-1D01*
G02X393682Y231021I1019J1106D01*
G02X396686I1502J0D01*
G02X396201Y229915I-1504J0D01*
G03X396136Y229768I135J-148D01*
G01Y229474D01*
G03X396201Y229327I200J1D01*
G02X396686Y228221I-1019J-1106D01*
G02X393682I-1502J0D01*
G02X394167Y229327I1504J0D01*
G03X394232Y229474I-135J148D01*
G37*
G36*
G01X544233D02*
Y229768D01*
G03X544168Y229915I-200J-1D01*
G02X543683Y231021I1019J1106D01*
G02X546687I1502J0D01*
G02X546202Y229915I-1504J0D01*
G03X546137Y229768I135J-148D01*
G01Y229474D01*
G03X546202Y229327I200J1D01*
G02X546687Y228221I-1019J-1106D01*
G02X543683I-1502J0D01*
G02X544168Y229327I1504J0D01*
G03X544233Y229474I-135J148D01*
G37*
G36*
G01X646595D02*
Y229768D01*
G03X646530Y229915I-200J-1D01*
G02X646045Y231021I1019J1106D01*
G02X649049I1502J0D01*
G02X648564Y229915I-1504J0D01*
G03X648499Y229768I135J-148D01*
G01Y229474D01*
G03X648564Y229327I200J1D01*
G02X649049Y228221I-1019J-1106D01*
G02X646045I-1502J0D01*
G02X646530Y229327I1504J0D01*
G03X646595Y229474I-135J148D01*
G37*
G36*
G01X748957D02*
Y229768D01*
G03X748892Y229915I-200J-1D01*
G02X748407Y231021I1019J1106D01*
G02X751411I1502J0D01*
G02X750926Y229915I-1504J0D01*
G03X750861Y229768I135J-148D01*
G01Y229474D01*
G03X750926Y229327I200J1D01*
G02X751411Y228221I-1019J-1106D01*
G02X748407I-1502J0D01*
G02X748892Y229327I1504J0D01*
G03X748957Y229474I-135J148D01*
G37*
G36*
G01X851319D02*
Y229768D01*
G03X851254Y229915I-200J-1D01*
G02X850769Y231021I1019J1106D01*
G02X853773I1502J0D01*
G02X853288Y229915I-1504J0D01*
G03X853223Y229768I135J-148D01*
G01Y229474D01*
G03X853288Y229327I200J1D01*
G02X853773Y228221I-1019J-1106D01*
G02X850769I-1502J0D01*
G02X851254Y229327I1504J0D01*
G03X851319Y229474I-135J148D01*
G37*
G36*
G01X1001319D02*
Y229768D01*
G03X1001254Y229915I-200J-1D01*
G02X1000769Y231021I1019J1106D01*
G02X1003773I1502J0D01*
G02X1003288Y229915I-1504J0D01*
G03X1003223Y229768I135J-148D01*
G01Y229474D01*
G03X1003288Y229327I200J1D01*
G02X1003773Y228221I-1019J-1106D01*
G02X1000769I-1502J0D01*
G02X1001254Y229327I1504J0D01*
G03X1001319Y229474I-135J148D01*
G37*
G36*
G01X1103681D02*
Y229768D01*
G03X1103616Y229915I-200J-1D01*
G02X1103131Y231021I1019J1106D01*
G02X1106135I1502J0D01*
G02X1105650Y229915I-1504J0D01*
G03X1105585Y229768I135J-148D01*
G01Y229474D01*
G03X1105650Y229327I200J1D01*
G02X1106135Y228221I-1019J-1106D01*
G02X1103131I-1502J0D01*
G02X1103616Y229327I1504J0D01*
G03X1103681Y229474I-135J148D01*
G37*
G36*
G01X1206043D02*
Y229768D01*
G03X1205978Y229915I-200J-1D01*
G02X1205493Y231021I1019J1106D01*
G02X1208497I1502J0D01*
G02X1208012Y229915I-1504J0D01*
G03X1207947Y229768I135J-148D01*
G01Y229474D01*
G03X1208012Y229327I200J1D01*
G02X1208497Y228221I-1019J-1106D01*
G02X1205493I-1502J0D01*
G02X1205978Y229327I1504J0D01*
G03X1206043Y229474I-135J148D01*
G37*
G36*
G01X1308405D02*
Y229768D01*
G03X1308340Y229915I-200J-1D01*
G02X1307855Y231021I1019J1106D01*
G02X1310859I1502J0D01*
G02X1310374Y229915I-1504J0D01*
G03X1310309Y229768I135J-148D01*
G01Y229474D01*
G03X1310374Y229327I200J1D01*
G02X1310859Y228221I-1019J-1106D01*
G02X1307855I-1502J0D01*
G02X1308340Y229327I1504J0D01*
G03X1308405Y229474I-135J148D01*
G37*
G36*
G01X1458406D02*
Y229768D01*
G03X1458341Y229915I-200J-1D01*
G02X1457856Y231021I1019J1106D01*
G02X1460860I1502J0D01*
G02X1460375Y229915I-1504J0D01*
G03X1460310Y229768I135J-148D01*
G01Y229474D01*
G03X1460375Y229327I200J1D01*
G02X1460860Y228221I-1019J-1106D01*
G02X1457856I-1502J0D01*
G02X1458341Y229327I1504J0D01*
G03X1458406Y229474I-135J148D01*
G37*
G36*
G01X1560768D02*
Y229768D01*
G03X1560703Y229915I-200J-1D01*
G02X1560218Y231021I1019J1106D01*
G02X1563222I1502J0D01*
G02X1562737Y229915I-1504J0D01*
G03X1562672Y229768I135J-148D01*
G01Y229474D01*
G03X1562737Y229327I200J1D01*
G02X1563222Y228221I-1019J-1106D01*
G02X1560218I-1502J0D01*
G02X1560703Y229327I1504J0D01*
G03X1560768Y229474I-135J148D01*
G37*
G36*
G01X1663130D02*
Y229768D01*
G03X1663065Y229915I-200J-1D01*
G02X1662580Y231021I1019J1106D01*
G02X1665584I1502J0D01*
G02X1665099Y229915I-1504J0D01*
G03X1665034Y229768I135J-148D01*
G01Y229474D01*
G03X1665099Y229327I200J1D01*
G02X1665584Y228221I-1019J-1106D01*
G02X1662580I-1502J0D01*
G02X1663065Y229327I1504J0D01*
G03X1663130Y229474I-135J148D01*
G37*
G36*
G01X1765492D02*
Y229768D01*
G03X1765427Y229915I-200J-1D01*
G02X1764942Y231021I1019J1106D01*
G02X1767946I1502J0D01*
G02X1767461Y229915I-1504J0D01*
G03X1767396Y229768I135J-148D01*
G01Y229474D01*
G03X1767461Y229327I200J1D01*
G02X1767946Y228221I-1019J-1106D01*
G02X1764942I-1502J0D01*
G02X1765427Y229327I1504J0D01*
G03X1765492Y229474I-135J148D01*
G37*
G36*
G01X194498Y237321D02*
X194499Y237320D01*
G03X194629Y237272I130J152D01*
G01X194893D01*
G03X195023Y237320I0J200D01*
G01X195024Y237321D01*
G02X196011Y237691I987J-1131D01*
G02Y234687I0J-1502D01*
G02X195024Y235057I0J1501D01*
G01X195023D01*
Y235058D01*
G03X194893Y235106I-130J-152D01*
G01X194629D01*
G03X194499Y235058I0J-200D01*
G01X194498Y235057D01*
G02X192524I-987J1131D01*
G01X192523D01*
Y235058D01*
G03X192393Y235106I-130J-152D01*
G01X192129D01*
G03X191999Y235058I0J-200D01*
G01X191998Y235057D01*
G02X191011Y234687I-987J1131D01*
G02Y237691I0J1502D01*
G02X191998Y237321I0J-1501D01*
G01X191999D01*
Y237320D01*
G03X192129Y237272I130J152D01*
G01X192393D01*
G03X192523Y237320I0J200D01*
G01X192524Y237321D01*
G02X194498I987J-1131D01*
G37*
G36*
G01X296860D02*
X296861Y237320D01*
G03X296991Y237272I130J152D01*
G01X297255D01*
G03X297385Y237320I0J200D01*
G01X297386Y237321D01*
G02X298373Y237691I987J-1131D01*
G02Y234687I0J-1502D01*
G02X297386Y235057I0J1501D01*
G01X297385D01*
Y235058D01*
G03X297255Y235106I-130J-152D01*
G01X296991D01*
G03X296861Y235058I0J-200D01*
G01X296860Y235057D01*
G02X294886I-987J1131D01*
G01X294885D01*
Y235058D01*
G03X294755Y235106I-130J-152D01*
G01X294491D01*
G03X294361Y235058I0J-200D01*
G01X294360Y235057D01*
G02X293373Y234687I-987J1131D01*
G02Y237691I0J1502D01*
G02X294360Y237321I0J-1501D01*
G01X294361D01*
Y237320D01*
G03X294491Y237272I130J152D01*
G01X294755D01*
G03X294885Y237320I0J200D01*
G01X294886Y237321D01*
G02X296860I987J-1131D01*
G37*
G36*
G01X399222D02*
X399223Y237320D01*
G03X399353Y237272I130J152D01*
G01X399617D01*
G03X399747Y237320I0J200D01*
G01X399748Y237321D01*
G02X400735Y237691I987J-1131D01*
G02Y234687I0J-1502D01*
G02X399748Y235057I0J1501D01*
G01X399747D01*
Y235058D01*
G03X399617Y235106I-130J-152D01*
G01X399353D01*
G03X399223Y235058I0J-200D01*
G01X399222Y235057D01*
G02X397248I-987J1131D01*
G01X397247D01*
Y235058D01*
G03X397117Y235106I-130J-152D01*
G01X396853D01*
G03X396723Y235058I0J-200D01*
G01X396722Y235057D01*
G02X395735Y234687I-987J1131D01*
G02Y237691I0J1502D01*
G02X396722Y237321I0J-1501D01*
G01X396723D01*
Y237320D01*
G03X396853Y237272I130J152D01*
G01X397117D01*
G03X397247Y237320I0J200D01*
G01X397248Y237321D01*
G02X399222I987J-1131D01*
G37*
G36*
G01X549223D02*
X549224Y237320D01*
G03X549354Y237272I130J152D01*
G01X549618D01*
G03X549748Y237320I0J200D01*
G01X549749Y237321D01*
G02X550736Y237691I987J-1131D01*
G02Y234687I0J-1502D01*
G02X549749Y235057I0J1501D01*
G01X549748D01*
Y235058D01*
G03X549618Y235106I-130J-152D01*
G01X549354D01*
G03X549224Y235058I0J-200D01*
G01X549223Y235057D01*
G02X547249I-987J1131D01*
G01X547248D01*
Y235058D01*
G03X547118Y235106I-130J-152D01*
G01X546854D01*
G03X546724Y235058I0J-200D01*
G01X546723Y235057D01*
G02X545736Y234687I-987J1131D01*
G02Y237691I0J1502D01*
G02X546723Y237321I0J-1501D01*
G01X546724D01*
Y237320D01*
G03X546854Y237272I130J152D01*
G01X547118D01*
G03X547248Y237320I0J200D01*
G01X547249Y237321D01*
G02X549223I987J-1131D01*
G37*
G36*
G01X651585D02*
X651586Y237320D01*
G03X651716Y237272I130J152D01*
G01X651980D01*
G03X652110Y237320I0J200D01*
G01X652111Y237321D01*
G02X653098Y237691I987J-1131D01*
G02Y234687I0J-1502D01*
G02X652111Y235057I0J1501D01*
G01X652110D01*
Y235058D01*
G03X651980Y235106I-130J-152D01*
G01X651716D01*
G03X651586Y235058I0J-200D01*
G01X651585Y235057D01*
G02X649611I-987J1131D01*
G01X649610D01*
Y235058D01*
G03X649480Y235106I-130J-152D01*
G01X649216D01*
G03X649086Y235058I0J-200D01*
G01X649085Y235057D01*
G02X648098Y234687I-987J1131D01*
G02Y237691I0J1502D01*
G02X649085Y237321I0J-1501D01*
G01X649086D01*
Y237320D01*
G03X649216Y237272I130J152D01*
G01X649480D01*
G03X649610Y237320I0J200D01*
G01X649611Y237321D01*
G02X651585I987J-1131D01*
G37*
G36*
G01X753947D02*
X753948Y237320D01*
G03X754078Y237272I130J152D01*
G01X754342D01*
G03X754472Y237320I0J200D01*
G01X754473Y237321D01*
G02X755460Y237691I987J-1131D01*
G02Y234687I0J-1502D01*
G02X754473Y235057I0J1501D01*
G01X754472D01*
Y235058D01*
G03X754342Y235106I-130J-152D01*
G01X754078D01*
G03X753948Y235058I0J-200D01*
G01X753947Y235057D01*
G02X751973I-987J1131D01*
G01X751972D01*
Y235058D01*
G03X751842Y235106I-130J-152D01*
G01X751578D01*
G03X751448Y235058I0J-200D01*
G01X751447Y235057D01*
G02X750460Y234687I-987J1131D01*
G02Y237691I0J1502D01*
G02X751447Y237321I0J-1501D01*
G01X751448D01*
Y237320D01*
G03X751578Y237272I130J152D01*
G01X751842D01*
G03X751972Y237320I0J200D01*
G01X751973Y237321D01*
G02X753947I987J-1131D01*
G37*
G36*
G01X856309D02*
X856310Y237320D01*
G03X856440Y237272I130J152D01*
G01X856704D01*
G03X856834Y237320I0J200D01*
G01X856835Y237321D01*
G02X857822Y237691I987J-1131D01*
G02Y234687I0J-1502D01*
G02X856835Y235057I0J1501D01*
G01X856834D01*
Y235058D01*
G03X856704Y235106I-130J-152D01*
G01X856440D01*
G03X856310Y235058I0J-200D01*
G01X856309Y235057D01*
G02X854335I-987J1131D01*
G01X854334D01*
Y235058D01*
G03X854204Y235106I-130J-152D01*
G01X853940D01*
G03X853810Y235058I0J-200D01*
G01X853809Y235057D01*
G02X852822Y234687I-987J1131D01*
G02Y237691I0J1502D01*
G02X853809Y237321I0J-1501D01*
G01X853810D01*
Y237320D01*
G03X853940Y237272I130J152D01*
G01X854204D01*
G03X854334Y237320I0J200D01*
G01X854335Y237321D01*
G02X856309I987J-1131D01*
G37*
G36*
G01X1006309D02*
X1006310Y237320D01*
G03X1006440Y237272I130J152D01*
G01X1006704D01*
G03X1006834Y237320I0J200D01*
G01X1006835Y237321D01*
G02X1007822Y237691I987J-1131D01*
G02Y234687I0J-1502D01*
G02X1006835Y235057I0J1501D01*
G01X1006834D01*
Y235058D01*
G03X1006704Y235106I-130J-152D01*
G01X1006440D01*
G03X1006310Y235058I0J-200D01*
G01X1006309Y235057D01*
G02X1004335I-987J1131D01*
G01X1004334D01*
Y235058D01*
G03X1004204Y235106I-130J-152D01*
G01X1003940D01*
G03X1003810Y235058I0J-200D01*
G01X1003809Y235057D01*
G02X1002822Y234687I-987J1131D01*
G02Y237691I0J1502D01*
G02X1003809Y237321I0J-1501D01*
G01X1003810D01*
Y237320D01*
G03X1003940Y237272I130J152D01*
G01X1004204D01*
G03X1004334Y237320I0J200D01*
G01X1004335Y237321D01*
G02X1006309I987J-1131D01*
G37*
G36*
G01X1108671D02*
X1108672Y237320D01*
G03X1108802Y237272I130J152D01*
G01X1109066D01*
G03X1109196Y237320I0J200D01*
G01X1109197Y237321D01*
G02X1110184Y237691I987J-1131D01*
G02Y234687I0J-1502D01*
G02X1109197Y235057I0J1501D01*
G01X1109196D01*
Y235058D01*
G03X1109066Y235106I-130J-152D01*
G01X1108802D01*
G03X1108672Y235058I0J-200D01*
G01X1108671Y235057D01*
G02X1106697I-987J1131D01*
G01X1106696D01*
Y235058D01*
G03X1106566Y235106I-130J-152D01*
G01X1106302D01*
G03X1106172Y235058I0J-200D01*
G01X1106171Y235057D01*
G02X1105184Y234687I-987J1131D01*
G02Y237691I0J1502D01*
G02X1106171Y237321I0J-1501D01*
G01X1106172D01*
Y237320D01*
G03X1106302Y237272I130J152D01*
G01X1106566D01*
G03X1106696Y237320I0J200D01*
G01X1106697Y237321D01*
G02X1108671I987J-1131D01*
G37*
G36*
G01X1211033D02*
X1211034Y237320D01*
G03X1211164Y237272I130J152D01*
G01X1211428D01*
G03X1211558Y237320I0J200D01*
G01X1211559Y237321D01*
G02X1212546Y237691I987J-1131D01*
G02Y234687I0J-1502D01*
G02X1211559Y235057I0J1501D01*
G01X1211558D01*
Y235058D01*
G03X1211428Y235106I-130J-152D01*
G01X1211164D01*
G03X1211034Y235058I0J-200D01*
G01X1211033Y235057D01*
G02X1209059I-987J1131D01*
G01X1209058D01*
Y235058D01*
G03X1208928Y235106I-130J-152D01*
G01X1208664D01*
G03X1208534Y235058I0J-200D01*
G01X1208533Y235057D01*
G02X1207546Y234687I-987J1131D01*
G02Y237691I0J1502D01*
G02X1208533Y237321I0J-1501D01*
G01X1208534D01*
Y237320D01*
G03X1208664Y237272I130J152D01*
G01X1208928D01*
G03X1209058Y237320I0J200D01*
G01X1209059Y237321D01*
G02X1211033I987J-1131D01*
G37*
G36*
G01X1313395D02*
X1313396Y237320D01*
G03X1313526Y237272I130J152D01*
G01X1313790D01*
G03X1313920Y237320I0J200D01*
G01X1313921Y237321D01*
G02X1314908Y237691I987J-1131D01*
G02Y234687I0J-1502D01*
G02X1313921Y235057I0J1501D01*
G01X1313920D01*
Y235058D01*
G03X1313790Y235106I-130J-152D01*
G01X1313526D01*
G03X1313396Y235058I0J-200D01*
G01X1313395Y235057D01*
G02X1311421I-987J1131D01*
G01X1311420D01*
Y235058D01*
G03X1311290Y235106I-130J-152D01*
G01X1311026D01*
G03X1310896Y235058I0J-200D01*
G01X1310895Y235057D01*
G02X1309908Y234687I-987J1131D01*
G02Y237691I0J1502D01*
G02X1310895Y237321I0J-1501D01*
G01X1310896D01*
Y237320D01*
G03X1311026Y237272I130J152D01*
G01X1311290D01*
G03X1311420Y237320I0J200D01*
G01X1311421Y237321D01*
G02X1313395I987J-1131D01*
G37*
G36*
G01X1463396D02*
X1463397Y237320D01*
G03X1463527Y237272I130J152D01*
G01X1463791D01*
G03X1463921Y237320I0J200D01*
G01X1463922Y237321D01*
G02X1464909Y237691I987J-1131D01*
G02Y234687I0J-1502D01*
G02X1463922Y235057I0J1501D01*
G01X1463921D01*
Y235058D01*
G03X1463791Y235106I-130J-152D01*
G01X1463527D01*
G03X1463397Y235058I0J-200D01*
G01X1463396Y235057D01*
G02X1461422I-987J1131D01*
G01X1461421D01*
Y235058D01*
G03X1461291Y235106I-130J-152D01*
G01X1461027D01*
G03X1460897Y235058I0J-200D01*
G01X1460896Y235057D01*
G02X1459909Y234687I-987J1131D01*
G02Y237691I0J1502D01*
G02X1460896Y237321I0J-1501D01*
G01X1460897D01*
Y237320D01*
G03X1461027Y237272I130J152D01*
G01X1461291D01*
G03X1461421Y237320I0J200D01*
G01X1461422Y237321D01*
G02X1463396I987J-1131D01*
G37*
G36*
G01X1565758D02*
X1565759Y237320D01*
G03X1565889Y237272I130J152D01*
G01X1566153D01*
G03X1566283Y237320I0J200D01*
G01X1566284Y237321D01*
G02X1567271Y237691I987J-1131D01*
G02Y234687I0J-1502D01*
G02X1566284Y235057I0J1501D01*
G01X1566283D01*
Y235058D01*
G03X1566153Y235106I-130J-152D01*
G01X1565889D01*
G03X1565759Y235058I0J-200D01*
G01X1565758Y235057D01*
G02X1563784I-987J1131D01*
G01X1563783D01*
Y235058D01*
G03X1563653Y235106I-130J-152D01*
G01X1563389D01*
G03X1563259Y235058I0J-200D01*
G01X1563258Y235057D01*
G02X1562271Y234687I-987J1131D01*
G02Y237691I0J1502D01*
G02X1563258Y237321I0J-1501D01*
G01X1563259D01*
Y237320D01*
G03X1563389Y237272I130J152D01*
G01X1563653D01*
G03X1563783Y237320I0J200D01*
G01X1563784Y237321D01*
G02X1565758I987J-1131D01*
G37*
G36*
G01X1668120D02*
X1668121Y237320D01*
G03X1668251Y237272I130J152D01*
G01X1668515D01*
G03X1668645Y237320I0J200D01*
G01X1668646Y237321D01*
G02X1669633Y237691I987J-1131D01*
G02Y234687I0J-1502D01*
G02X1668646Y235057I0J1501D01*
G01X1668645D01*
Y235058D01*
G03X1668515Y235106I-130J-152D01*
G01X1668251D01*
G03X1668121Y235058I0J-200D01*
G01X1668120Y235057D01*
G02X1666146I-987J1131D01*
G01X1666145D01*
Y235058D01*
G03X1666015Y235106I-130J-152D01*
G01X1665751D01*
G03X1665621Y235058I0J-200D01*
G01X1665620Y235057D01*
G02X1664633Y234687I-987J1131D01*
G02Y237691I0J1502D01*
G02X1665620Y237321I0J-1501D01*
G01X1665621D01*
Y237320D01*
G03X1665751Y237272I130J152D01*
G01X1666015D01*
G03X1666145Y237320I0J200D01*
G01X1666146Y237321D01*
G02X1668120I987J-1131D01*
G37*
G36*
G01X1770482D02*
X1770483Y237320D01*
G03X1770613Y237272I130J152D01*
G01X1770877D01*
G03X1771007Y237320I0J200D01*
G01X1771008Y237321D01*
G02X1771995Y237691I987J-1131D01*
G02Y234687I0J-1502D01*
G02X1771008Y235057I0J1501D01*
G01X1771007D01*
Y235058D01*
G03X1770877Y235106I-130J-152D01*
G01X1770613D01*
G03X1770483Y235058I0J-200D01*
G01X1770482Y235057D01*
G02X1768508I-987J1131D01*
G01X1768507D01*
Y235058D01*
G03X1768377Y235106I-130J-152D01*
G01X1768113D01*
G03X1767983Y235058I0J-200D01*
G01X1767982Y235057D01*
G02X1766995Y234687I-987J1131D01*
G02Y237691I0J1502D01*
G02X1767982Y237321I0J-1501D01*
G01X1767983D01*
Y237320D01*
G03X1768113Y237272I130J152D01*
G01X1768377D01*
G03X1768507Y237320I0J200D01*
G01X1768508Y237321D01*
G02X1770482I987J-1131D01*
G37*
G36*
G01X296801Y249897D02*
X296802Y249896D01*
G03X296932Y249848I130J152D01*
G01X297196D01*
G03X297326Y249896I0J200D01*
G01X297327Y249897D01*
G02X298314Y250267I987J-1131D01*
G02Y247263I0J-1502D01*
G02X297327Y247633I0J1501D01*
G01X297326D01*
Y247634D01*
G03X297196Y247682I-130J-152D01*
G01X296932D01*
G03X296802Y247634I0J-200D01*
G01X296801Y247633D01*
G02X294827I-987J1131D01*
G01X294826D01*
Y247634D01*
G03X294696Y247682I-130J-152D01*
G01X294432D01*
G03X294302Y247634I0J-200D01*
G01X294301Y247633D01*
G02X293314Y247263I-987J1131D01*
G02Y250267I0J1502D01*
G02X294301Y249897I0J-1501D01*
G01X294302D01*
Y249896D01*
G03X294432Y249848I130J152D01*
G01X294696D01*
G03X294826Y249896I0J200D01*
G01X294827Y249897D01*
G02X296801I987J-1131D01*
G37*
G36*
G01X399163D02*
X399164Y249896D01*
G03X399294Y249848I130J152D01*
G01X399558D01*
G03X399688Y249896I0J200D01*
G01X399689Y249897D01*
G02X400676Y250267I987J-1131D01*
G02Y247263I0J-1502D01*
G02X399689Y247633I0J1501D01*
G01X399688D01*
Y247634D01*
G03X399558Y247682I-130J-152D01*
G01X399294D01*
G03X399164Y247634I0J-200D01*
G01X399163Y247633D01*
G02X397189I-987J1131D01*
G01X397188D01*
Y247634D01*
G03X397058Y247682I-130J-152D01*
G01X396794D01*
G03X396664Y247634I0J-200D01*
G01X396663Y247633D01*
G02X395676Y247263I-987J1131D01*
G02Y250267I0J1502D01*
G02X396663Y249897I0J-1501D01*
G01X396664D01*
Y249896D01*
G03X396794Y249848I130J152D01*
G01X397058D01*
G03X397188Y249896I0J200D01*
G01X397189Y249897D01*
G02X399163I987J-1131D01*
G37*
G36*
G01X651526D02*
X651527Y249896D01*
G03X651657Y249848I130J152D01*
G01X651921D01*
G03X652051Y249896I0J200D01*
G01X652052Y249897D01*
G02X653039Y250267I987J-1131D01*
G02Y247263I0J-1502D01*
G02X652052Y247633I0J1501D01*
G01X652051D01*
Y247634D01*
G03X651921Y247682I-130J-152D01*
G01X651657D01*
G03X651527Y247634I0J-200D01*
G01X651526Y247633D01*
G02X649552I-987J1131D01*
G01X649551D01*
Y247634D01*
G03X649421Y247682I-130J-152D01*
G01X649157D01*
G03X649027Y247634I0J-200D01*
G01X649026Y247633D01*
G02X648039Y247263I-987J1131D01*
G02Y250267I0J1502D01*
G02X649026Y249897I0J-1501D01*
G01X649027D01*
Y249896D01*
G03X649157Y249848I130J152D01*
G01X649421D01*
G03X649551Y249896I0J200D01*
G01X649552Y249897D01*
G02X651526I987J-1131D01*
G37*
G36*
G01X970865Y262566D02*
G02Y265570I0J1502D01*
G02X971852Y265200I0J-1501D01*
G01X971853D01*
Y265199D01*
G03X971983Y265151I130J152D01*
G01X972247D01*
G03X972377Y265199I0J200D01*
G01X972378Y265200D01*
G02X973365Y265570I987J-1131D01*
G02Y262566I0J-1502D01*
G02X972378Y262936I0J1501D01*
G01X972377D01*
Y262937D01*
G03X972247Y262985I-130J-152D01*
G01X971983D01*
G03X971853Y262937I0J-200D01*
G01X971852Y262936D01*
G02X970865Y262566I-987J1131D01*
G37*
G36*
G01X160424Y262678D02*
G02Y265682I0J1502D01*
G02X161411Y265312I0J-1501D01*
G01X161412D01*
Y265311D01*
G03X161542Y265263I130J152D01*
G01X161806D01*
G03X161936Y265311I0J200D01*
G01X161937Y265312D01*
G02X162924Y265682I987J-1131D01*
G02Y262678I0J-1502D01*
G02X161937Y263048I0J1501D01*
G01X161936D01*
Y263049D01*
G03X161806Y263097I-130J-152D01*
G01X161542D01*
G03X161412Y263049I0J-200D01*
G01X161411Y263048D01*
G02X160424Y262678I-987J1131D01*
G37*
G36*
G01X262786D02*
G02Y265682I0J1502D01*
G02X263773Y265312I0J-1501D01*
G01X263774D01*
Y265311D01*
G03X263904Y265263I130J152D01*
G01X264168D01*
G03X264298Y265311I0J200D01*
G01X264299Y265312D01*
G02X265286Y265682I987J-1131D01*
G02Y262678I0J-1502D01*
G02X264299Y263048I0J1501D01*
G01X264298D01*
Y263049D01*
G03X264168Y263097I-130J-152D01*
G01X263904D01*
G03X263774Y263049I0J-200D01*
G01X263773Y263048D01*
G02X262786Y262678I-987J1131D01*
G37*
G36*
G01X365148D02*
G02Y265682I0J1502D01*
G02X366135Y265312I0J-1501D01*
G01X366136D01*
Y265311D01*
G03X366266Y265263I130J152D01*
G01X366530D01*
G03X366660Y265311I0J200D01*
G01X366661Y265312D01*
G02X367648Y265682I987J-1131D01*
G02Y262678I0J-1502D01*
G02X366661Y263048I0J1501D01*
G01X366660D01*
Y263049D01*
G03X366530Y263097I-130J-152D01*
G01X366266D01*
G03X366136Y263049I0J-200D01*
G01X366135Y263048D01*
G02X365148Y262678I-987J1131D01*
G37*
G36*
G01X515149D02*
G02Y265682I0J1502D01*
G02X516136Y265312I0J-1501D01*
G01X516137D01*
Y265311D01*
G03X516267Y265263I130J152D01*
G01X516531D01*
G03X516661Y265311I0J200D01*
G01X516662Y265312D01*
G02X517649Y265682I987J-1131D01*
G02Y262678I0J-1502D01*
G02X516662Y263048I0J1501D01*
G01X516661D01*
Y263049D01*
G03X516531Y263097I-130J-152D01*
G01X516267D01*
G03X516137Y263049I0J-200D01*
G01X516136Y263048D01*
G02X515149Y262678I-987J1131D01*
G37*
G36*
G01X617511D02*
G02Y265682I0J1502D01*
G02X618498Y265312I0J-1501D01*
G01X618499D01*
Y265311D01*
G03X618629Y265263I130J152D01*
G01X618893D01*
G03X619023Y265311I0J200D01*
G01X619024Y265312D01*
G02X620011Y265682I987J-1131D01*
G02Y262678I0J-1502D01*
G02X619024Y263048I0J1501D01*
G01X619023D01*
Y263049D01*
G03X618893Y263097I-130J-152D01*
G01X618629D01*
G03X618499Y263049I0J-200D01*
G01X618498Y263048D01*
G02X617511Y262678I-987J1131D01*
G37*
G36*
G01X719873D02*
G02Y265682I0J1502D01*
G02X720860Y265312I0J-1501D01*
G01X720861D01*
Y265311D01*
G03X720991Y265263I130J152D01*
G01X721255D01*
G03X721385Y265311I0J200D01*
G01X721386Y265312D01*
G02X722373Y265682I987J-1131D01*
G02Y262678I0J-1502D01*
G02X721386Y263048I0J1501D01*
G01X721385D01*
Y263049D01*
G03X721255Y263097I-130J-152D01*
G01X720991D01*
G03X720861Y263049I0J-200D01*
G01X720860Y263048D01*
G02X719873Y262678I-987J1131D01*
G37*
G36*
G01X822235D02*
G02Y265682I0J1502D01*
G02X823222Y265312I0J-1501D01*
G01X823223D01*
Y265311D01*
G03X823353Y265263I130J152D01*
G01X823617D01*
G03X823747Y265311I0J200D01*
G01X823748Y265312D01*
G02X824735Y265682I987J-1131D01*
G02Y262678I0J-1502D01*
G02X823748Y263048I0J1501D01*
G01X823747D01*
Y263049D01*
G03X823617Y263097I-130J-152D01*
G01X823353D01*
G03X823223Y263049I0J-200D01*
G01X823222Y263048D01*
G02X822235Y262678I-987J1131D01*
G37*
G36*
G01X1074597D02*
G02Y265682I0J1502D01*
G02X1075584Y265312I0J-1501D01*
G01X1075585D01*
Y265311D01*
G03X1075715Y265263I130J152D01*
G01X1075979D01*
G03X1076109Y265311I0J200D01*
G01X1076110Y265312D01*
G02X1077097Y265682I987J-1131D01*
G02Y262678I0J-1502D01*
G02X1076110Y263048I0J1501D01*
G01X1076109D01*
Y263049D01*
G03X1075979Y263097I-130J-152D01*
G01X1075715D01*
G03X1075585Y263049I0J-200D01*
G01X1075584Y263048D01*
G02X1074597Y262678I-987J1131D01*
G37*
G36*
G01X1176959D02*
G02Y265682I0J1502D01*
G02X1177946Y265312I0J-1501D01*
G01X1177947D01*
Y265311D01*
G03X1178077Y265263I130J152D01*
G01X1178341D01*
G03X1178471Y265311I0J200D01*
G01X1178472Y265312D01*
G02X1179459Y265682I987J-1131D01*
G02Y262678I0J-1502D01*
G02X1178472Y263048I0J1501D01*
G01X1178471D01*
Y263049D01*
G03X1178341Y263097I-130J-152D01*
G01X1178077D01*
G03X1177947Y263049I0J-200D01*
G01X1177946Y263048D01*
G02X1176959Y262678I-987J1131D01*
G37*
G36*
G01X1736408D02*
G02Y265682I0J1502D01*
G02X1737395Y265312I0J-1501D01*
G01X1737396D01*
Y265311D01*
G03X1737526Y265263I130J152D01*
G01X1737790D01*
G03X1737920Y265311I0J200D01*
G01X1737921Y265312D01*
G02X1738908Y265682I987J-1131D01*
G02Y262678I0J-1502D01*
G02X1737921Y263048I0J1501D01*
G01X1737920D01*
Y263049D01*
G03X1737790Y263097I-130J-152D01*
G01X1737526D01*
G03X1737396Y263049I0J-200D01*
G01X1737395Y263048D01*
G02X1736408Y262678I-987J1131D01*
G37*
G36*
G01X1358367Y257204D02*
X1384916D01*
G02X1385838Y256822I-1J-1306D01*
G01X1396997Y245663D01*
G03X1397139Y245604I142J141D01*
G01X1401251D01*
G03X1401421Y245700I-1J200D01*
G01X1401600Y245992D01*
G03X1401607Y246187I-171J104D01*
G02X1401440Y246874I1335J688D01*
G02X1404444I1502J0D01*
G01Y246873D01*
G02X1404110Y245929I-1502J0D01*
G01X1404088Y245902D01*
X1404065Y245838D01*
Y245804D01*
G03X1404265Y245604I200J0D01*
G01X1404372D01*
G03X1404461Y245625I0J200D01*
G01X1404463Y245626D01*
G02X1405162Y245799I700J-1329D01*
G02X1405859Y245627I-1J-1502D01*
G03X1405863Y245625I91J178D01*
G01X1405884Y245614D01*
X1405928Y245604D01*
X1407110D01*
G02X1408034Y245221I0J-1306D01*
G01X1410991Y242264D01*
G02X1411374Y241340I-923J-924D01*
G01Y183645D01*
G02X1410991Y182721I-1306J0D01*
G01X1388095Y159825D01*
G03X1388036Y159683I141J-142D01*
G01Y157257D01*
G02X1387653Y156333I-1306J0D01*
G01X1371643Y140323D01*
G02X1370719Y139940I-924J923D01*
G01X1360912D01*
G03X1360823Y139919I0J-200D01*
G01X1360821Y139918D01*
G02X1360122Y139745I-700J1329D01*
G02Y142749I0J1502D01*
G02X1360819Y142577I-1J-1502D01*
G03X1360823Y142575I91J178D01*
G01X1360844Y142564D01*
X1360888Y142554D01*
X1362793D01*
G03X1362954Y142635I0J200D01*
G01X1363174Y142933D01*
X1363189Y143027D01*
X1363175Y143072D01*
G02X1363107Y143518I1434J447D01*
G02X1366111I1502J0D01*
G02X1366043Y143072I-1502J1D01*
G01X1366029Y143027D01*
X1366044Y142933D01*
X1366264Y142635D01*
G03X1366425Y142554I161J119D01*
G01X1370095D01*
G03X1370237Y142613I0J200D01*
G01X1385363Y157739D01*
G03X1385422Y157881I-141J142D01*
G01Y159550D01*
G03X1385299Y159735I-200J0D01*
G01X1385243Y159758D01*
X1385125Y159735D01*
X1381836Y156446D01*
G02X1380914Y156064I-923J924D01*
G01X1373146D01*
G03X1373053Y156041I0J-200D01*
G02X1372354Y155868I-700J1329D01*
G02Y158872I0J1502D01*
G02X1373053Y158699I-1J-1502D01*
G03X1373146Y158676I93J177D01*
G01X1380288D01*
G03X1380430Y158735I0J200D01*
G01X1407291Y185597D01*
G03X1407350Y185739I-141J142D01*
G01Y213224D01*
G03X1407291Y213366I-200J0D01*
G01X1393494Y227163D01*
G03X1393414Y227212I-142J-141D01*
G01X1393413D01*
G02X1392357Y228646I446J1434D01*
G02X1393859Y230148I1502J0D01*
G02X1395293Y229093I0J-1502D01*
G01Y229091D01*
G03X1395342Y229011I190J62D01*
G01X1408419Y215934D01*
G03X1408637Y215890I142J141D01*
G01X1408693Y215913D01*
X1408760Y216013D01*
Y228450D01*
G03X1408662Y228622I-200J0D01*
G01X1408366Y228797D01*
G03X1408168Y228800I-102J-172D01*
G02X1407447Y228615I-722J1317D01*
G01X1407445D01*
G02Y231619I0J1502D01*
G01X1407447D01*
G02X1408168Y231434I-1J-1502D01*
G03X1408366Y231437I96J175D01*
G01X1408662Y231612D01*
G03X1408760Y231784I-102J172D01*
G01Y240716D01*
G03X1408701Y240858I-200J0D01*
G01X1406628Y242931D01*
G03X1406486Y242990I-142J-141D01*
G01X1405952D01*
G03X1405863Y242969I0J-200D01*
G01X1405861Y242968D01*
G02X1405162Y242795I-700J1329D01*
G02X1404465Y242967I1J1502D01*
G03X1404461Y242969I-91J-178D01*
G01X1404440Y242980D01*
X1404396Y242990D01*
X1399416D01*
G03X1399257Y242911I0J-200D01*
G01X1399036Y242619D01*
X1399018Y242529D01*
X1399031Y242483D01*
G02X1399087Y242078I-1446J-406D01*
G02X1396083I-1502J0D01*
G02X1396179Y242604I1502J-2D01*
G01Y242606D01*
G03X1396176Y242751I-188J69D01*
G01X1396072Y243004D01*
G03X1395971Y243109I-185J-77D01*
G02X1395591Y243373I544J1188D01*
G01X1384432Y254533D01*
G03X1384290Y254592I-142J-141D01*
G01X1357741D01*
G02X1356819Y254974I1J1306D01*
G01X1348054Y263739D01*
G03X1347974Y263788I-142J-141D01*
G01X1347973D01*
G02X1346917Y265222I446J1434D01*
G02X1348419Y266724I1502J0D01*
G02X1349853Y265669I0J-1502D01*
G01Y265667D01*
G03X1349902Y265587I190J62D01*
G01X1358225Y257263D01*
G03X1358367Y257204I142J141D01*
G37*
G36*
G01X200109Y264395D02*
G02Y267399I0J1502D01*
G02X201096Y267029I0J-1501D01*
G01X201097D01*
Y267028D01*
G03X201227Y266980I130J152D01*
G01X201491D01*
G03X201621Y267028I0J200D01*
G01X201622Y267029D01*
G02X202609Y267399I987J-1131D01*
G02Y264395I0J-1502D01*
G02X201622Y264765I0J1501D01*
G01X201621D01*
Y264766D01*
G03X201491Y264814I-130J-152D01*
G01X201227D01*
G03X201097Y264766I0J-200D01*
G01X201096Y264765D01*
G02X200109Y264395I-987J1131D01*
G37*
G36*
G01X302471D02*
G02Y267399I0J1502D01*
G02X303458Y267029I0J-1501D01*
G01X303459D01*
Y267028D01*
G03X303589Y266980I130J152D01*
G01X303853D01*
G03X303983Y267028I0J200D01*
G01X303984Y267029D01*
G02X304971Y267399I987J-1131D01*
G02Y264395I0J-1502D01*
G02X303984Y264765I0J1501D01*
G01X303983D01*
Y264766D01*
G03X303853Y264814I-130J-152D01*
G01X303589D01*
G03X303459Y264766I0J-200D01*
G01X303458Y264765D01*
G02X302471Y264395I-987J1131D01*
G37*
G36*
G01X404833D02*
G02Y267399I0J1502D01*
G02X405820Y267029I0J-1501D01*
G01X405821D01*
Y267028D01*
G03X405951Y266980I130J152D01*
G01X406215D01*
G03X406345Y267028I0J200D01*
G01X406346Y267029D01*
G02X407333Y267399I987J-1131D01*
G02Y264395I0J-1502D01*
G02X406346Y264765I0J1501D01*
G01X406345D01*
Y264766D01*
G03X406215Y264814I-130J-152D01*
G01X405951D01*
G03X405821Y264766I0J-200D01*
G01X405820Y264765D01*
G02X404833Y264395I-987J1131D01*
G37*
G36*
G01X657196D02*
G02Y267399I0J1502D01*
G02X658183Y267029I0J-1501D01*
G01X658184D01*
Y267028D01*
G03X658314Y266980I130J152D01*
G01X658578D01*
G03X658708Y267028I0J200D01*
G01X658709Y267029D01*
G02X659696Y267399I987J-1131D01*
G02Y264395I0J-1502D01*
G02X658709Y264765I0J1501D01*
G01X658708D01*
Y264766D01*
G03X658578Y264814I-130J-152D01*
G01X658314D01*
G03X658184Y264766I0J-200D01*
G01X658183Y264765D01*
G02X657196Y264395I-987J1131D01*
G37*
G36*
G01X1114282D02*
G02Y267399I0J1502D01*
G02X1115269Y267029I0J-1501D01*
G01X1115270D01*
Y267028D01*
G03X1115400Y266980I130J152D01*
G01X1115664D01*
G03X1115794Y267028I0J200D01*
G01X1115795Y267029D01*
G02X1116782Y267399I987J-1131D01*
G02Y264395I0J-1502D01*
G02X1115795Y264765I0J1501D01*
G01X1115794D01*
Y264766D01*
G03X1115664Y264814I-130J-152D01*
G01X1115400D01*
G03X1115270Y264766I0J-200D01*
G01X1115269Y264765D01*
G02X1114282Y264395I-987J1131D01*
G37*
G36*
G01X1216644D02*
G02Y267399I0J1502D01*
G02X1217631Y267029I0J-1501D01*
G01X1217632D01*
Y267028D01*
G03X1217762Y266980I130J152D01*
G01X1218026D01*
G03X1218156Y267028I0J200D01*
G01X1218157Y267029D01*
G02X1219144Y267399I987J-1131D01*
G02Y264395I0J-1502D01*
G02X1218157Y264765I0J1501D01*
G01X1218156D01*
Y264766D01*
G03X1218026Y264814I-130J-152D01*
G01X1217762D01*
G03X1217632Y264766I0J-200D01*
G01X1217631Y264765D01*
G02X1216644Y264395I-987J1131D01*
G37*
G36*
G01X1319006D02*
G02Y267399I0J1502D01*
G02X1319993Y267029I0J-1501D01*
G01X1319994D01*
Y267028D01*
G03X1320124Y266980I130J152D01*
G01X1320388D01*
G03X1320518Y267028I0J200D01*
G01X1320519Y267029D01*
G02X1321506Y267399I987J-1131D01*
G02Y264395I0J-1502D01*
G02X1320519Y264765I0J1501D01*
G01X1320518D01*
Y264766D01*
G03X1320388Y264814I-130J-152D01*
G01X1320124D01*
G03X1319994Y264766I0J-200D01*
G01X1319993Y264765D01*
G02X1319006Y264395I-987J1131D01*
G37*
G36*
G01X1571369D02*
G02Y267399I0J1502D01*
G02X1572356Y267029I0J-1501D01*
G01X1572357D01*
Y267028D01*
G03X1572487Y266980I130J152D01*
G01X1572751D01*
G03X1572881Y267028I0J200D01*
G01X1572882Y267029D01*
G02X1573869Y267399I987J-1131D01*
G02Y264395I0J-1502D01*
G02X1572882Y264765I0J1501D01*
G01X1572881D01*
Y264766D01*
G03X1572751Y264814I-130J-152D01*
G01X1572487D01*
G03X1572357Y264766I0J-200D01*
G01X1572356Y264765D01*
G02X1571369Y264395I-987J1131D01*
G37*
G36*
G01X1776093D02*
G02Y267399I0J1502D01*
G02X1777080Y267029I0J-1501D01*
G01X1777081D01*
Y267028D01*
G03X1777211Y266980I130J152D01*
G01X1777475D01*
G03X1777605Y267028I0J200D01*
G01X1777606Y267029D01*
G02X1778593Y267399I987J-1131D01*
G02Y264395I0J-1502D01*
G02X1777606Y264765I0J1501D01*
G01X1777605D01*
Y264766D01*
G03X1777475Y264814I-130J-152D01*
G01X1777211D01*
G03X1777081Y264766I0J-200D01*
G01X1777080Y264765D01*
G02X1776093Y264395I-987J1131D01*
G37*
G36*
G01X170571Y270978D02*
X170865D01*
G03X171012Y271043I-1J200D01*
G02X172118Y271528I1106J-1019D01*
G02X173105Y271158I0J-1501D01*
G01X173106D01*
Y271157D01*
G03X173236Y271109I130J152D01*
G01X173500D01*
G03X173630Y271157I0J200D01*
G01X173631Y271158D01*
G02X174618Y271528I987J-1131D01*
G02X176120Y270026I0J-1502D01*
G02X175750Y269039I-1501J0D01*
G01Y269038D01*
X175749D01*
G03X175701Y268908I152J-130D01*
G01Y268644D01*
G03X175749Y268514I200J0D01*
G01X175750Y268513D01*
G02X176120Y267526I-1131J-987D01*
G02X174618Y266024I-1502J0D01*
G02X173631Y266394I0J1501D01*
G01X173630D01*
Y266395D01*
G03X173500Y266443I-130J-152D01*
G01X173236D01*
G03X173106Y266395I0J-200D01*
G01X173105Y266394D01*
G02X172118Y266024I-987J1131D01*
G02X171012Y266509I0J1504D01*
G03X170865Y266574I-148J-135D01*
G01X170571D01*
G03X170424Y266509I1J-200D01*
G02X169318Y266024I-1106J1019D01*
G02X167816Y267526I0J1502D01*
G02X168186Y268513I1501J0D01*
G01Y268514D01*
X168187D01*
G03X168235Y268644I-152J130D01*
G01Y268908D01*
G03X168187Y269038I-200J0D01*
G01X168186Y269039D01*
G02X167816Y270026I1131J987D01*
G02X169318Y271528I1502J0D01*
G02X170424Y271043I0J-1504D01*
G03X170571Y270978I148J135D01*
G37*
G36*
G01X272933D02*
X273227D01*
G03X273374Y271043I-1J200D01*
G02X274480Y271528I1106J-1019D01*
G02X275467Y271158I0J-1501D01*
G01X275468D01*
Y271157D01*
G03X275598Y271109I130J152D01*
G01X275862D01*
G03X275992Y271157I0J200D01*
G01X275993Y271158D01*
G02X276980Y271528I987J-1131D01*
G02X278482Y270026I0J-1502D01*
G02X278112Y269039I-1501J0D01*
G01Y269038D01*
X278111D01*
G03X278063Y268908I152J-130D01*
G01Y268644D01*
G03X278111Y268514I200J0D01*
G01X278112Y268513D01*
G02X278482Y267526I-1131J-987D01*
G02X276980Y266024I-1502J0D01*
G02X275993Y266394I0J1501D01*
G01X275992D01*
Y266395D01*
G03X275862Y266443I-130J-152D01*
G01X275598D01*
G03X275468Y266395I0J-200D01*
G01X275467Y266394D01*
G02X274480Y266024I-987J1131D01*
G02X273374Y266509I0J1504D01*
G03X273227Y266574I-148J-135D01*
G01X272933D01*
G03X272786Y266509I1J-200D01*
G02X271680Y266024I-1106J1019D01*
G02X270178Y267526I0J1502D01*
G02X270548Y268513I1501J0D01*
G01Y268514D01*
X270549D01*
G03X270597Y268644I-152J130D01*
G01Y268908D01*
G03X270549Y269038I-200J0D01*
G01X270548Y269039D01*
G02X270178Y270026I1131J987D01*
G02X271680Y271528I1502J0D01*
G02X272786Y271043I0J-1504D01*
G03X272933Y270978I148J135D01*
G37*
G36*
G01X375295D02*
X375589D01*
G03X375736Y271043I-1J200D01*
G02X376842Y271528I1106J-1019D01*
G02X377829Y271158I0J-1501D01*
G01X377830D01*
Y271157D01*
G03X377960Y271109I130J152D01*
G01X378224D01*
G03X378354Y271157I0J200D01*
G01X378355Y271158D01*
G02X379342Y271528I987J-1131D01*
G02X380844Y270026I0J-1502D01*
G02X380474Y269039I-1501J0D01*
G01Y269038D01*
X380473D01*
G03X380425Y268908I152J-130D01*
G01Y268644D01*
G03X380473Y268514I200J0D01*
G01X380474Y268513D01*
G02X380844Y267526I-1131J-987D01*
G02X379342Y266024I-1502J0D01*
G02X378355Y266394I0J1501D01*
G01X378354D01*
Y266395D01*
G03X378224Y266443I-130J-152D01*
G01X377960D01*
G03X377830Y266395I0J-200D01*
G01X377829Y266394D01*
G02X376842Y266024I-987J1131D01*
G02X375736Y266509I0J1504D01*
G03X375589Y266574I-148J-135D01*
G01X375295D01*
G03X375148Y266509I1J-200D01*
G02X374042Y266024I-1106J1019D01*
G02X372540Y267526I0J1502D01*
G02X372910Y268513I1501J0D01*
G01Y268514D01*
X372911D01*
G03X372959Y268644I-152J130D01*
G01Y268908D01*
G03X372911Y269038I-200J0D01*
G01X372910Y269039D01*
G02X372540Y270026I1131J987D01*
G02X374042Y271528I1502J0D01*
G02X375148Y271043I0J-1504D01*
G03X375295Y270978I148J135D01*
G37*
G36*
G01X525296D02*
X525590D01*
G03X525737Y271043I-1J200D01*
G02X526843Y271528I1106J-1019D01*
G02X527830Y271158I0J-1501D01*
G01X527831D01*
Y271157D01*
G03X527961Y271109I130J152D01*
G01X528225D01*
G03X528355Y271157I0J200D01*
G01X528356Y271158D01*
G02X529343Y271528I987J-1131D01*
G02X530845Y270026I0J-1502D01*
G02X530475Y269039I-1501J0D01*
G01Y269038D01*
X530474D01*
G03X530426Y268908I152J-130D01*
G01Y268644D01*
G03X530474Y268514I200J0D01*
G01X530475Y268513D01*
G02X530845Y267526I-1131J-987D01*
G02X529343Y266024I-1502J0D01*
G02X528356Y266394I0J1501D01*
G01X528355D01*
Y266395D01*
G03X528225Y266443I-130J-152D01*
G01X527961D01*
G03X527831Y266395I0J-200D01*
G01X527830Y266394D01*
G02X526843Y266024I-987J1131D01*
G02X525737Y266509I0J1504D01*
G03X525590Y266574I-148J-135D01*
G01X525296D01*
G03X525149Y266509I1J-200D01*
G02X524043Y266024I-1106J1019D01*
G02X522541Y267526I0J1502D01*
G02X522911Y268513I1501J0D01*
G01Y268514D01*
X522912D01*
G03X522960Y268644I-152J130D01*
G01Y268908D01*
G03X522912Y269038I-200J0D01*
G01X522911Y269039D01*
G02X522541Y270026I1131J987D01*
G02X524043Y271528I1502J0D01*
G02X525149Y271043I0J-1504D01*
G03X525296Y270978I148J135D01*
G37*
G36*
G01X627658D02*
X627952D01*
G03X628099Y271043I-1J200D01*
G02X629205Y271528I1106J-1019D01*
G02X630192Y271158I0J-1501D01*
G01X630193D01*
Y271157D01*
G03X630323Y271109I130J152D01*
G01X630587D01*
G03X630717Y271157I0J200D01*
G01X630718Y271158D01*
G02X631705Y271528I987J-1131D01*
G02X633207Y270026I0J-1502D01*
G02X632837Y269039I-1501J0D01*
G01Y269038D01*
X632836D01*
G03X632788Y268908I152J-130D01*
G01Y268644D01*
G03X632836Y268514I200J0D01*
G01X632837Y268513D01*
G02X633207Y267526I-1131J-987D01*
G02X631705Y266024I-1502J0D01*
G02X630718Y266394I0J1501D01*
G01X630717D01*
Y266395D01*
G03X630587Y266443I-130J-152D01*
G01X630323D01*
G03X630193Y266395I0J-200D01*
G01X630192Y266394D01*
G02X629205Y266024I-987J1131D01*
G02X628099Y266509I0J1504D01*
G03X627952Y266574I-148J-135D01*
G01X627658D01*
G03X627511Y266509I1J-200D01*
G02X626405Y266024I-1106J1019D01*
G02X624903Y267526I0J1502D01*
G02X625273Y268513I1501J0D01*
G01Y268514D01*
X625274D01*
G03X625322Y268644I-152J130D01*
G01Y268908D01*
G03X625274Y269038I-200J0D01*
G01X625273Y269039D01*
G02X624903Y270026I1131J987D01*
G02X626405Y271528I1502J0D01*
G02X627511Y271043I0J-1504D01*
G03X627658Y270978I148J135D01*
G37*
G36*
G01X730020D02*
X730314D01*
G03X730461Y271043I-1J200D01*
G02X731567Y271528I1106J-1019D01*
G02X732554Y271158I0J-1501D01*
G01X732555D01*
Y271157D01*
G03X732685Y271109I130J152D01*
G01X732949D01*
G03X733079Y271157I0J200D01*
G01X733080Y271158D01*
G02X734067Y271528I987J-1131D01*
G02X735569Y270026I0J-1502D01*
G02X735199Y269039I-1501J0D01*
G01Y269038D01*
X735198D01*
G03X735150Y268908I152J-130D01*
G01Y268644D01*
G03X735198Y268514I200J0D01*
G01X735199Y268513D01*
G02X735569Y267526I-1131J-987D01*
G02X734067Y266024I-1502J0D01*
G02X733080Y266394I0J1501D01*
G01X733079D01*
Y266395D01*
G03X732949Y266443I-130J-152D01*
G01X732685D01*
G03X732555Y266395I0J-200D01*
G01X732554Y266394D01*
G02X731567Y266024I-987J1131D01*
G02X730461Y266509I0J1504D01*
G03X730314Y266574I-148J-135D01*
G01X730020D01*
G03X729873Y266509I1J-200D01*
G02X728767Y266024I-1106J1019D01*
G02X727265Y267526I0J1502D01*
G02X727635Y268513I1501J0D01*
G01Y268514D01*
X727636D01*
G03X727684Y268644I-152J130D01*
G01Y268908D01*
G03X727636Y269038I-200J0D01*
G01X727635Y269039D01*
G02X727265Y270026I1131J987D01*
G02X728767Y271528I1502J0D01*
G02X729873Y271043I0J-1504D01*
G03X730020Y270978I148J135D01*
G37*
G36*
G01X832382D02*
X832676D01*
G03X832823Y271043I-1J200D01*
G02X833929Y271528I1106J-1019D01*
G02X834916Y271158I0J-1501D01*
G01X834917D01*
Y271157D01*
G03X835047Y271109I130J152D01*
G01X835311D01*
G03X835441Y271157I0J200D01*
G01X835442Y271158D01*
G02X836429Y271528I987J-1131D01*
G02X837931Y270026I0J-1502D01*
G02X837561Y269039I-1501J0D01*
G01Y269038D01*
X837560D01*
G03X837512Y268908I152J-130D01*
G01Y268644D01*
G03X837560Y268514I200J0D01*
G01X837561Y268513D01*
G02X837931Y267526I-1131J-987D01*
G02X836429Y266024I-1502J0D01*
G02X835442Y266394I0J1501D01*
G01X835441D01*
Y266395D01*
G03X835311Y266443I-130J-152D01*
G01X835047D01*
G03X834917Y266395I0J-200D01*
G01X834916Y266394D01*
G02X833929Y266024I-987J1131D01*
G02X832823Y266509I0J1504D01*
G03X832676Y266574I-148J-135D01*
G01X832382D01*
G03X832235Y266509I1J-200D01*
G02X831129Y266024I-1106J1019D01*
G02X829627Y267526I0J1502D01*
G02X829997Y268513I1501J0D01*
G01Y268514D01*
X829998D01*
G03X830046Y268644I-152J130D01*
G01Y268908D01*
G03X829998Y269038I-200J0D01*
G01X829997Y269039D01*
G02X829627Y270026I1131J987D01*
G02X831129Y271528I1502J0D01*
G02X832235Y271043I0J-1504D01*
G03X832382Y270978I148J135D01*
G37*
G36*
G01X982382D02*
X982676D01*
G03X982823Y271043I-1J200D01*
G02X983929Y271528I1106J-1019D01*
G02X984916Y271158I0J-1501D01*
G01X984917D01*
Y271157D01*
G03X985047Y271109I130J152D01*
G01X985311D01*
G03X985441Y271157I0J200D01*
G01X985442Y271158D01*
G02X986429Y271528I987J-1131D01*
G02X987931Y270026I0J-1502D01*
G02X987561Y269039I-1501J0D01*
G01Y269038D01*
X987560D01*
G03X987512Y268908I152J-130D01*
G01Y268644D01*
G03X987560Y268514I200J0D01*
G01X987561Y268513D01*
G02X987931Y267526I-1131J-987D01*
G02X986429Y266024I-1502J0D01*
G02X985442Y266394I0J1501D01*
G01X985441D01*
Y266395D01*
G03X985311Y266443I-130J-152D01*
G01X985047D01*
G03X984917Y266395I0J-200D01*
G01X984916Y266394D01*
G02X983929Y266024I-987J1131D01*
G02X982823Y266509I0J1504D01*
G03X982676Y266574I-148J-135D01*
G01X982382D01*
G03X982235Y266509I1J-200D01*
G02X981129Y266024I-1106J1019D01*
G02X979627Y267526I0J1502D01*
G02X979997Y268513I1501J0D01*
G01Y268514D01*
X979998D01*
G03X980046Y268644I-152J130D01*
G01Y268908D01*
G03X979998Y269038I-200J0D01*
G01X979997Y269039D01*
G02X979627Y270026I1131J987D01*
G02X981129Y271528I1502J0D01*
G02X982235Y271043I0J-1504D01*
G03X982382Y270978I148J135D01*
G37*
G36*
G01X1084744D02*
X1085038D01*
G03X1085185Y271043I-1J200D01*
G02X1086291Y271528I1106J-1019D01*
G02X1087278Y271158I0J-1501D01*
G01X1087279D01*
Y271157D01*
G03X1087409Y271109I130J152D01*
G01X1087673D01*
G03X1087803Y271157I0J200D01*
G01X1087804Y271158D01*
G02X1088791Y271528I987J-1131D01*
G02X1090293Y270026I0J-1502D01*
G02X1089923Y269039I-1501J0D01*
G01Y269038D01*
X1089922D01*
G03X1089874Y268908I152J-130D01*
G01Y268644D01*
G03X1089922Y268514I200J0D01*
G01X1089923Y268513D01*
G02X1090293Y267526I-1131J-987D01*
G02X1088791Y266024I-1502J0D01*
G02X1087804Y266394I0J1501D01*
G01X1087803D01*
Y266395D01*
G03X1087673Y266443I-130J-152D01*
G01X1087409D01*
G03X1087279Y266395I0J-200D01*
G01X1087278Y266394D01*
G02X1086291Y266024I-987J1131D01*
G02X1085185Y266509I0J1504D01*
G03X1085038Y266574I-148J-135D01*
G01X1084744D01*
G03X1084597Y266509I1J-200D01*
G02X1083491Y266024I-1106J1019D01*
G02X1081989Y267526I0J1502D01*
G02X1082359Y268513I1501J0D01*
G01Y268514D01*
X1082360D01*
G03X1082408Y268644I-152J130D01*
G01Y268908D01*
G03X1082360Y269038I-200J0D01*
G01X1082359Y269039D01*
G02X1081989Y270026I1131J987D01*
G02X1083491Y271528I1502J0D01*
G02X1084597Y271043I0J-1504D01*
G03X1084744Y270978I148J135D01*
G37*
G36*
G01X1187106D02*
X1187400D01*
G03X1187547Y271043I-1J200D01*
G02X1188653Y271528I1106J-1019D01*
G02X1189640Y271158I0J-1501D01*
G01X1189641D01*
Y271157D01*
G03X1189771Y271109I130J152D01*
G01X1190035D01*
G03X1190165Y271157I0J200D01*
G01X1190166Y271158D01*
G02X1191153Y271528I987J-1131D01*
G02X1192655Y270026I0J-1502D01*
G02X1192285Y269039I-1501J0D01*
G01Y269038D01*
X1192284D01*
G03X1192236Y268908I152J-130D01*
G01Y268644D01*
G03X1192284Y268514I200J0D01*
G01X1192285Y268513D01*
G02X1192655Y267526I-1131J-987D01*
G02X1191153Y266024I-1502J0D01*
G02X1190166Y266394I0J1501D01*
G01X1190165D01*
Y266395D01*
G03X1190035Y266443I-130J-152D01*
G01X1189771D01*
G03X1189641Y266395I0J-200D01*
G01X1189640Y266394D01*
G02X1188653Y266024I-987J1131D01*
G02X1187547Y266509I0J1504D01*
G03X1187400Y266574I-148J-135D01*
G01X1187106D01*
G03X1186959Y266509I1J-200D01*
G02X1185853Y266024I-1106J1019D01*
G02X1184351Y267526I0J1502D01*
G02X1184721Y268513I1501J0D01*
G01Y268514D01*
X1184722D01*
G03X1184770Y268644I-152J130D01*
G01Y268908D01*
G03X1184722Y269038I-200J0D01*
G01X1184721Y269039D01*
G02X1184351Y270026I1131J987D01*
G02X1185853Y271528I1502J0D01*
G02X1186959Y271043I0J-1504D01*
G03X1187106Y270978I148J135D01*
G37*
G36*
G01X1289468D02*
X1289762D01*
G03X1289909Y271043I-1J200D01*
G02X1291015Y271528I1106J-1019D01*
G02X1292002Y271158I0J-1501D01*
G01X1292003D01*
Y271157D01*
G03X1292133Y271109I130J152D01*
G01X1292397D01*
G03X1292527Y271157I0J200D01*
G01X1292528Y271158D01*
G02X1293515Y271528I987J-1131D01*
G02X1295017Y270026I0J-1502D01*
G02X1294647Y269039I-1501J0D01*
G01Y269038D01*
X1294646D01*
G03X1294598Y268908I152J-130D01*
G01Y268644D01*
G03X1294646Y268514I200J0D01*
G01X1294647Y268513D01*
G02X1295017Y267526I-1131J-987D01*
G02X1293515Y266024I-1502J0D01*
G02X1292528Y266394I0J1501D01*
G01X1292527D01*
Y266395D01*
G03X1292397Y266443I-130J-152D01*
G01X1292133D01*
G03X1292003Y266395I0J-200D01*
G01X1292002Y266394D01*
G02X1291015Y266024I-987J1131D01*
G02X1289909Y266509I0J1504D01*
G03X1289762Y266574I-148J-135D01*
G01X1289468D01*
G03X1289321Y266509I1J-200D01*
G02X1288215Y266024I-1106J1019D01*
G02X1286713Y267526I0J1502D01*
G02X1287083Y268513I1501J0D01*
G01Y268514D01*
X1287084D01*
G03X1287132Y268644I-152J130D01*
G01Y268908D01*
G03X1287084Y269038I-200J0D01*
G01X1287083Y269039D01*
G02X1286713Y270026I1131J987D01*
G02X1288215Y271528I1502J0D01*
G02X1289321Y271043I0J-1504D01*
G03X1289468Y270978I148J135D01*
G37*
G36*
G01X1541831D02*
X1542125D01*
G03X1542272Y271043I-1J200D01*
G02X1543378Y271528I1106J-1019D01*
G02X1544365Y271158I0J-1501D01*
G01X1544366D01*
Y271157D01*
G03X1544496Y271109I130J152D01*
G01X1544760D01*
G03X1544890Y271157I0J200D01*
G01X1544891Y271158D01*
G02X1545878Y271528I987J-1131D01*
G02X1547380Y270026I0J-1502D01*
G02X1547010Y269039I-1501J0D01*
G01Y269038D01*
X1547009D01*
G03X1546961Y268908I152J-130D01*
G01Y268644D01*
G03X1547009Y268514I200J0D01*
G01X1547010Y268513D01*
G02X1547380Y267526I-1131J-987D01*
G02X1545878Y266024I-1502J0D01*
G02X1544891Y266394I0J1501D01*
G01X1544890D01*
Y266395D01*
G03X1544760Y266443I-130J-152D01*
G01X1544496D01*
G03X1544366Y266395I0J-200D01*
G01X1544365Y266394D01*
G02X1543378Y266024I-987J1131D01*
G02X1542272Y266509I0J1504D01*
G03X1542125Y266574I-148J-135D01*
G01X1541831D01*
G03X1541684Y266509I1J-200D01*
G02X1540578Y266024I-1106J1019D01*
G02X1539076Y267526I0J1502D01*
G02X1539446Y268513I1501J0D01*
G01Y268514D01*
X1539447D01*
G03X1539495Y268644I-152J130D01*
G01Y268908D01*
G03X1539447Y269038I-200J0D01*
G01X1539446Y269039D01*
G02X1539076Y270026I1131J987D01*
G02X1540578Y271528I1502J0D01*
G02X1541684Y271043I0J-1504D01*
G03X1541831Y270978I148J135D01*
G37*
G36*
G01X1746555D02*
X1746849D01*
G03X1746996Y271043I-1J200D01*
G02X1748102Y271528I1106J-1019D01*
G02X1749089Y271158I0J-1501D01*
G01X1749090D01*
Y271157D01*
G03X1749220Y271109I130J152D01*
G01X1749484D01*
G03X1749614Y271157I0J200D01*
G01X1749615Y271158D01*
G02X1750602Y271528I987J-1131D01*
G02X1752104Y270026I0J-1502D01*
G02X1751734Y269039I-1501J0D01*
G01Y269038D01*
X1751733D01*
G03X1751685Y268908I152J-130D01*
G01Y268644D01*
G03X1751733Y268514I200J0D01*
G01X1751734Y268513D01*
G02X1752104Y267526I-1131J-987D01*
G02X1750602Y266024I-1502J0D01*
G02X1749615Y266394I0J1501D01*
G01X1749614D01*
Y266395D01*
G03X1749484Y266443I-130J-152D01*
G01X1749220D01*
G03X1749090Y266395I0J-200D01*
G01X1749089Y266394D01*
G02X1748102Y266024I-987J1131D01*
G02X1746996Y266509I0J1504D01*
G03X1746849Y266574I-148J-135D01*
G01X1746555D01*
G03X1746408Y266509I1J-200D01*
G02X1745302Y266024I-1106J1019D01*
G02X1743800Y267526I0J1502D01*
G02X1744170Y268513I1501J0D01*
G01Y268514D01*
X1744171D01*
G03X1744219Y268644I-152J130D01*
G01Y268908D01*
G03X1744171Y269038I-200J0D01*
G01X1744170Y269039D01*
G02X1743800Y270026I1131J987D01*
G02X1745302Y271528I1502J0D01*
G02X1746408Y271043I0J-1504D01*
G03X1746555Y270978I148J135D01*
G37*
G36*
G01X193649Y272197D02*
G02X194755Y271712I0J-1504D01*
G03X194902Y271647I148J135D01*
G01X195196D01*
G03X195343Y271712I-1J200D01*
G02X196449Y272197I1106J-1019D01*
G02X197951Y270695I0J-1502D01*
G02X197581Y269708I-1501J0D01*
G01Y269707D01*
X197580D01*
G03X197532Y269577I152J-130D01*
G01Y269313D01*
G03X197580Y269183I200J0D01*
G01X197581Y269182D01*
G02X197951Y268195I-1131J-987D01*
G02X196449Y266693I-1502J0D01*
G02X195343Y267178I0J1504D01*
G03X195196Y267243I-148J-135D01*
G01X194902D01*
G03X194755Y267178I1J-200D01*
G02X193649Y266693I-1106J1019D01*
G02X192662Y267063I0J1501D01*
G01X192661D01*
Y267064D01*
G03X192531Y267112I-130J-152D01*
G01X192267D01*
G03X192137Y267064I0J-200D01*
G01X192136Y267063D01*
G02X191149Y266693I-987J1131D01*
G02X189647Y268195I0J1502D01*
G02X190017Y269182I1501J0D01*
G01Y269183D01*
X190018D01*
G03X190066Y269313I-152J130D01*
G01Y269577D01*
G03X190018Y269707I-200J0D01*
G01X190017Y269708D01*
G02X189647Y270695I1131J987D01*
G02X191149Y272197I1502J0D01*
G02X192136Y271827I0J-1501D01*
G01X192137D01*
Y271826D01*
G03X192267Y271778I130J152D01*
G01X192531D01*
G03X192661Y271826I0J200D01*
G01X192662Y271827D01*
G02X193649Y272197I987J-1131D01*
G37*
G36*
G01X296011D02*
G02X297117Y271712I0J-1504D01*
G03X297264Y271647I148J135D01*
G01X297558D01*
G03X297705Y271712I-1J200D01*
G02X298811Y272197I1106J-1019D01*
G02X300313Y270695I0J-1502D01*
G02X299943Y269708I-1501J0D01*
G01Y269707D01*
X299942D01*
G03X299894Y269577I152J-130D01*
G01Y269313D01*
G03X299942Y269183I200J0D01*
G01X299943Y269182D01*
G02X300313Y268195I-1131J-987D01*
G02X298811Y266693I-1502J0D01*
G02X297705Y267178I0J1504D01*
G03X297558Y267243I-148J-135D01*
G01X297264D01*
G03X297117Y267178I1J-200D01*
G02X296011Y266693I-1106J1019D01*
G02X295024Y267063I0J1501D01*
G01X295023D01*
Y267064D01*
G03X294893Y267112I-130J-152D01*
G01X294629D01*
G03X294499Y267064I0J-200D01*
G01X294498Y267063D01*
G02X293511Y266693I-987J1131D01*
G02X292009Y268195I0J1502D01*
G02X292379Y269182I1501J0D01*
G01Y269183D01*
X292380D01*
G03X292428Y269313I-152J130D01*
G01Y269577D01*
G03X292380Y269707I-200J0D01*
G01X292379Y269708D01*
G02X292009Y270695I1131J987D01*
G02X293511Y272197I1502J0D01*
G02X294498Y271827I0J-1501D01*
G01X294499D01*
Y271826D01*
G03X294629Y271778I130J152D01*
G01X294893D01*
G03X295023Y271826I0J200D01*
G01X295024Y271827D01*
G02X296011Y272197I987J-1131D01*
G37*
G36*
G01X398373D02*
G02X399479Y271712I0J-1504D01*
G03X399626Y271647I148J135D01*
G01X399920D01*
G03X400067Y271712I-1J200D01*
G02X401173Y272197I1106J-1019D01*
G02X402675Y270695I0J-1502D01*
G02X402305Y269708I-1501J0D01*
G01Y269707D01*
X402304D01*
G03X402256Y269577I152J-130D01*
G01Y269313D01*
G03X402304Y269183I200J0D01*
G01X402305Y269182D01*
G02X402675Y268195I-1131J-987D01*
G02X401173Y266693I-1502J0D01*
G02X400067Y267178I0J1504D01*
G03X399920Y267243I-148J-135D01*
G01X399626D01*
G03X399479Y267178I1J-200D01*
G02X398373Y266693I-1106J1019D01*
G02X397386Y267063I0J1501D01*
G01X397385D01*
Y267064D01*
G03X397255Y267112I-130J-152D01*
G01X396991D01*
G03X396861Y267064I0J-200D01*
G01X396860Y267063D01*
G02X395873Y266693I-987J1131D01*
G02X394371Y268195I0J1502D01*
G02X394741Y269182I1501J0D01*
G01Y269183D01*
X394742D01*
G03X394790Y269313I-152J130D01*
G01Y269577D01*
G03X394742Y269707I-200J0D01*
G01X394741Y269708D01*
G02X394371Y270695I1131J987D01*
G02X395873Y272197I1502J0D01*
G02X396860Y271827I0J-1501D01*
G01X396861D01*
Y271826D01*
G03X396991Y271778I130J152D01*
G01X397255D01*
G03X397385Y271826I0J200D01*
G01X397386Y271827D01*
G02X398373Y272197I987J-1131D01*
G37*
G36*
G01X548374D02*
G02X549480Y271712I0J-1504D01*
G03X549627Y271647I148J135D01*
G01X549921D01*
G03X550068Y271712I-1J200D01*
G02X551174Y272197I1106J-1019D01*
G02X552676Y270695I0J-1502D01*
G02X552306Y269708I-1501J0D01*
G01Y269707D01*
X552305D01*
G03X552257Y269577I152J-130D01*
G01Y269313D01*
G03X552305Y269183I200J0D01*
G01X552306Y269182D01*
G02X552676Y268195I-1131J-987D01*
G02X551174Y266693I-1502J0D01*
G02X550068Y267178I0J1504D01*
G03X549921Y267243I-148J-135D01*
G01X549627D01*
G03X549480Y267178I1J-200D01*
G02X548374Y266693I-1106J1019D01*
G02X547387Y267063I0J1501D01*
G01X547386D01*
Y267064D01*
G03X547256Y267112I-130J-152D01*
G01X546992D01*
G03X546862Y267064I0J-200D01*
G01X546861Y267063D01*
G02X545874Y266693I-987J1131D01*
G02X544372Y268195I0J1502D01*
G02X544742Y269182I1501J0D01*
G01Y269183D01*
X544743D01*
G03X544791Y269313I-152J130D01*
G01Y269577D01*
G03X544743Y269707I-200J0D01*
G01X544742Y269708D01*
G02X544372Y270695I1131J987D01*
G02X545874Y272197I1502J0D01*
G02X546861Y271827I0J-1501D01*
G01X546862D01*
Y271826D01*
G03X546992Y271778I130J152D01*
G01X547256D01*
G03X547386Y271826I0J200D01*
G01X547387Y271827D01*
G02X548374Y272197I987J-1131D01*
G37*
G36*
G01X650736D02*
G02X651842Y271712I0J-1504D01*
G03X651989Y271647I148J135D01*
G01X652283D01*
G03X652430Y271712I-1J200D01*
G02X653536Y272197I1106J-1019D01*
G02X655038Y270695I0J-1502D01*
G02X654668Y269708I-1501J0D01*
G01Y269707D01*
X654667D01*
G03X654619Y269577I152J-130D01*
G01Y269313D01*
G03X654667Y269183I200J0D01*
G01X654668Y269182D01*
G02X655038Y268195I-1131J-987D01*
G02X653536Y266693I-1502J0D01*
G02X652430Y267178I0J1504D01*
G03X652283Y267243I-148J-135D01*
G01X651989D01*
G03X651842Y267178I1J-200D01*
G02X650736Y266693I-1106J1019D01*
G02X649749Y267063I0J1501D01*
G01X649748D01*
Y267064D01*
G03X649618Y267112I-130J-152D01*
G01X649354D01*
G03X649224Y267064I0J-200D01*
G01X649223Y267063D01*
G02X648236Y266693I-987J1131D01*
G02X646734Y268195I0J1502D01*
G02X647104Y269182I1501J0D01*
G01Y269183D01*
X647105D01*
G03X647153Y269313I-152J130D01*
G01Y269577D01*
G03X647105Y269707I-200J0D01*
G01X647104Y269708D01*
G02X646734Y270695I1131J987D01*
G02X648236Y272197I1502J0D01*
G02X649223Y271827I0J-1501D01*
G01X649224D01*
Y271826D01*
G03X649354Y271778I130J152D01*
G01X649618D01*
G03X649748Y271826I0J200D01*
G01X649749Y271827D01*
G02X650736Y272197I987J-1131D01*
G37*
G36*
G01X753098D02*
G02X754204Y271712I0J-1504D01*
G03X754351Y271647I148J135D01*
G01X754645D01*
G03X754792Y271712I-1J200D01*
G02X755898Y272197I1106J-1019D01*
G02X757400Y270695I0J-1502D01*
G02X757030Y269708I-1501J0D01*
G01Y269707D01*
X757029D01*
G03X756981Y269577I152J-130D01*
G01Y269313D01*
G03X757029Y269183I200J0D01*
G01X757030Y269182D01*
G02X757400Y268195I-1131J-987D01*
G02X755898Y266693I-1502J0D01*
G02X754792Y267178I0J1504D01*
G03X754645Y267243I-148J-135D01*
G01X754351D01*
G03X754204Y267178I1J-200D01*
G02X753098Y266693I-1106J1019D01*
G02X752111Y267063I0J1501D01*
G01X752110D01*
Y267064D01*
G03X751980Y267112I-130J-152D01*
G01X751716D01*
G03X751586Y267064I0J-200D01*
G01X751585Y267063D01*
G02X750598Y266693I-987J1131D01*
G02X749096Y268195I0J1502D01*
G02X749466Y269182I1501J0D01*
G01Y269183D01*
X749467D01*
G03X749515Y269313I-152J130D01*
G01Y269577D01*
G03X749467Y269707I-200J0D01*
G01X749466Y269708D01*
G02X749096Y270695I1131J987D01*
G02X750598Y272197I1502J0D01*
G02X751585Y271827I0J-1501D01*
G01X751586D01*
Y271826D01*
G03X751716Y271778I130J152D01*
G01X751980D01*
G03X752110Y271826I0J200D01*
G01X752111Y271827D01*
G02X753098Y272197I987J-1131D01*
G37*
G36*
G01X855460D02*
G02X856566Y271712I0J-1504D01*
G03X856713Y271647I148J135D01*
G01X857007D01*
G03X857154Y271712I-1J200D01*
G02X858260Y272197I1106J-1019D01*
G02X859762Y270695I0J-1502D01*
G02X859392Y269708I-1501J0D01*
G01Y269707D01*
X859391D01*
G03X859343Y269577I152J-130D01*
G01Y269313D01*
G03X859391Y269183I200J0D01*
G01X859392Y269182D01*
G02X859762Y268195I-1131J-987D01*
G02X858260Y266693I-1502J0D01*
G02X857154Y267178I0J1504D01*
G03X857007Y267243I-148J-135D01*
G01X856713D01*
G03X856566Y267178I1J-200D01*
G02X855460Y266693I-1106J1019D01*
G02X854473Y267063I0J1501D01*
G01X854472D01*
Y267064D01*
G03X854342Y267112I-130J-152D01*
G01X854078D01*
G03X853948Y267064I0J-200D01*
G01X853947Y267063D01*
G02X852960Y266693I-987J1131D01*
G02X851458Y268195I0J1502D01*
G02X851828Y269182I1501J0D01*
G01Y269183D01*
X851829D01*
G03X851877Y269313I-152J130D01*
G01Y269577D01*
G03X851829Y269707I-200J0D01*
G01X851828Y269708D01*
G02X851458Y270695I1131J987D01*
G02X852960Y272197I1502J0D01*
G02X853947Y271827I0J-1501D01*
G01X853948D01*
Y271826D01*
G03X854078Y271778I130J152D01*
G01X854342D01*
G03X854472Y271826I0J200D01*
G01X854473Y271827D01*
G02X855460Y272197I987J-1131D01*
G37*
G36*
G01X1005460D02*
G02X1006566Y271712I0J-1504D01*
G03X1006713Y271647I148J135D01*
G01X1007007D01*
G03X1007154Y271712I-1J200D01*
G02X1008260Y272197I1106J-1019D01*
G02X1009762Y270695I0J-1502D01*
G02X1009392Y269708I-1501J0D01*
G01Y269707D01*
X1009391D01*
G03X1009343Y269577I152J-130D01*
G01Y269313D01*
G03X1009391Y269183I200J0D01*
G01X1009392Y269182D01*
G02X1009762Y268195I-1131J-987D01*
G02X1008260Y266693I-1502J0D01*
G02X1007154Y267178I0J1504D01*
G03X1007007Y267243I-148J-135D01*
G01X1006713D01*
G03X1006566Y267178I1J-200D01*
G02X1005460Y266693I-1106J1019D01*
G02X1004473Y267063I0J1501D01*
G01X1004472D01*
Y267064D01*
G03X1004342Y267112I-130J-152D01*
G01X1004078D01*
G03X1003948Y267064I0J-200D01*
G01X1003947Y267063D01*
G02X1002960Y266693I-987J1131D01*
G02X1001458Y268195I0J1502D01*
G02X1001828Y269182I1501J0D01*
G01Y269183D01*
X1001829D01*
G03X1001877Y269313I-152J130D01*
G01Y269577D01*
G03X1001829Y269707I-200J0D01*
G01X1001828Y269708D01*
G02X1001458Y270695I1131J987D01*
G02X1002960Y272197I1502J0D01*
G02X1003947Y271827I0J-1501D01*
G01X1003948D01*
Y271826D01*
G03X1004078Y271778I130J152D01*
G01X1004342D01*
G03X1004472Y271826I0J200D01*
G01X1004473Y271827D01*
G02X1005460Y272197I987J-1131D01*
G37*
G36*
G01X1107822D02*
G02X1108928Y271712I0J-1504D01*
G03X1109075Y271647I148J135D01*
G01X1109369D01*
G03X1109516Y271712I-1J200D01*
G02X1110622Y272197I1106J-1019D01*
G02X1112124Y270695I0J-1502D01*
G02X1111754Y269708I-1501J0D01*
G01Y269707D01*
X1111753D01*
G03X1111705Y269577I152J-130D01*
G01Y269313D01*
G03X1111753Y269183I200J0D01*
G01X1111754Y269182D01*
G02X1112124Y268195I-1131J-987D01*
G02X1110622Y266693I-1502J0D01*
G02X1109516Y267178I0J1504D01*
G03X1109369Y267243I-148J-135D01*
G01X1109075D01*
G03X1108928Y267178I1J-200D01*
G02X1107822Y266693I-1106J1019D01*
G02X1106835Y267063I0J1501D01*
G01X1106834D01*
Y267064D01*
G03X1106704Y267112I-130J-152D01*
G01X1106440D01*
G03X1106310Y267064I0J-200D01*
G01X1106309Y267063D01*
G02X1105322Y266693I-987J1131D01*
G02X1103820Y268195I0J1502D01*
G02X1104190Y269182I1501J0D01*
G01Y269183D01*
X1104191D01*
G03X1104239Y269313I-152J130D01*
G01Y269577D01*
G03X1104191Y269707I-200J0D01*
G01X1104190Y269708D01*
G02X1103820Y270695I1131J987D01*
G02X1105322Y272197I1502J0D01*
G02X1106309Y271827I0J-1501D01*
G01X1106310D01*
Y271826D01*
G03X1106440Y271778I130J152D01*
G01X1106704D01*
G03X1106834Y271826I0J200D01*
G01X1106835Y271827D01*
G02X1107822Y272197I987J-1131D01*
G37*
G36*
G01X1210184D02*
G02X1211290Y271712I0J-1504D01*
G03X1211437Y271647I148J135D01*
G01X1211731D01*
G03X1211878Y271712I-1J200D01*
G02X1212984Y272197I1106J-1019D01*
G02X1214486Y270695I0J-1502D01*
G02X1214116Y269708I-1501J0D01*
G01Y269707D01*
X1214115D01*
G03X1214067Y269577I152J-130D01*
G01Y269313D01*
G03X1214115Y269183I200J0D01*
G01X1214116Y269182D01*
G02X1214486Y268195I-1131J-987D01*
G02X1212984Y266693I-1502J0D01*
G02X1211878Y267178I0J1504D01*
G03X1211731Y267243I-148J-135D01*
G01X1211437D01*
G03X1211290Y267178I1J-200D01*
G02X1210184Y266693I-1106J1019D01*
G02X1209197Y267063I0J1501D01*
G01X1209196D01*
Y267064D01*
G03X1209066Y267112I-130J-152D01*
G01X1208802D01*
G03X1208672Y267064I0J-200D01*
G01X1208671Y267063D01*
G02X1207684Y266693I-987J1131D01*
G02X1206182Y268195I0J1502D01*
G02X1206552Y269182I1501J0D01*
G01Y269183D01*
X1206553D01*
G03X1206601Y269313I-152J130D01*
G01Y269577D01*
G03X1206553Y269707I-200J0D01*
G01X1206552Y269708D01*
G02X1206182Y270695I1131J987D01*
G02X1207684Y272197I1502J0D01*
G02X1208671Y271827I0J-1501D01*
G01X1208672D01*
Y271826D01*
G03X1208802Y271778I130J152D01*
G01X1209066D01*
G03X1209196Y271826I0J200D01*
G01X1209197Y271827D01*
G02X1210184Y272197I987J-1131D01*
G37*
G36*
G01X1312546D02*
G02X1313652Y271712I0J-1504D01*
G03X1313799Y271647I148J135D01*
G01X1314093D01*
G03X1314240Y271712I-1J200D01*
G02X1315346Y272197I1106J-1019D01*
G02X1316848Y270695I0J-1502D01*
G02X1316478Y269708I-1501J0D01*
G01Y269707D01*
X1316477D01*
G03X1316429Y269577I152J-130D01*
G01Y269313D01*
G03X1316477Y269183I200J0D01*
G01X1316478Y269182D01*
G02X1316848Y268195I-1131J-987D01*
G02X1315346Y266693I-1502J0D01*
G02X1314240Y267178I0J1504D01*
G03X1314093Y267243I-148J-135D01*
G01X1313799D01*
G03X1313652Y267178I1J-200D01*
G02X1312546Y266693I-1106J1019D01*
G02X1311559Y267063I0J1501D01*
G01X1311558D01*
Y267064D01*
G03X1311428Y267112I-130J-152D01*
G01X1311164D01*
G03X1311034Y267064I0J-200D01*
G01X1311033Y267063D01*
G02X1310046Y266693I-987J1131D01*
G02X1308544Y268195I0J1502D01*
G02X1308914Y269182I1501J0D01*
G01Y269183D01*
X1308915D01*
G03X1308963Y269313I-152J130D01*
G01Y269577D01*
G03X1308915Y269707I-200J0D01*
G01X1308914Y269708D01*
G02X1308544Y270695I1131J987D01*
G02X1310046Y272197I1502J0D01*
G02X1311033Y271827I0J-1501D01*
G01X1311034D01*
Y271826D01*
G03X1311164Y271778I130J152D01*
G01X1311428D01*
G03X1311558Y271826I0J200D01*
G01X1311559Y271827D01*
G02X1312546Y272197I987J-1131D01*
G37*
G36*
G01X1564909D02*
G02X1566015Y271712I0J-1504D01*
G03X1566162Y271647I148J135D01*
G01X1566456D01*
G03X1566603Y271712I-1J200D01*
G02X1567709Y272197I1106J-1019D01*
G02X1569211Y270695I0J-1502D01*
G02X1568841Y269708I-1501J0D01*
G01Y269707D01*
X1568840D01*
G03X1568792Y269577I152J-130D01*
G01Y269313D01*
G03X1568840Y269183I200J0D01*
G01X1568841Y269182D01*
G02X1569211Y268195I-1131J-987D01*
G02X1567709Y266693I-1502J0D01*
G02X1566603Y267178I0J1504D01*
G03X1566456Y267243I-148J-135D01*
G01X1566162D01*
G03X1566015Y267178I1J-200D01*
G02X1564909Y266693I-1106J1019D01*
G02X1563922Y267063I0J1501D01*
G01X1563921D01*
Y267064D01*
G03X1563791Y267112I-130J-152D01*
G01X1563527D01*
G03X1563397Y267064I0J-200D01*
G01X1563396Y267063D01*
G02X1562409Y266693I-987J1131D01*
G02X1560907Y268195I0J1502D01*
G02X1561277Y269182I1501J0D01*
G01Y269183D01*
X1561278D01*
G03X1561326Y269313I-152J130D01*
G01Y269577D01*
G03X1561278Y269707I-200J0D01*
G01X1561277Y269708D01*
G02X1560907Y270695I1131J987D01*
G02X1562409Y272197I1502J0D01*
G02X1563396Y271827I0J-1501D01*
G01X1563397D01*
Y271826D01*
G03X1563527Y271778I130J152D01*
G01X1563791D01*
G03X1563921Y271826I0J200D01*
G01X1563922Y271827D01*
G02X1564909Y272197I987J-1131D01*
G37*
G36*
G01X1769633D02*
G02X1770739Y271712I0J-1504D01*
G03X1770886Y271647I148J135D01*
G01X1771180D01*
G03X1771327Y271712I-1J200D01*
G02X1772433Y272197I1106J-1019D01*
G02X1773935Y270695I0J-1502D01*
G02X1773565Y269708I-1501J0D01*
G01Y269707D01*
X1773564D01*
G03X1773516Y269577I152J-130D01*
G01Y269313D01*
G03X1773564Y269183I200J0D01*
G01X1773565Y269182D01*
G02X1773935Y268195I-1131J-987D01*
G02X1772433Y266693I-1502J0D01*
G02X1771327Y267178I0J1504D01*
G03X1771180Y267243I-148J-135D01*
G01X1770886D01*
G03X1770739Y267178I1J-200D01*
G02X1769633Y266693I-1106J1019D01*
G02X1768646Y267063I0J1501D01*
G01X1768645D01*
Y267064D01*
G03X1768515Y267112I-130J-152D01*
G01X1768251D01*
G03X1768121Y267064I0J-200D01*
G01X1768120Y267063D01*
G02X1767133Y266693I-987J1131D01*
G02X1765631Y268195I0J1502D01*
G02X1766001Y269182I1501J0D01*
G01Y269183D01*
X1766002D01*
G03X1766050Y269313I-152J130D01*
G01Y269577D01*
G03X1766002Y269707I-200J0D01*
G01X1766001Y269708D01*
G02X1765631Y270695I1131J987D01*
G02X1767133Y272197I1502J0D01*
G02X1768120Y271827I0J-1501D01*
G01X1768121D01*
Y271826D01*
G03X1768251Y271778I130J152D01*
G01X1768515D01*
G03X1768645Y271826I0J200D01*
G01X1768646Y271827D01*
G02X1769633Y272197I987J-1131D01*
G37*
G36*
G01X954262Y176161D02*
G02X953880Y175239I-1306J1D01*
G01X918964Y140323D01*
G02X918040Y139940I-924J923D01*
G01X903825D01*
G03X903736Y139919I0J-200D01*
G01X903734Y139918D01*
G02X903035Y139745I-700J1329D01*
G02Y142749I0J1502D01*
G02X903732Y142577I-1J-1502D01*
G03X903736Y142575I91J178D01*
G01X903757Y142564D01*
X903801Y142554D01*
X905706D01*
G03X905867Y142635I0J200D01*
G01X906087Y142933D01*
X906102Y143027D01*
X906088Y143072D01*
G02X906020Y143518I1434J447D01*
G02X909024I1502J0D01*
G02X908956Y143072I-1502J1D01*
G01X908942Y143027D01*
X908957Y142933D01*
X909177Y142635D01*
G03X909338Y142554I161J119D01*
G01X917416D01*
G03X917558Y142613I0J200D01*
G01X930668Y155723D01*
G03X930711Y155940I-142J141D01*
G01X930688Y155997D01*
X930587Y156064D01*
X916059D01*
G03X915966Y156041I0J-200D01*
G02X915267Y155868I-700J1329D01*
G02Y158872I0J1502D01*
G02X915966Y158699I-1J-1502D01*
G03X916059Y158676I93J177D01*
G01X931063D01*
G03X931205Y158735I0J200D01*
G01X950035Y177565D01*
G03X950094Y177707I-141J142D01*
G01Y199231D01*
G03X950035Y199373I-200J0D01*
G01X937073Y212334D01*
G03X936993Y212383I-142J-141D01*
G01X936992D01*
G02X935936Y213817I446J1434D01*
G02X937438Y215319I1502J0D01*
G02X938872Y214264I0J-1502D01*
G01Y214262D01*
G03X938921Y214182I190J62D01*
G01X951309Y201794D01*
G03X951526Y201751I141J142D01*
G01X951583Y201774D01*
X951650Y201875D01*
Y214159D01*
G03X951543Y214336I-200J0D01*
G01X951230Y214502D01*
G03X951024Y214490I-93J-177D01*
G02X950177Y214228I-848J1240D01*
G02Y217232I0J1502D01*
G02X951024Y216970I-1J-1502D01*
G03X951230Y216958I113J165D01*
G01X951543Y217124D01*
G03X951650Y217301I-93J177D01*
G01Y224629D01*
G03X951591Y224771I-200J0D01*
G01X948376Y227985D01*
G03X948296Y228034I-142J-141D01*
G01X948295D01*
G02X948294Y230902I445J1434D01*
G01X948296D01*
G03X948376Y230951I-62J190D01*
G01X953143Y235718D01*
G03X953202Y235860I-141J142D01*
G01Y289211D01*
G03X953143Y289353I-200J0D01*
G01X952308Y290189D01*
G03X952166Y290248I-142J-141D01*
G01X950766D01*
G03X950673Y290225I0J-200D01*
G02X949974Y290052I-700J1329D01*
G02Y293056I0J1502D01*
G02X950673Y292883I-1J-1502D01*
G03X950766Y292860I93J177D01*
G01X952792D01*
G02X953714Y292478I-1J-1306D01*
G01X955433Y290759D01*
G02X955816Y289835I-923J-924D01*
G01Y235236D01*
G02X955433Y234312I-1306J0D01*
G01X950730Y229609D01*
G03Y229327I142J-141D01*
G01X953880Y226177D01*
G02X954262Y225255I-924J-923D01*
G01Y176161D01*
G37*
G36*
G01X1020933Y312865D02*
G02X1023937I1502J0D01*
G02X1023292Y311631I-1503J0D01*
G01X1023262Y311611D01*
X1023220Y311549D01*
X1023150Y311253D01*
G03X1023168Y311112I194J-47D01*
G02X1023350Y310396I-1320J-717D01*
G02X1020346I-1502J0D01*
G02X1020991Y311630I1503J0D01*
G01X1021021Y311650D01*
X1021063Y311712D01*
X1021133Y312008D01*
G03X1021115Y312149I-194J47D01*
G02X1020933Y312865I1320J717D01*
G37*
G36*
G01X807988Y333368D02*
G02X810992I1502J0D01*
G01Y333367D01*
G02X810445Y332208I-1502J0D01*
G01X810410Y332179D01*
X810372Y332101D01*
X810368Y331706D01*
X810404Y331625D01*
X810438Y331597D01*
G02X810959Y330459I-982J-1138D01*
G02X807955I-1502J0D01*
G01Y330460D01*
G02X808502Y331619I1502J0D01*
G01X808537Y331648D01*
X808575Y331726D01*
X808579Y332121D01*
X808543Y332202D01*
X808509Y332230D01*
G02X807988Y333368I982J1138D01*
G37*
G36*
G01X988918Y340454D02*
G02X991922I1502J0D01*
G02X991552Y339467I-1501J0D01*
G01Y339466D01*
X991551D01*
G03X991503Y339336I152J-130D01*
G01Y339072D01*
G03X991551Y338942I200J0D01*
G01X991552Y338941D01*
G02X991922Y337954I-1131J-987D01*
G02X988918I-1502J0D01*
G02X989288Y338941I1501J0D01*
G01Y338942D01*
X989289D01*
G03X989337Y339072I-152J130D01*
G01Y339336D01*
G03X989289Y339466I-200J0D01*
G01X989288Y339467D01*
G02X988918Y340454I1131J987D01*
G37*
G36*
G01X647411Y379065D02*
X647412D01*
G02Y370659I0J-4203D01*
G01X647411D01*
G02Y379065I0J4203D01*
G37*
G36*
G01X1275316Y384277D02*
X1275002D01*
G03X1274844Y384200I0J-200D01*
G02X1273659Y383621I-1185J923D01*
G02Y386625I0J1502D01*
G02X1274844Y386046I0J-1502D01*
G03X1275002Y385969I158J123D01*
G01X1275316D01*
G03X1275474Y386046I0J200D01*
G02X1276659Y386625I1185J-923D01*
G02Y383621I0J-1502D01*
G02X1275474Y384200I0J1502D01*
G03X1275316Y384277I-158J-123D01*
G37*
G36*
G01X1732403D02*
X1732089D01*
G03X1731931Y384200I0J-200D01*
G02X1730746Y383621I-1185J923D01*
G02Y386625I0J1502D01*
G02X1731931Y386046I0J-1502D01*
G03X1732089Y385969I158J123D01*
G01X1732403D01*
G03X1732561Y386046I0J200D01*
G02X1733746Y386625I1185J-923D01*
G02Y383621I0J-1502D01*
G02X1732561Y384200I0J1502D01*
G03X1732403Y384277I-158J-123D01*
G37*
G36*
G01X1331606Y388069D02*
G02X1332664Y387633I0J-1502D01*
G01X1332692Y387605D01*
X1332765Y387575D01*
X1333126D01*
X1333199Y387605D01*
X1333227Y387633D01*
G02X1334285Y388069I1058J-1066D01*
G02Y385065I0J-1502D01*
G02X1333227Y385501I0J1502D01*
G01X1333199Y385529D01*
X1333126Y385559D01*
X1332765D01*
X1332692Y385529D01*
X1332664Y385501D01*
G02X1331606Y385065I-1058J1066D01*
G02X1330536Y385513I0J1502D01*
G03X1330393Y385573I-143J-140D01*
G01X1330109D01*
G03X1329966Y385513I0J-200D01*
G02X1328896Y385065I-1070J1054D01*
G02Y388069I0J1502D01*
G02X1329966Y387621I0J-1502D01*
G03X1330109Y387561I143J140D01*
G01X1330393D01*
G03X1330536Y387621I0J200D01*
G02X1331606Y388069I1070J-1054D01*
G37*
G36*
G01X1319092Y387151D02*
G02X1322096I1502J0D01*
G02X1321726Y386164I-1501J0D01*
G01Y386163D01*
X1321725D01*
G03X1321677Y386033I152J-130D01*
G01Y385769D01*
G03X1321725Y385639I200J0D01*
G01X1321726Y385638D01*
G02Y383664I-1131J-987D01*
G01Y383663D01*
X1321725D01*
G03X1321677Y383533I152J-130D01*
G01Y383269D01*
G03X1321725Y383139I200J0D01*
G01X1321726Y383138D01*
G02X1322096Y382151I-1131J-987D01*
G02X1319092I-1502J0D01*
G02X1319462Y383138I1501J0D01*
G01Y383139D01*
X1319463D01*
G03X1319511Y383269I-152J130D01*
G01Y383533D01*
G03X1319463Y383663I-200J0D01*
G01X1319462Y383664D01*
G02Y385638I1131J987D01*
G01Y385639D01*
X1319463D01*
G03X1319511Y385769I-152J130D01*
G01Y386033D01*
G03X1319463Y386163I-200J0D01*
G01X1319462Y386164D01*
G02X1319092Y387151I1131J987D01*
G37*
G36*
G01X1776179D02*
G02X1779183I1502J0D01*
G02X1778813Y386164I-1501J0D01*
G01Y386163D01*
X1778812D01*
G03X1778764Y386033I152J-130D01*
G01Y385769D01*
G03X1778812Y385639I200J0D01*
G01X1778813Y385638D01*
G02Y383664I-1131J-987D01*
G01Y383663D01*
X1778812D01*
G03X1778764Y383533I152J-130D01*
G01Y383269D01*
G03X1778812Y383139I200J0D01*
G01X1778813Y383138D01*
G02X1779183Y382151I-1131J-987D01*
G02X1776179I-1502J0D01*
G02X1776549Y383138I1501J0D01*
G01Y383139D01*
X1776550D01*
G03X1776598Y383269I-152J130D01*
G01Y383533D01*
G03X1776550Y383663I-200J0D01*
G01X1776549Y383664D01*
G02Y385638I1131J987D01*
G01Y385639D01*
X1776550D01*
G03X1776598Y385769I-152J130D01*
G01Y386033D01*
G03X1776550Y386163I-200J0D01*
G01X1776549Y386164D01*
G02X1776179Y387151I1131J987D01*
G37*
G36*
G01X1314173Y386750D02*
X1313879D01*
G03X1313732Y386685I1J-200D01*
G02X1312626Y386200I-1106J1019D01*
G02Y389204I0J1502D01*
G02X1313732Y388719I0J-1504D01*
G03X1313879Y388654I148J135D01*
G01X1314173D01*
G03X1314320Y388719I-1J200D01*
G02X1315426Y389204I1106J-1019D01*
G02Y386200I0J-1502D01*
G02X1314320Y386685I0J1504D01*
G03X1314173Y386750I-148J-135D01*
G37*
G36*
G01X1771260D02*
X1770966D01*
G03X1770819Y386685I1J-200D01*
G02X1769713Y386200I-1106J1019D01*
G02Y389204I0J1502D01*
G02X1770819Y388719I0J-1504D01*
G03X1770966Y388654I148J135D01*
G01X1771260D01*
G03X1771407Y388719I-1J200D01*
G02X1772513Y389204I1106J-1019D01*
G02Y386200I0J-1502D01*
G02X1771407Y386685I0J1504D01*
G03X1771260Y386750I-148J-135D01*
G37*
G36*
G01X1304611Y388817D02*
G02X1306113Y390319I1502J0D01*
G02X1306968Y390052I0J-1502D01*
G01X1307002Y390029D01*
X1307083Y390012D01*
X1307450Y390092D01*
X1307517Y390140D01*
X1307538Y390175D01*
G02X1308826Y390904I1288J-773D01*
G02Y387900I0J-1502D01*
G02X1307971Y388167I0J1502D01*
G01X1307937Y388190D01*
X1307856Y388207D01*
X1307489Y388127D01*
X1307422Y388079D01*
X1307401Y388044D01*
G02X1307245Y387831I-1285J777D01*
G03X1307244Y387829I173J-88D01*
G03X1307196Y387699I152J-130D01*
G01Y387435D01*
G03X1307244Y387305I200J0D01*
G01X1307245Y387304D01*
G02Y385330I-1131J-987D01*
G01Y385329D01*
X1307244D01*
G03X1307196Y385199I152J-130D01*
G01Y384935D01*
G03X1307244Y384805I200J0D01*
G01X1307245Y384804D01*
G02X1307615Y383817I-1131J-987D01*
G02X1304611I-1502J0D01*
G02X1304981Y384804I1501J0D01*
G01Y384805D01*
X1304982D01*
G03X1305030Y384935I-152J130D01*
G01Y385199D01*
G03X1304982Y385329I-200J0D01*
G01X1304981Y385330D01*
G02Y387304I1131J987D01*
G01Y387305D01*
X1304982D01*
G03X1305030Y387435I-152J130D01*
G01Y387699D01*
G03X1304982Y387829I-200J0D01*
G01X1304981Y387830D01*
G02X1304611Y388817I1131J987D01*
G37*
G36*
G01X1761698D02*
G02X1763200Y390319I1502J0D01*
G02X1764055Y390052I0J-1502D01*
G01X1764089Y390029D01*
X1764170Y390012D01*
X1764537Y390092D01*
X1764604Y390140D01*
X1764625Y390175D01*
G02X1765913Y390904I1288J-773D01*
G02Y387900I0J-1502D01*
G02X1765058Y388167I0J1502D01*
G01X1765024Y388190D01*
X1764943Y388207D01*
X1764576Y388127D01*
X1764509Y388079D01*
X1764488Y388044D01*
G02X1764332Y387831I-1285J777D01*
G03X1764331Y387829I173J-88D01*
G03X1764283Y387699I152J-130D01*
G01Y387435D01*
G03X1764331Y387305I200J0D01*
G01X1764332Y387304D01*
G02Y385330I-1131J-987D01*
G01Y385329D01*
X1764331D01*
G03X1764283Y385199I152J-130D01*
G01Y384935D01*
G03X1764331Y384805I200J0D01*
G01X1764332Y384804D01*
G02X1764702Y383817I-1131J-987D01*
G02X1761698I-1502J0D01*
G02X1762068Y384804I1501J0D01*
G01Y384805D01*
X1762069D01*
G03X1762117Y384935I-152J130D01*
G01Y385199D01*
G03X1762069Y385329I-200J0D01*
G01X1762068Y385330D01*
G02Y387304I1131J987D01*
G01Y387305D01*
X1762069D01*
G03X1762117Y387435I-152J130D01*
G01Y387699D01*
G03X1762069Y387829I-200J0D01*
G01X1762068Y387830D01*
G02X1761698Y388817I1131J987D01*
G37*
G36*
G01X1297537Y396776D02*
G02Y399780I0J1502D01*
G02X1298524Y399410I0J-1501D01*
G01X1298525D01*
Y399409D01*
G03X1298655Y399361I130J152D01*
G01X1298919D01*
G03X1299049Y399409I0J200D01*
G01X1299050Y399410D01*
G02X1300037Y399780I987J-1131D01*
G02Y396776I0J-1502D01*
G02X1299050Y397146I0J1501D01*
G01X1299049D01*
Y397147D01*
G03X1298919Y397195I-130J-152D01*
G01X1298655D01*
G03X1298525Y397147I0J-200D01*
G01X1298524Y397146D01*
G02X1297537Y396776I-987J1131D01*
G37*
G36*
G01X1754624D02*
G02Y399780I0J1502D01*
G02X1755611Y399410I0J-1501D01*
G01X1755612D01*
Y399409D01*
G03X1755742Y399361I130J152D01*
G01X1756006D01*
G03X1756136Y399409I0J200D01*
G01X1756137Y399410D01*
G02X1757124Y399780I987J-1131D01*
G02Y396776I0J-1502D01*
G02X1756137Y397146I0J1501D01*
G01X1756136D01*
Y397147D01*
G03X1756006Y397195I-130J-152D01*
G01X1755742D01*
G03X1755612Y397147I0J-200D01*
G01X1755611Y397146D01*
G02X1754624Y396776I-987J1131D01*
G37*
G36*
G01X1295764Y400479D02*
G02Y403483I0J1502D01*
G02X1296751Y403113I0J-1501D01*
G01X1296752D01*
Y403112D01*
G03X1296882Y403064I130J152D01*
G01X1297146D01*
G03X1297276Y403112I0J200D01*
G01X1297277Y403113D01*
G02X1298264Y403483I987J-1131D01*
G02Y400479I0J-1502D01*
G02X1297277Y400849I0J1501D01*
G01X1297276D01*
Y400850D01*
G03X1297146Y400898I-130J-152D01*
G01X1296882D01*
G03X1296752Y400850I0J-200D01*
G01X1296751Y400849D01*
G02X1295764Y400479I-987J1131D01*
G37*
G36*
G01X1752851D02*
G02Y403483I0J1502D01*
G02X1753838Y403113I0J-1501D01*
G01X1753839D01*
Y403112D01*
G03X1753969Y403064I130J152D01*
G01X1754233D01*
G03X1754363Y403112I0J200D01*
G01X1754364Y403113D01*
G02X1755351Y403483I987J-1131D01*
G02Y400479I0J-1502D01*
G02X1754364Y400849I0J1501D01*
G01X1754363D01*
Y400850D01*
G03X1754233Y400898I-130J-152D01*
G01X1753969D01*
G03X1753839Y400850I0J-200D01*
G01X1753838Y400849D01*
G02X1752851Y400479I-987J1131D01*
G37*
G36*
G01X1344063Y409056D02*
X1344357D01*
G03X1344504Y409121I-1J200D01*
G02X1346716I1106J-1017D01*
G03X1346863Y409056I148J135D01*
G01X1347157D01*
G03X1347304Y409121I-1J200D01*
G02X1348410Y409606I1106J-1019D01*
G02Y406602I0J-1502D01*
G02X1347304Y407087I0J1504D01*
G03X1347157Y407152I-148J-135D01*
G01X1346863D01*
G03X1346716Y407087I1J-200D01*
G02X1344504I-1106J1017D01*
G03X1344357Y407152I-148J-135D01*
G01X1344063D01*
G03X1343916Y407087I1J-200D01*
G02X1342810Y406602I-1106J1019D01*
G02Y409606I0J1502D01*
G02X1343916Y409121I0J-1504D01*
G03X1344063Y409056I148J135D01*
G37*
G36*
G01X1801150D02*
X1801444D01*
G03X1801591Y409121I-1J200D01*
G02X1803803I1106J-1017D01*
G03X1803950Y409056I148J135D01*
G01X1804244D01*
G03X1804391Y409121I-1J200D01*
G02X1805497Y409606I1106J-1019D01*
G02Y406602I0J-1502D01*
G02X1804391Y407087I0J1504D01*
G03X1804244Y407152I-148J-135D01*
G01X1803950D01*
G03X1803803Y407087I1J-200D01*
G02X1801591I-1106J1017D01*
G03X1801444Y407152I-148J-135D01*
G01X1801150D01*
G03X1801003Y407087I1J-200D01*
G02X1799897Y406602I-1106J1019D01*
G02Y409606I0J1502D01*
G02X1801003Y409121I0J-1504D01*
G03X1801150Y409056I148J135D01*
G37*
G36*
G01X989890Y409230D02*
G02X991392Y410732I1502J0D01*
G02X992826Y409677I0J-1502D01*
G01Y409675D01*
G03X992875Y409595I190J62D01*
G01X996015Y406455D01*
G02X996398Y405531I-923J-924D01*
G01Y377831D01*
G03X996457Y377689I200J0D01*
G01X1008532Y365614D01*
G02X1008914Y364692I-924J-923D01*
G01Y346333D01*
G03X1008991Y346175I200J0D01*
G01X1009276Y345952D01*
X1009366Y345933D01*
X1009410Y345944D01*
G02X1009770Y345988I361J-1458D01*
G02X1011272Y344486I0J-1502D01*
G02X1009788Y342984I-1502J0D01*
G01X1009747D01*
X1009673Y342951D01*
X1009419Y342680D01*
X1009392Y342604D01*
X1009394Y342563D01*
G02X1009396Y342495I-1305J-72D01*
G01Y312096D01*
G03X1009455Y311954I200J0D01*
G01X1010864Y310545D01*
G03X1010944Y310496I142J141D01*
G01X1010945D01*
G02X1012001Y309062I-446J-1434D01*
G02X1010499Y307560I-1502J0D01*
G02X1009065Y308615I0J1502D01*
G01Y308617D01*
G03X1009016Y308697I-190J-62D01*
G01X1007165Y310548D01*
G02X1006782Y311472I923J924D01*
G01Y323345D01*
G03X1006659Y323530I-200J0D01*
G01X1006603Y323553D01*
X1006485Y323530D01*
X1004596Y321642D01*
G02X1003181Y321056I-1415J1415D01*
G02X1001180Y323057I0J2001D01*
G02X1001766Y324472I2001J0D01*
G01X1003781Y326488D01*
G03X1003840Y326630I-141J142D01*
G01Y330630D01*
G03X1003767Y330784I-200J0D01*
G01X1003494Y331009D01*
X1003408Y331031D01*
X1003364Y331022D01*
G02X1003076Y330994I-289J1474D01*
G02X1001574Y332496I0J1502D01*
G02X1002609Y333923I1501J0D01*
G03X1002715Y334004I-62J190D01*
G01X1002779Y334104D01*
G03X1002810Y334234I-168J109D01*
G02X1002798Y334451I1990J219D01*
G01Y348662D01*
G03X1002739Y348804I-200J0D01*
G01X999005Y352539D01*
G02X998418Y353954I1415J1416D01*
G02X1000420Y355956I2002J0D01*
G02X1001835Y355369I-1J-2002D01*
G01X1005961Y351244D01*
G03X1006178Y351201I141J142D01*
G01X1006235Y351224D01*
X1006302Y351325D01*
Y364066D01*
G03X1006243Y364208I-200J0D01*
G01X994167Y376283D01*
G02X993784Y377207I923J924D01*
G01Y404907D01*
G03X993725Y405049I-200J0D01*
G01X991027Y407747D01*
G03X990947Y407796I-142J-141D01*
G01X990946D01*
G02X989890Y409230I446J1434D01*
G37*
G36*
G01X1298605Y414743D02*
X1298606Y414742D01*
G03X1298736Y414694I130J152D01*
G01X1299000D01*
G03X1299130Y414742I0J200D01*
G01X1299131Y414743D01*
G02X1300118Y415113I987J-1131D01*
G02Y412109I0J-1502D01*
G02X1299131Y412479I0J1501D01*
G01X1299130D01*
Y412480D01*
G03X1299000Y412528I-130J-152D01*
G01X1298736D01*
G03X1298606Y412480I0J-200D01*
G01X1298605Y412479D01*
G02X1296631I-987J1131D01*
G01X1296630D01*
Y412480D01*
G03X1296500Y412528I-130J-152D01*
G01X1296236D01*
G03X1296106Y412480I0J-200D01*
G01X1296105Y412479D01*
G02X1294131I-987J1131D01*
G01X1294130D01*
Y412480D01*
G03X1294000Y412528I-130J-152D01*
G01X1293736D01*
G03X1293606Y412480I0J-200D01*
G01X1293605Y412479D01*
G02X1292618Y412109I-987J1131D01*
G02Y415113I0J1502D01*
G02X1293605Y414743I0J-1501D01*
G01X1293606D01*
Y414742D01*
G03X1293736Y414694I130J152D01*
G01X1294000D01*
G03X1294130Y414742I0J200D01*
G01X1294131Y414743D01*
G02X1296105I987J-1131D01*
G01X1296106D01*
Y414742D01*
G03X1296236Y414694I130J152D01*
G01X1296500D01*
G03X1296630Y414742I0J200D01*
G01X1296631Y414743D01*
G02X1298605I987J-1131D01*
G37*
G36*
G01X1755692D02*
X1755693Y414742D01*
G03X1755823Y414694I130J152D01*
G01X1756087D01*
G03X1756217Y414742I0J200D01*
G01X1756218Y414743D01*
G02X1757205Y415113I987J-1131D01*
G02Y412109I0J-1502D01*
G02X1756218Y412479I0J1501D01*
G01X1756217D01*
Y412480D01*
G03X1756087Y412528I-130J-152D01*
G01X1755823D01*
G03X1755693Y412480I0J-200D01*
G01X1755692Y412479D01*
G02X1753718I-987J1131D01*
G01X1753717D01*
Y412480D01*
G03X1753587Y412528I-130J-152D01*
G01X1753323D01*
G03X1753193Y412480I0J-200D01*
G01X1753192Y412479D01*
G02X1751218I-987J1131D01*
G01X1751217D01*
Y412480D01*
G03X1751087Y412528I-130J-152D01*
G01X1750823D01*
G03X1750693Y412480I0J-200D01*
G01X1750692Y412479D01*
G02X1749705Y412109I-987J1131D01*
G02Y415113I0J1502D01*
G02X1750692Y414743I0J-1501D01*
G01X1750693D01*
Y414742D01*
G03X1750823Y414694I130J152D01*
G01X1751087D01*
G03X1751217Y414742I0J200D01*
G01X1751218Y414743D01*
G02X1753192I987J-1131D01*
G01X1753193D01*
Y414742D01*
G03X1753323Y414694I130J152D01*
G01X1753587D01*
G03X1753717Y414742I0J200D01*
G01X1753718Y414743D01*
G02X1755692I987J-1131D01*
G37*
G36*
G01X1343780Y421327D02*
X1344074D01*
G03X1344221Y421392I-1J200D01*
G02X1346433I1106J-1017D01*
G03X1346580Y421327I148J135D01*
G01X1346874D01*
G03X1347021Y421392I-1J200D01*
G02X1348127Y421877I1106J-1019D01*
G02Y418873I0J-1502D01*
G02X1347021Y419358I0J1504D01*
G03X1346874Y419423I-148J-135D01*
G01X1346580D01*
G03X1346433Y419358I1J-200D01*
G02X1344221I-1106J1017D01*
G03X1344074Y419423I-148J-135D01*
G01X1343780D01*
G03X1343633Y419358I1J-200D01*
G02X1342527Y418873I-1106J1019D01*
G02Y421877I0J1502D01*
G02X1343633Y421392I0J-1504D01*
G03X1343780Y421327I148J135D01*
G37*
G36*
G01X1800867D02*
X1801161D01*
G03X1801308Y421392I-1J200D01*
G02X1803520I1106J-1017D01*
G03X1803667Y421327I148J135D01*
G01X1803961D01*
G03X1804108Y421392I-1J200D01*
G02X1805214Y421877I1106J-1019D01*
G02Y418873I0J-1502D01*
G02X1804108Y419358I0J1504D01*
G03X1803961Y419423I-148J-135D01*
G01X1803667D01*
G03X1803520Y419358I1J-200D01*
G02X1801308I-1106J1017D01*
G03X1801161Y419423I-148J-135D01*
G01X1800867D01*
G03X1800720Y419358I1J-200D01*
G02X1799614Y418873I-1106J1019D01*
G02Y421877I0J1502D01*
G02X1800720Y421392I0J-1504D01*
G03X1800867Y421327I148J135D01*
G37*
G36*
G01X1266826Y421489D02*
G02X1269830I1502J0D01*
G02X1269424Y420462I-1502J0D01*
G01X1269398Y420435D01*
X1269370Y420364D01*
Y420014D01*
X1269398Y419943D01*
X1269424Y419916D01*
G02Y417862I-1096J-1027D01*
G01X1269398Y417835D01*
X1269370Y417764D01*
Y417414D01*
X1269398Y417343D01*
X1269424Y417316D01*
G02X1269830Y416289I-1096J-1027D01*
G02X1266826I-1502J0D01*
G02X1267232Y417316I1502J0D01*
G01X1267258Y417343D01*
X1267286Y417414D01*
Y417764D01*
X1267258Y417835D01*
X1267232Y417862D01*
G02Y419916I1096J1027D01*
G01X1267258Y419943D01*
X1267286Y420014D01*
Y420364D01*
X1267258Y420435D01*
X1267232Y420462D01*
G02X1266826Y421489I1096J1027D01*
G37*
G36*
G01X1723913D02*
G02X1726917I1502J0D01*
G02X1726511Y420462I-1502J0D01*
G01X1726485Y420435D01*
X1726457Y420364D01*
Y420014D01*
X1726485Y419943D01*
X1726511Y419916D01*
G02Y417862I-1096J-1027D01*
G01X1726485Y417835D01*
X1726457Y417764D01*
Y417414D01*
X1726485Y417343D01*
X1726511Y417316D01*
G02X1726917Y416289I-1096J-1027D01*
G02X1723913I-1502J0D01*
G02X1724319Y417316I1502J0D01*
G01X1724345Y417343D01*
X1724373Y417414D01*
Y417764D01*
X1724345Y417835D01*
X1724319Y417862D01*
G02Y419916I1096J1027D01*
G01X1724345Y419943D01*
X1724373Y420014D01*
Y420364D01*
X1724345Y420435D01*
X1724319Y420462D01*
G02X1723913Y421489I1096J1027D01*
G37*
G36*
G01X1251743Y422088D02*
G02X1254747I1502J0D01*
G02X1254341Y421061I-1502J0D01*
G01X1254315Y421034D01*
X1254287Y420963D01*
Y420613D01*
X1254315Y420542D01*
X1254341Y420515D01*
G02Y418461I-1096J-1027D01*
G01X1254315Y418434D01*
X1254287Y418363D01*
Y418013D01*
X1254315Y417942D01*
X1254341Y417915D01*
G02X1254747Y416888I-1096J-1027D01*
G02X1251743I-1502J0D01*
G02X1252149Y417915I1502J0D01*
G01X1252175Y417942D01*
X1252203Y418013D01*
Y418363D01*
X1252175Y418434D01*
X1252149Y418461D01*
G02Y420515I1096J1027D01*
G01X1252175Y420542D01*
X1252203Y420613D01*
Y420963D01*
X1252175Y421034D01*
X1252149Y421061D01*
G02X1251743Y422088I1096J1027D01*
G37*
G36*
G01X1298370Y425199D02*
X1298371Y425198D01*
G03X1298501Y425150I130J152D01*
G01X1298765D01*
G03X1298895Y425198I0J200D01*
G01X1298896Y425199D01*
G02X1299883Y425569I987J-1131D01*
G02Y422565I0J-1502D01*
G02X1298896Y422935I0J1501D01*
G01X1298895D01*
Y422936D01*
G03X1298765Y422984I-130J-152D01*
G01X1298501D01*
G03X1298371Y422936I0J-200D01*
G01X1298370Y422935D01*
G02X1296396I-987J1131D01*
G01X1296395D01*
Y422936D01*
G03X1296265Y422984I-130J-152D01*
G01X1296001D01*
G03X1295871Y422936I0J-200D01*
G01X1295870Y422935D01*
G02X1293896I-987J1131D01*
G01X1293895D01*
Y422936D01*
G03X1293765Y422984I-130J-152D01*
G01X1293501D01*
G03X1293371Y422936I0J-200D01*
G01X1293370Y422935D01*
G02X1292383Y422565I-987J1131D01*
G02Y425569I0J1502D01*
G02X1293370Y425199I0J-1501D01*
G01X1293371D01*
Y425198D01*
G03X1293501Y425150I130J152D01*
G01X1293765D01*
G03X1293895Y425198I0J200D01*
G01X1293896Y425199D01*
G02X1295870I987J-1131D01*
G01X1295871D01*
Y425198D01*
G03X1296001Y425150I130J152D01*
G01X1296265D01*
G03X1296395Y425198I0J200D01*
G01X1296396Y425199D01*
G02X1298370I987J-1131D01*
G37*
G36*
G01X1755457D02*
X1755458Y425198D01*
G03X1755588Y425150I130J152D01*
G01X1755852D01*
G03X1755982Y425198I0J200D01*
G01X1755983Y425199D01*
G02X1756970Y425569I987J-1131D01*
G02Y422565I0J-1502D01*
G02X1755983Y422935I0J1501D01*
G01X1755982D01*
Y422936D01*
G03X1755852Y422984I-130J-152D01*
G01X1755588D01*
G03X1755458Y422936I0J-200D01*
G01X1755457Y422935D01*
G02X1753483I-987J1131D01*
G01X1753482D01*
Y422936D01*
G03X1753352Y422984I-130J-152D01*
G01X1753088D01*
G03X1752958Y422936I0J-200D01*
G01X1752957Y422935D01*
G02X1750983I-987J1131D01*
G01X1750982D01*
Y422936D01*
G03X1750852Y422984I-130J-152D01*
G01X1750588D01*
G03X1750458Y422936I0J-200D01*
G01X1750457Y422935D01*
G02X1749470Y422565I-987J1131D01*
G02Y425569I0J1502D01*
G02X1750457Y425199I0J-1501D01*
G01X1750458D01*
Y425198D01*
G03X1750588Y425150I130J152D01*
G01X1750852D01*
G03X1750982Y425198I0J200D01*
G01X1750983Y425199D01*
G02X1752957I987J-1131D01*
G01X1752958D01*
Y425198D01*
G03X1753088Y425150I130J152D01*
G01X1753352D01*
G03X1753482Y425198I0J200D01*
G01X1753483Y425199D01*
G02X1755457I987J-1131D01*
G37*
G36*
G01X1270326Y426689D02*
G02X1273330I1502J0D01*
G02X1272924Y425662I-1502J0D01*
G01X1272898Y425635D01*
X1272870Y425564D01*
Y425214D01*
X1272898Y425143D01*
X1272924Y425116D01*
G02Y423062I-1096J-1027D01*
G01X1272898Y423035D01*
X1272870Y422964D01*
Y422614D01*
X1272898Y422543D01*
X1272924Y422516D01*
G02Y420462I-1096J-1027D01*
G01X1272898Y420435D01*
X1272870Y420364D01*
Y420014D01*
X1272898Y419943D01*
X1272924Y419916D01*
G02Y417862I-1096J-1027D01*
G01X1272898Y417835D01*
X1272870Y417764D01*
Y417414D01*
X1272898Y417343D01*
X1272924Y417316D01*
G02Y415262I-1096J-1027D01*
G01X1272898Y415235D01*
X1272870Y415164D01*
Y414814D01*
X1272898Y414743D01*
X1272924Y414716D01*
G02Y412662I-1096J-1027D01*
G01X1272898Y412635D01*
X1272870Y412564D01*
Y412214D01*
X1272898Y412143D01*
X1272924Y412116D01*
G02Y410062I-1096J-1027D01*
G01X1272898Y410035D01*
X1272870Y409964D01*
Y409614D01*
X1272898Y409543D01*
X1272924Y409516D01*
G02Y407462I-1096J-1027D01*
G01X1272898Y407435D01*
X1272870Y407364D01*
Y407014D01*
X1272898Y406943D01*
X1272924Y406916D01*
G02X1273330Y405889I-1096J-1027D01*
G02X1273110Y405108I-1502J2D01*
G01Y405106D01*
X1273109D01*
G03X1273086Y404958I172J-103D01*
G01X1273158Y404647D01*
X1273202Y404583D01*
X1273235Y404562D01*
G02X1273923Y403300I-813J-1262D01*
G02X1270919I-1502J0D01*
G02X1271139Y404081I1502J-2D01*
G01Y404083D01*
X1271140D01*
G03X1271163Y404231I-172J103D01*
G01X1271091Y404542D01*
X1271047Y404606D01*
X1271014Y404627D01*
G02X1270326Y405889I813J1262D01*
G02X1270732Y406916I1502J0D01*
G01X1270758Y406943D01*
X1270786Y407014D01*
Y407364D01*
X1270758Y407435D01*
X1270732Y407462D01*
G02Y409516I1096J1027D01*
G01X1270758Y409543D01*
X1270786Y409614D01*
Y409964D01*
X1270758Y410035D01*
X1270732Y410062D01*
G02Y412116I1096J1027D01*
G01X1270758Y412143D01*
X1270786Y412214D01*
Y412564D01*
X1270758Y412635D01*
X1270732Y412662D01*
G02Y414716I1096J1027D01*
G01X1270758Y414743D01*
X1270786Y414814D01*
Y415164D01*
X1270758Y415235D01*
X1270732Y415262D01*
G02Y417316I1096J1027D01*
G01X1270758Y417343D01*
X1270786Y417414D01*
Y417764D01*
X1270758Y417835D01*
X1270732Y417862D01*
G02Y419916I1096J1027D01*
G01X1270758Y419943D01*
X1270786Y420014D01*
Y420364D01*
X1270758Y420435D01*
X1270732Y420462D01*
G02Y422516I1096J1027D01*
G01X1270758Y422543D01*
X1270786Y422614D01*
Y422964D01*
X1270758Y423035D01*
X1270732Y423062D01*
G02Y425116I1096J1027D01*
G01X1270758Y425143D01*
X1270786Y425214D01*
Y425564D01*
X1270758Y425635D01*
X1270732Y425662D01*
G02X1270326Y426689I1096J1027D01*
G37*
G36*
G01X1727413D02*
G02X1730417I1502J0D01*
G02X1730011Y425662I-1502J0D01*
G01X1729985Y425635D01*
X1729957Y425564D01*
Y425214D01*
X1729985Y425143D01*
X1730011Y425116D01*
G02Y423062I-1096J-1027D01*
G01X1729985Y423035D01*
X1729957Y422964D01*
Y422614D01*
X1729985Y422543D01*
X1730011Y422516D01*
G02Y420462I-1096J-1027D01*
G01X1729985Y420435D01*
X1729957Y420364D01*
Y420014D01*
X1729985Y419943D01*
X1730011Y419916D01*
G02Y417862I-1096J-1027D01*
G01X1729985Y417835D01*
X1729957Y417764D01*
Y417414D01*
X1729985Y417343D01*
X1730011Y417316D01*
G02Y415262I-1096J-1027D01*
G01X1729985Y415235D01*
X1729957Y415164D01*
Y414814D01*
X1729985Y414743D01*
X1730011Y414716D01*
G02Y412662I-1096J-1027D01*
G01X1729985Y412635D01*
X1729957Y412564D01*
Y412214D01*
X1729985Y412143D01*
X1730011Y412116D01*
G02Y410062I-1096J-1027D01*
G01X1729985Y410035D01*
X1729957Y409964D01*
Y409614D01*
X1729985Y409543D01*
X1730011Y409516D01*
G02Y407462I-1096J-1027D01*
G01X1729985Y407435D01*
X1729957Y407364D01*
Y407014D01*
X1729985Y406943D01*
X1730011Y406916D01*
G02X1730417Y405889I-1096J-1027D01*
G02X1730197Y405108I-1502J2D01*
G01Y405106D01*
X1730196D01*
G03X1730173Y404958I172J-103D01*
G01X1730245Y404647D01*
X1730289Y404583D01*
X1730322Y404562D01*
G02X1731010Y403300I-813J-1262D01*
G02X1728006I-1502J0D01*
G02X1728226Y404081I1502J-2D01*
G01Y404083D01*
X1728227D01*
G03X1728250Y404231I-172J103D01*
G01X1728178Y404542D01*
X1728134Y404606D01*
X1728101Y404627D01*
G02X1727413Y405889I813J1262D01*
G02X1727819Y406916I1502J0D01*
G01X1727845Y406943D01*
X1727873Y407014D01*
Y407364D01*
X1727845Y407435D01*
X1727819Y407462D01*
G02Y409516I1096J1027D01*
G01X1727845Y409543D01*
X1727873Y409614D01*
Y409964D01*
X1727845Y410035D01*
X1727819Y410062D01*
G02Y412116I1096J1027D01*
G01X1727845Y412143D01*
X1727873Y412214D01*
Y412564D01*
X1727845Y412635D01*
X1727819Y412662D01*
G02Y414716I1096J1027D01*
G01X1727845Y414743D01*
X1727873Y414814D01*
Y415164D01*
X1727845Y415235D01*
X1727819Y415262D01*
G02Y417316I1096J1027D01*
G01X1727845Y417343D01*
X1727873Y417414D01*
Y417764D01*
X1727845Y417835D01*
X1727819Y417862D01*
G02Y419916I1096J1027D01*
G01X1727845Y419943D01*
X1727873Y420014D01*
Y420364D01*
X1727845Y420435D01*
X1727819Y420462D01*
G02Y422516I1096J1027D01*
G01X1727845Y422543D01*
X1727873Y422614D01*
Y422964D01*
X1727845Y423035D01*
X1727819Y423062D01*
G02Y425116I1096J1027D01*
G01X1727845Y425143D01*
X1727873Y425214D01*
Y425564D01*
X1727845Y425635D01*
X1727819Y425662D01*
G02X1727413Y426689I1096J1027D01*
G37*
G36*
G01X1334886Y427439D02*
G02X1337890I1502J0D01*
G02X1337520Y426452I-1501J0D01*
G01Y426451D01*
X1337519D01*
G03X1337471Y426321I152J-130D01*
G01Y426057D01*
G03X1337519Y425927I200J0D01*
G01X1337520Y425926D01*
G02X1337890Y424939I-1131J-987D01*
G02X1334886I-1502J0D01*
G02X1335256Y425926I1501J0D01*
G01Y425927D01*
X1335257D01*
G03X1335305Y426057I-152J130D01*
G01Y426321D01*
G03X1335257Y426451I-200J0D01*
G01X1335256Y426452D01*
G02X1334886Y427439I1131J987D01*
G37*
G36*
G01X1791973D02*
G02X1794977I1502J0D01*
G02X1794607Y426452I-1501J0D01*
G01Y426451D01*
X1794606D01*
G03X1794558Y426321I152J-130D01*
G01Y426057D01*
G03X1794606Y425927I200J0D01*
G01X1794607Y425926D01*
G02X1794977Y424939I-1131J-987D01*
G02X1791973I-1502J0D01*
G02X1792343Y425926I1501J0D01*
G01Y425927D01*
X1792344D01*
G03X1792392Y426057I-152J130D01*
G01Y426321D01*
G03X1792344Y426451I-200J0D01*
G01X1792343Y426452D01*
G02X1791973Y427439I1131J987D01*
G37*
G36*
G01X1373898Y435192D02*
G02X1376902I1502J0D01*
G02X1376328Y434011I-1502J0D01*
G01X1376292Y433983D01*
X1376252Y433902D01*
X1376247Y433500D01*
X1376285Y433418D01*
X1376320Y433389D01*
G02X1376862Y432234I-960J-1155D01*
G02X1373858I-1502J0D01*
G02X1374432Y433415I1502J0D01*
G01X1374468Y433443D01*
X1374508Y433524D01*
X1374513Y433926D01*
X1374475Y434008D01*
X1374440Y434037D01*
G02X1373898Y435192I960J1155D01*
G37*
G36*
G01X1271263Y433971D02*
Y434265D01*
G03X1271198Y434412I-200J-1D01*
G02X1270713Y435518I1019J1106D01*
G02X1273717I1502J0D01*
G02X1273232Y434412I-1504J0D01*
G03X1273167Y434265I135J-148D01*
G01Y433971D01*
G03X1273232Y433824I200J1D01*
G02X1273717Y432718I-1019J-1106D01*
G02X1270713I-1502J0D01*
G02X1271198Y433824I1504J0D01*
G03X1271263Y433971I-135J148D01*
G37*
G36*
G01X1728350D02*
Y434265D01*
G03X1728285Y434412I-200J-1D01*
G02X1727800Y435518I1019J1106D01*
G02X1730804I1502J0D01*
G02X1730319Y434412I-1504J0D01*
G03X1730254Y434265I135J-148D01*
G01Y433971D01*
G03X1730319Y433824I200J1D01*
G02X1730804Y432718I-1019J-1106D01*
G02X1727800I-1502J0D01*
G02X1728285Y433824I1504J0D01*
G03X1728350Y433971I-135J148D01*
G37*
G36*
G01X823601Y435558D02*
G02X826605I1502J0D01*
G02X826199Y434531I-1502J0D01*
G01X826173Y434504D01*
X826145Y434433D01*
Y434083D01*
X826173Y434012D01*
X826199Y433985D01*
G02Y431931I-1096J-1027D01*
G01X826173Y431904D01*
X826145Y431833D01*
Y431483D01*
X826173Y431412D01*
X826199Y431385D01*
G02X826605Y430358I-1096J-1027D01*
G02X823601I-1502J0D01*
G02X824007Y431385I1502J0D01*
G01X824033Y431412D01*
X824061Y431483D01*
Y431833D01*
X824033Y431904D01*
X824007Y431931D01*
G02Y433985I1096J1027D01*
G01X824033Y434012D01*
X824061Y434083D01*
Y434433D01*
X824033Y434504D01*
X824007Y434531D01*
G02X823601Y435558I1096J1027D01*
G37*
G36*
G01X829876Y435686D02*
G02X832880I1502J0D01*
G02X832474Y434659I-1502J0D01*
G01X832448Y434632D01*
X832420Y434561D01*
Y434211D01*
X832448Y434140D01*
X832474Y434113D01*
G02Y432059I-1096J-1027D01*
G01X832448Y432032D01*
X832420Y431961D01*
Y431611D01*
X832448Y431540D01*
X832474Y431513D01*
G02X832880Y430486I-1096J-1027D01*
G02X829876I-1502J0D01*
G02X830282Y431513I1502J0D01*
G01X830308Y431540D01*
X830336Y431611D01*
Y431961D01*
X830308Y432032D01*
X830282Y432059D01*
G02Y434113I1096J1027D01*
G01X830308Y434140D01*
X830336Y434211D01*
Y434561D01*
X830308Y434632D01*
X830282Y434659D01*
G02X829876Y435686I1096J1027D01*
G37*
G36*
G01X748037Y440869D02*
G02X749539Y442371I1502J0D01*
G02X750645Y441886I0J-1504D01*
G03X750792Y441821I148J135D01*
G01X751086D01*
G03X751233Y441886I-1J200D01*
G02X752339Y442371I1106J-1019D01*
G02X753841Y440869I0J-1502D01*
G02X753435Y439842I-1502J0D01*
G01X753409Y439815D01*
X753381Y439744D01*
Y439394D01*
X753409Y439323D01*
X753435Y439296D01*
G02Y437242I-1096J-1027D01*
G01X753409Y437215D01*
X753381Y437144D01*
Y436794D01*
X753409Y436723D01*
X753435Y436696D01*
G02Y434642I-1096J-1027D01*
G01X753409Y434615D01*
X753381Y434544D01*
Y434194D01*
X753409Y434123D01*
X753435Y434096D01*
G02Y432042I-1096J-1027D01*
G01X753409Y432015D01*
X753381Y431944D01*
Y431594D01*
X753409Y431523D01*
X753435Y431496D01*
G02X753841Y430469I-1096J-1027D01*
G02X752339Y428967I-1502J0D01*
G02X751233Y429452I0J1504D01*
G03X751086Y429517I-148J-135D01*
G01X750792D01*
G03X750645Y429452I1J-200D01*
G02X749539Y428967I-1106J1019D01*
G02X748037Y430469I0J1502D01*
G02X748443Y431496I1502J0D01*
G01X748469Y431523D01*
X748497Y431594D01*
Y431944D01*
X748469Y432015D01*
X748443Y432042D01*
G02Y434096I1096J1027D01*
G01X748469Y434123D01*
X748497Y434194D01*
Y434544D01*
X748469Y434615D01*
X748443Y434642D01*
G02Y436696I1096J1027D01*
G01X748469Y436723D01*
X748497Y436794D01*
Y437144D01*
X748469Y437215D01*
X748443Y437242D01*
G02Y439296I1096J1027D01*
G01X748469Y439323D01*
X748497Y439394D01*
Y439744D01*
X748469Y439815D01*
X748443Y439842D01*
G02X748037Y440869I1096J1027D01*
G37*
G36*
G01X1205124D02*
G02X1206626Y442371I1502J0D01*
G02X1207732Y441886I0J-1504D01*
G03X1207879Y441821I148J135D01*
G01X1208173D01*
G03X1208320Y441886I-1J200D01*
G02X1209426Y442371I1106J-1019D01*
G02X1210928Y440869I0J-1502D01*
G02X1210522Y439842I-1502J0D01*
G01X1210496Y439815D01*
X1210468Y439744D01*
Y439394D01*
X1210496Y439323D01*
X1210522Y439296D01*
G02Y437242I-1096J-1027D01*
G01X1210496Y437215D01*
X1210468Y437144D01*
Y436794D01*
X1210496Y436723D01*
X1210522Y436696D01*
G02Y434642I-1096J-1027D01*
G01X1210496Y434615D01*
X1210468Y434544D01*
Y434194D01*
X1210496Y434123D01*
X1210522Y434096D01*
G02Y432042I-1096J-1027D01*
G01X1210496Y432015D01*
X1210468Y431944D01*
Y431594D01*
X1210496Y431523D01*
X1210522Y431496D01*
G02X1210928Y430469I-1096J-1027D01*
G02X1209426Y428967I-1502J0D01*
G02X1208320Y429452I0J1504D01*
G03X1208173Y429517I-148J-135D01*
G01X1207879D01*
G03X1207732Y429452I1J-200D01*
G02X1206626Y428967I-1106J1019D01*
G02X1205124Y430469I0J1502D01*
G02X1205530Y431496I1502J0D01*
G01X1205556Y431523D01*
X1205584Y431594D01*
Y431944D01*
X1205556Y432015D01*
X1205530Y432042D01*
G02Y434096I1096J1027D01*
G01X1205556Y434123D01*
X1205584Y434194D01*
Y434544D01*
X1205556Y434615D01*
X1205530Y434642D01*
G02Y436696I1096J1027D01*
G01X1205556Y436723D01*
X1205584Y436794D01*
Y437144D01*
X1205556Y437215D01*
X1205530Y437242D01*
G02Y439296I1096J1027D01*
G01X1205556Y439323D01*
X1205584Y439394D01*
Y439744D01*
X1205556Y439815D01*
X1205530Y439842D01*
G02X1205124Y440869I1096J1027D01*
G37*
G36*
G01X1662211D02*
G02X1663713Y442371I1502J0D01*
G02X1664819Y441886I0J-1504D01*
G03X1664966Y441821I148J135D01*
G01X1665260D01*
G03X1665407Y441886I-1J200D01*
G02X1666513Y442371I1106J-1019D01*
G02X1668015Y440869I0J-1502D01*
G02X1667609Y439842I-1502J0D01*
G01X1667583Y439815D01*
X1667555Y439744D01*
Y439394D01*
X1667583Y439323D01*
X1667609Y439296D01*
G02Y437242I-1096J-1027D01*
G01X1667583Y437215D01*
X1667555Y437144D01*
Y436794D01*
X1667583Y436723D01*
X1667609Y436696D01*
G02Y434642I-1096J-1027D01*
G01X1667583Y434615D01*
X1667555Y434544D01*
Y434194D01*
X1667583Y434123D01*
X1667609Y434096D01*
G02Y432042I-1096J-1027D01*
G01X1667583Y432015D01*
X1667555Y431944D01*
Y431594D01*
X1667583Y431523D01*
X1667609Y431496D01*
G02X1668015Y430469I-1096J-1027D01*
G02X1666513Y428967I-1502J0D01*
G02X1665407Y429452I0J1504D01*
G03X1665260Y429517I-148J-135D01*
G01X1664966D01*
G03X1664819Y429452I1J-200D01*
G02X1663713Y428967I-1106J1019D01*
G02X1662211Y430469I0J1502D01*
G02X1662617Y431496I1502J0D01*
G01X1662643Y431523D01*
X1662671Y431594D01*
Y431944D01*
X1662643Y432015D01*
X1662617Y432042D01*
G02Y434096I1096J1027D01*
G01X1662643Y434123D01*
X1662671Y434194D01*
Y434544D01*
X1662643Y434615D01*
X1662617Y434642D01*
G02Y436696I1096J1027D01*
G01X1662643Y436723D01*
X1662671Y436794D01*
Y437144D01*
X1662643Y437215D01*
X1662617Y437242D01*
G02Y439296I1096J1027D01*
G01X1662643Y439323D01*
X1662671Y439394D01*
Y439744D01*
X1662643Y439815D01*
X1662617Y439842D01*
G02X1662211Y440869I1096J1027D01*
G37*
G36*
G01X1281140Y440571D02*
Y440865D01*
G03X1281075Y441012I-200J-1D01*
G02X1280590Y442118I1019J1106D01*
G02X1283594I1502J0D01*
G02X1283109Y441012I-1504J0D01*
G03X1283044Y440865I135J-148D01*
G01Y440571D01*
G03X1283109Y440424I200J1D01*
G02X1283594Y439318I-1019J-1106D01*
G02X1280590I-1502J0D01*
G02X1281075Y440424I1504J0D01*
G03X1281140Y440571I-135J148D01*
G37*
G36*
G01X1289140D02*
Y440865D01*
G03X1289075Y441012I-200J-1D01*
G02X1288590Y442118I1019J1106D01*
G02X1291594I1502J0D01*
G02X1291109Y441012I-1504J0D01*
G03X1291044Y440865I135J-148D01*
G01Y440571D01*
G03X1291109Y440424I200J1D01*
G02X1291594Y439318I-1019J-1106D01*
G02X1288590I-1502J0D01*
G02X1289075Y440424I1504J0D01*
G03X1289140Y440571I-135J148D01*
G37*
G36*
G01X1738227D02*
Y440865D01*
G03X1738162Y441012I-200J-1D01*
G02X1737677Y442118I1019J1106D01*
G02X1740681I1502J0D01*
G02X1740196Y441012I-1504J0D01*
G03X1740131Y440865I135J-148D01*
G01Y440571D01*
G03X1740196Y440424I200J1D01*
G02X1740681Y439318I-1019J-1106D01*
G02X1737677I-1502J0D01*
G02X1738162Y440424I1504J0D01*
G03X1738227Y440571I-135J148D01*
G37*
G36*
G01X1746227D02*
Y440865D01*
G03X1746162Y441012I-200J-1D01*
G02X1745677Y442118I1019J1106D01*
G02X1748681I1502J0D01*
G02X1748196Y441012I-1504J0D01*
G03X1748131Y440865I135J-148D01*
G01Y440571D01*
G03X1748196Y440424I200J1D01*
G02X1748681Y439318I-1019J-1106D01*
G02X1745677I-1502J0D01*
G02X1746162Y440424I1504J0D01*
G03X1746227Y440571I-135J148D01*
G37*
G36*
G01X1325345Y442174D02*
Y442468D01*
G03X1325280Y442615I-200J-1D01*
G02X1324795Y443721I1019J1106D01*
G02X1326297Y445223I1502J0D01*
G02X1327403Y444738I0J-1504D01*
G03X1327550Y444673I148J135D01*
G01X1327844D01*
G03X1327991Y444738I-1J200D01*
G02X1329097Y445223I1106J-1019D01*
G02X1330599Y443721I0J-1502D01*
G02X1330114Y442615I-1504J0D01*
G03X1330049Y442468I135J-148D01*
G01Y442174D01*
G03X1330114Y442027I200J1D01*
G02Y439815I-1017J-1106D01*
G03X1330049Y439668I135J-148D01*
G01Y439374D01*
G03X1330114Y439227I200J1D01*
G02Y437015I-1017J-1106D01*
G03X1330049Y436868I135J-148D01*
G01Y436574D01*
G03X1330114Y436427I200J1D01*
G02X1330599Y435321I-1019J-1106D01*
G02X1329097Y433819I-1502J0D01*
G02X1327991Y434304I0J1504D01*
G03X1327844Y434369I-148J-135D01*
G01X1327550D01*
G03X1327403Y434304I1J-200D01*
G02X1326297Y433819I-1106J1019D01*
G02X1324795Y435321I0J1502D01*
G02X1325280Y436427I1504J0D01*
G03X1325345Y436574I-135J148D01*
G01Y436868D01*
G03X1325280Y437015I-200J-1D01*
G02Y439227I1017J1106D01*
G03X1325345Y439374I-135J148D01*
G01Y439668D01*
G03X1325280Y439815I-200J-1D01*
G02Y442027I1017J1106D01*
G03X1325345Y442174I-135J148D01*
G37*
G36*
G01X1782432D02*
Y442468D01*
G03X1782367Y442615I-200J-1D01*
G02X1781882Y443721I1019J1106D01*
G02X1783384Y445223I1502J0D01*
G02X1784490Y444738I0J-1504D01*
G03X1784637Y444673I148J135D01*
G01X1784931D01*
G03X1785078Y444738I-1J200D01*
G02X1786184Y445223I1106J-1019D01*
G02X1787686Y443721I0J-1502D01*
G02X1787201Y442615I-1504J0D01*
G03X1787136Y442468I135J-148D01*
G01Y442174D01*
G03X1787201Y442027I200J1D01*
G02Y439815I-1017J-1106D01*
G03X1787136Y439668I135J-148D01*
G01Y439374D01*
G03X1787201Y439227I200J1D01*
G02Y437015I-1017J-1106D01*
G03X1787136Y436868I135J-148D01*
G01Y436574D01*
G03X1787201Y436427I200J1D01*
G02X1787686Y435321I-1019J-1106D01*
G02X1786184Y433819I-1502J0D01*
G02X1785078Y434304I0J1504D01*
G03X1784931Y434369I-148J-135D01*
G01X1784637D01*
G03X1784490Y434304I1J-200D01*
G02X1783384Y433819I-1106J1019D01*
G02X1781882Y435321I0J1502D01*
G02X1782367Y436427I1504J0D01*
G03X1782432Y436574I-135J148D01*
G01Y436868D01*
G03X1782367Y437015I-200J-1D01*
G02Y439227I1017J1106D01*
G03X1782432Y439374I-135J148D01*
G01Y439668D01*
G03X1782367Y439815I-200J-1D01*
G02Y442027I1017J1106D01*
G03X1782432Y442174I-135J148D01*
G37*
G36*
G01X1298805Y442346D02*
Y442640D01*
G03X1298740Y442787I-200J-1D01*
G02X1298255Y443893I1019J1106D01*
G02X1301259I1502J0D01*
G02X1300774Y442787I-1504J0D01*
G03X1300709Y442640I135J-148D01*
G01Y442346D01*
G03X1300774Y442199I200J1D01*
G02Y439987I-1017J-1106D01*
G03X1300709Y439840I135J-148D01*
G01Y439546D01*
G03X1300774Y439399I200J1D01*
G02X1301259Y438293I-1019J-1106D01*
G02X1298255I-1502J0D01*
G02X1298740Y439399I1504J0D01*
G03X1298805Y439546I-135J148D01*
G01Y439840D01*
G03X1298740Y439987I-200J-1D01*
G02Y442199I1017J1106D01*
G03X1298805Y442346I-135J148D01*
G37*
G36*
G01X1308798D02*
Y442640D01*
G03X1308733Y442787I-200J-1D01*
G02X1308248Y443893I1019J1106D01*
G02X1311252I1502J0D01*
G02X1310767Y442787I-1504J0D01*
G03X1310702Y442640I135J-148D01*
G01Y442346D01*
G03X1310767Y442199I200J1D01*
G02Y439987I-1017J-1106D01*
G03X1310702Y439840I135J-148D01*
G01Y439546D01*
G03X1310767Y439399I200J1D01*
G02X1311252Y438293I-1019J-1106D01*
G02X1308248I-1502J0D01*
G02X1308733Y439399I1504J0D01*
G03X1308798Y439546I-135J148D01*
G01Y439840D01*
G03X1308733Y439987I-200J-1D01*
G02Y442199I1017J1106D01*
G03X1308798Y442346I-135J148D01*
G37*
G36*
G01X1755892D02*
Y442640D01*
G03X1755827Y442787I-200J-1D01*
G02X1755342Y443893I1019J1106D01*
G02X1758346I1502J0D01*
G02X1757861Y442787I-1504J0D01*
G03X1757796Y442640I135J-148D01*
G01Y442346D01*
G03X1757861Y442199I200J1D01*
G02Y439987I-1017J-1106D01*
G03X1757796Y439840I135J-148D01*
G01Y439546D01*
G03X1757861Y439399I200J1D01*
G02X1758346Y438293I-1019J-1106D01*
G02X1755342I-1502J0D01*
G02X1755827Y439399I1504J0D01*
G03X1755892Y439546I-135J148D01*
G01Y439840D01*
G03X1755827Y439987I-200J-1D01*
G02Y442199I1017J1106D01*
G03X1755892Y442346I-135J148D01*
G37*
G36*
G01X1765885D02*
Y442640D01*
G03X1765820Y442787I-200J-1D01*
G02X1765335Y443893I1019J1106D01*
G02X1768339I1502J0D01*
G02X1767854Y442787I-1504J0D01*
G03X1767789Y442640I135J-148D01*
G01Y442346D01*
G03X1767854Y442199I200J1D01*
G02Y439987I-1017J-1106D01*
G03X1767789Y439840I135J-148D01*
G01Y439546D01*
G03X1767854Y439399I200J1D01*
G02X1768339Y438293I-1019J-1106D01*
G02X1765335I-1502J0D01*
G02X1765820Y439399I1504J0D01*
G03X1765885Y439546I-135J148D01*
G01Y439840D01*
G03X1765820Y439987I-200J-1D01*
G02Y442199I1017J1106D01*
G03X1765885Y442346I-135J148D01*
G37*
G36*
G01X748891Y454177D02*
G02X750393Y455679I1502J0D01*
G02X751380Y455309I0J-1501D01*
G01X751381D01*
Y455308D01*
G03X751511Y455260I130J152D01*
G01X751775D01*
G03X751905Y455308I0J200D01*
G01X751906Y455309D01*
G02X752893Y455679I987J-1131D01*
G02X754395Y454177I0J-1502D01*
G02X754025Y453190I-1501J0D01*
G01Y453189D01*
X754024D01*
G03X753976Y453059I152J-130D01*
G01Y452795D01*
G03X754024Y452665I200J0D01*
G01X754025Y452664D01*
G02X754395Y451677I-1131J-987D01*
G02X752893Y450175I-1502J0D01*
G02X751906Y450545I0J1501D01*
G01X751905D01*
Y450546D01*
G03X751775Y450594I-130J-152D01*
G01X751511D01*
G03X751381Y450546I0J-200D01*
G01X751380Y450545D01*
G02X750393Y450175I-987J1131D01*
G02X748891Y451677I0J1502D01*
G02X749261Y452664I1501J0D01*
G01Y452665D01*
X749262D01*
G03X749310Y452795I-152J130D01*
G01Y453059D01*
G03X749262Y453189I-200J0D01*
G01X749261Y453190D01*
G02X748891Y454177I1131J987D01*
G37*
G36*
G01X1205978D02*
G02X1207480Y455679I1502J0D01*
G02X1208467Y455309I0J-1501D01*
G01X1208468D01*
Y455308D01*
G03X1208598Y455260I130J152D01*
G01X1208862D01*
G03X1208992Y455308I0J200D01*
G01X1208993Y455309D01*
G02X1209980Y455679I987J-1131D01*
G02X1211482Y454177I0J-1502D01*
G02X1211112Y453190I-1501J0D01*
G01Y453189D01*
X1211111D01*
G03X1211063Y453059I152J-130D01*
G01Y452795D01*
G03X1211111Y452665I200J0D01*
G01X1211112Y452664D01*
G02X1211482Y451677I-1131J-987D01*
G02X1209980Y450175I-1502J0D01*
G02X1208993Y450545I0J1501D01*
G01X1208992D01*
Y450546D01*
G03X1208862Y450594I-130J-152D01*
G01X1208598D01*
G03X1208468Y450546I0J-200D01*
G01X1208467Y450545D01*
G02X1207480Y450175I-987J1131D01*
G02X1205978Y451677I0J1502D01*
G02X1206348Y452664I1501J0D01*
G01Y452665D01*
X1206349D01*
G03X1206397Y452795I-152J130D01*
G01Y453059D01*
G03X1206349Y453189I-200J0D01*
G01X1206348Y453190D01*
G02X1205978Y454177I1131J987D01*
G37*
G36*
G01X1663065D02*
G02X1664567Y455679I1502J0D01*
G02X1665554Y455309I0J-1501D01*
G01X1665555D01*
Y455308D01*
G03X1665685Y455260I130J152D01*
G01X1665949D01*
G03X1666079Y455308I0J200D01*
G01X1666080Y455309D01*
G02X1667067Y455679I987J-1131D01*
G02X1668569Y454177I0J-1502D01*
G02X1668199Y453190I-1501J0D01*
G01Y453189D01*
X1668198D01*
G03X1668150Y453059I152J-130D01*
G01Y452795D01*
G03X1668198Y452665I200J0D01*
G01X1668199Y452664D01*
G02X1668569Y451677I-1131J-987D01*
G02X1667067Y450175I-1502J0D01*
G02X1666080Y450545I0J1501D01*
G01X1666079D01*
Y450546D01*
G03X1665949Y450594I-130J-152D01*
G01X1665685D01*
G03X1665555Y450546I0J-200D01*
G01X1665554Y450545D01*
G02X1664567Y450175I-987J1131D01*
G02X1663065Y451677I0J1502D01*
G02X1663435Y452664I1501J0D01*
G01Y452665D01*
X1663436D01*
G03X1663484Y452795I-152J130D01*
G01Y453059D01*
G03X1663436Y453189I-200J0D01*
G01X1663435Y453190D01*
G02X1663065Y454177I1131J987D01*
G37*
G36*
G01X817497Y455214D02*
X817183D01*
G03X817025Y455137I0J-200D01*
G02X815840Y454558I-1185J923D01*
G02Y457562I0J1502D01*
G02X817025Y456983I0J-1502D01*
G03X817183Y456906I158J123D01*
G01X817497D01*
G03X817655Y456983I0J200D01*
G02X818840Y457562I1185J-923D01*
G02Y454558I0J-1502D01*
G02X817655Y455137I0J1502D01*
G03X817497Y455214I-158J-123D01*
G37*
G36*
G01X1274584Y461214D02*
X1274270D01*
G03X1274112Y461137I0J-200D01*
G02X1272927Y460558I-1185J923D01*
G02Y463562I0J1502D01*
G02X1274112Y462983I0J-1502D01*
G03X1274270Y462906I158J123D01*
G01X1274584D01*
G03X1274742Y462983I0J200D01*
G02X1275927Y463562I1185J-923D01*
G02Y460558I0J-1502D01*
G02X1274742Y461137I0J1502D01*
G03X1274584Y461214I-158J-123D01*
G37*
G36*
G01X1731671D02*
X1731357D01*
G03X1731199Y461137I0J-200D01*
G02X1730014Y460558I-1185J923D01*
G02Y463562I0J1502D01*
G02X1731199Y462983I0J-1502D01*
G03X1731357Y462906I158J123D01*
G01X1731671D01*
G03X1731829Y462983I0J200D01*
G02X1733014Y463562I1185J-923D01*
G02Y460558I0J-1502D01*
G02X1731829Y461137I0J1502D01*
G03X1731671Y461214I-158J-123D01*
G37*
G36*
G01X1287719Y468499D02*
G02Y471503I0J1502D01*
G02X1288706Y471133I0J-1501D01*
G01X1288707D01*
Y471132D01*
G03X1288837Y471084I130J152D01*
G01X1289101D01*
G03X1289231Y471132I0J200D01*
G01X1289232Y471133D01*
G02X1290219Y471503I987J-1131D01*
G02Y468499I0J-1502D01*
G02X1289232Y468869I0J1501D01*
G01X1289231D01*
Y468870D01*
G03X1289101Y468918I-130J-152D01*
G01X1288837D01*
G03X1288707Y468870I0J-200D01*
G01X1288706Y468869D01*
G02X1287719Y468499I-987J1131D01*
G37*
G36*
G01X1744806D02*
G02Y471503I0J1502D01*
G02X1745793Y471133I0J-1501D01*
G01X1745794D01*
Y471132D01*
G03X1745924Y471084I130J152D01*
G01X1746188D01*
G03X1746318Y471132I0J200D01*
G01X1746319Y471133D01*
G02X1747306Y471503I987J-1131D01*
G02Y468499I0J-1502D01*
G02X1746319Y468869I0J1501D01*
G01X1746318D01*
Y468870D01*
G03X1746188Y468918I-130J-152D01*
G01X1745924D01*
G03X1745794Y468870I0J-200D01*
G01X1745793Y468869D01*
G02X1744806Y468499I-987J1131D01*
G37*
G36*
G01X823544Y476563D02*
G02X825046Y475061I0J-1502D01*
G02X824676Y474074I-1501J0D01*
G01Y474073D01*
X824675D01*
G03X824627Y473943I152J-130D01*
G01Y473679D01*
G03X824675Y473549I200J0D01*
G01X824676Y473548D01*
G02X825046Y472561I-1131J-987D01*
G02X823544Y471059I-1502J0D01*
G02X822859Y471225I1J1502D01*
G01X822857D01*
G03X822680Y471227I-91J-178D01*
G01X822349Y471068D01*
X822292Y470994D01*
X822283Y470948D01*
G02X820810Y469741I-1473J295D01*
G02X819308Y471243I0J1502D01*
G02X819678Y472230I1501J0D01*
G01Y472231D01*
X819679D01*
G03X819727Y472361I-152J130D01*
G01Y472625D01*
G03X819679Y472755I-200J0D01*
G01X819678Y472756D01*
G02X819308Y473743I1131J987D01*
G02X820810Y475245I1502J0D01*
G02X821495Y475079I-1J-1502D01*
G01X821497D01*
G03X821674Y475077I91J178D01*
G01X822005Y475236D01*
X822062Y475310D01*
X822071Y475356D01*
G02X823544Y476563I1473J-295D01*
G37*
G36*
G01X809254Y476071D02*
G02X812258I1502J0D01*
G02X811888Y475084I-1501J0D01*
G01Y475083D01*
X811887D01*
G03X811839Y474953I152J-130D01*
G01Y474689D01*
G03X811887Y474559I200J0D01*
G01X811888Y474558D01*
G02Y472584I-1131J-987D01*
G01Y472583D01*
X811887D01*
G03X811839Y472453I152J-130D01*
G01Y472189D01*
G03X811887Y472059I200J0D01*
G01X811888Y472058D01*
G02Y470084I-1131J-987D01*
G01Y470083D01*
X811887D01*
G03X811839Y469953I152J-130D01*
G01Y469689D01*
G03X811887Y469559I200J0D01*
G01X811888Y469558D01*
G02X812258Y468571I-1131J-987D01*
G02X809254I-1502J0D01*
G02X809624Y469558I1501J0D01*
G01Y469559D01*
X809625D01*
G03X809673Y469689I-152J130D01*
G01Y469953D01*
G03X809625Y470083I-200J0D01*
G01X809624Y470084D01*
G02Y472058I1131J987D01*
G01Y472059D01*
X809625D01*
G03X809673Y472189I-152J130D01*
G01Y472453D01*
G03X809625Y472583I-200J0D01*
G01X809624Y472584D01*
G02Y474558I1131J987D01*
G01Y474559D01*
X809625D01*
G03X809673Y474689I-152J130D01*
G01Y474953D01*
G03X809625Y475083I-200J0D01*
G01X809624Y475084D01*
G02X809254Y476071I1131J987D01*
G37*
G36*
G01X1271915Y475551D02*
G02Y478555I0J1502D01*
G02X1272902Y478185I0J-1501D01*
G01X1272903D01*
Y478184D01*
G03X1273033Y478136I130J152D01*
G01X1273297D01*
G03X1273427Y478184I0J200D01*
G01X1273428Y478185D01*
G02X1274415Y478555I987J-1131D01*
G02Y475551I0J-1502D01*
G02X1273428Y475921I0J1501D01*
G01X1273427D01*
Y475922D01*
G03X1273297Y475970I-130J-152D01*
G01X1273033D01*
G03X1272903Y475922I0J-200D01*
G01X1272902Y475921D01*
G02X1271915Y475551I-987J1131D01*
G37*
G36*
G01X832405Y481712D02*
X832406Y481711D01*
G03X832536Y481663I130J152D01*
G01X832800D01*
G03X832930Y481711I0J200D01*
G01X832931Y481712D01*
G02X833918Y482082I987J-1131D01*
G02Y479078I0J-1502D01*
G02X832931Y479448I0J1501D01*
G01X832930D01*
Y479449D01*
G03X832800Y479497I-130J-152D01*
G01X832536D01*
G03X832406Y479449I0J-200D01*
G01X832405Y479448D01*
G02X830431I-987J1131D01*
G01X830430D01*
Y479449D01*
G03X830300Y479497I-130J-152D01*
G01X830036D01*
G03X829906Y479449I0J-200D01*
G01X829905Y479448D01*
G02X828918Y479078I-987J1131D01*
G02Y482082I0J1502D01*
G02X829905Y481712I0J-1501D01*
G01X829906D01*
Y481711D01*
G03X830036Y481663I130J152D01*
G01X830300D01*
G03X830430Y481711I0J200D01*
G01X830431Y481712D01*
G02X832405I987J-1131D01*
G37*
G36*
G01X1266341Y481071D02*
G02X1269345I1502J0D01*
G02X1268975Y480084I-1501J0D01*
G01Y480083D01*
X1268974D01*
G03X1268926Y479953I152J-130D01*
G01Y479689D01*
G03X1268974Y479559I200J0D01*
G01X1268975Y479558D01*
G02Y477584I-1131J-987D01*
G01Y477583D01*
X1268974D01*
G03X1268926Y477453I152J-130D01*
G01Y477189D01*
G03X1268974Y477059I200J0D01*
G01X1268975Y477058D01*
G02Y475084I-1131J-987D01*
G01Y475083D01*
X1268974D01*
G03X1268926Y474953I152J-130D01*
G01Y474689D01*
G03X1268974Y474559I200J0D01*
G01X1268975Y474558D01*
G02X1269345Y473571I-1131J-987D01*
G02X1266341I-1502J0D01*
G02X1266711Y474558I1501J0D01*
G01Y474559D01*
X1266712D01*
G03X1266760Y474689I-152J130D01*
G01Y474953D01*
G03X1266712Y475083I-200J0D01*
G01X1266711Y475084D01*
G02Y477058I1131J987D01*
G01Y477059D01*
X1266712D01*
G03X1266760Y477189I-152J130D01*
G01Y477453D01*
G03X1266712Y477583I-200J0D01*
G01X1266711Y477584D01*
G02Y479558I1131J987D01*
G01Y479559D01*
X1266712D01*
G03X1266760Y479689I-152J130D01*
G01Y479953D01*
G03X1266712Y480083I-200J0D01*
G01X1266711Y480084D01*
G02X1266341Y481071I1131J987D01*
G37*
G36*
G01X1746579Y486712D02*
X1746580Y486711D01*
G03X1746710Y486663I130J152D01*
G01X1746974D01*
G03X1747104Y486711I0J200D01*
G01X1747105Y486712D01*
G02X1748092Y487082I987J-1131D01*
G02Y484078I0J-1502D01*
G02X1747105Y484448I0J1501D01*
G01X1747104D01*
Y484449D01*
G03X1746974Y484497I-130J-152D01*
G01X1746710D01*
G03X1746580Y484449I0J-200D01*
G01X1746579Y484448D01*
G02X1744605I-987J1131D01*
G01X1744604D01*
Y484449D01*
G03X1744474Y484497I-130J-152D01*
G01X1744210D01*
G03X1744080Y484449I0J-200D01*
G01X1744079Y484448D01*
G02X1743092Y484078I-987J1131D01*
G02Y487082I0J1502D01*
G02X1744079Y486712I0J-1501D01*
G01X1744080D01*
Y486711D01*
G03X1744210Y486663I130J152D01*
G01X1744474D01*
G03X1744604Y486711I0J200D01*
G01X1744605Y486712D01*
G02X1746579I987J-1131D01*
G37*
G36*
G01X832341Y489089D02*
Y489383D01*
G03X832276Y489530I-200J-1D01*
G02X831791Y490636I1019J1106D01*
G02X834795I1502J0D01*
G02X834310Y489530I-1504J0D01*
G03X834245Y489383I135J-148D01*
G01Y489089D01*
G03X834310Y488942I200J1D01*
G02X834795Y487836I-1019J-1106D01*
G02X831791I-1502J0D01*
G02X832276Y488942I1504J0D01*
G03X832341Y489089I-135J148D01*
G37*
G36*
G01X1289428Y494089D02*
Y494383D01*
G03X1289363Y494530I-200J-1D01*
G02X1288878Y495636I1019J1106D01*
G02X1291882I1502J0D01*
G02X1291397Y494530I-1504J0D01*
G03X1291332Y494383I135J-148D01*
G01Y494089D01*
G03X1291397Y493942I200J1D01*
G02X1291882Y492836I-1019J-1106D01*
G02X1288878I-1502J0D01*
G02X1289363Y493942I1504J0D01*
G03X1289428Y494089I-135J148D01*
G37*
G36*
G01X1746515D02*
Y494383D01*
G03X1746450Y494530I-200J-1D01*
G02X1745965Y495636I1019J1106D01*
G02X1748969I1502J0D01*
G02X1748484Y494530I-1504J0D01*
G03X1748419Y494383I135J-148D01*
G01Y494089D01*
G03X1748484Y493942I200J1D01*
G02X1748969Y492836I-1019J-1106D01*
G02X1745965I-1502J0D01*
G02X1746450Y493942I1504J0D01*
G03X1746515Y494089I-135J148D01*
G37*
G36*
G01X1136871Y549800D02*
G02X1139875I1502J0D01*
G02X1139336Y548648I-1502J1D01*
G01X1139335Y548647D01*
G03X1139265Y548509I129J-152D01*
G01X1139244Y548221D01*
G03X1139293Y548075I200J-14D01*
G01X1139294Y548074D01*
G02X1139675Y547075I-1121J-1000D01*
G02X1136671I-1502J0D01*
G02X1137210Y548227I1502J-1D01*
G01X1137211Y548228D01*
G03X1137281Y548366I-129J152D01*
G01X1137302Y548654D01*
G03X1137253Y548800I-200J14D01*
G01X1137252Y548801D01*
G02X1136871Y549800I1121J1000D01*
G37*
G36*
G01X1593958D02*
G02X1596962I1502J0D01*
G02X1596423Y548648I-1502J1D01*
G01X1596422Y548647D01*
G03X1596352Y548509I129J-152D01*
G01X1596331Y548221D01*
G03X1596380Y548075I200J-14D01*
G01X1596381Y548074D01*
G02X1596762Y547075I-1121J-1000D01*
G02X1593758I-1502J0D01*
G02X1594297Y548227I1502J-1D01*
G01X1594298Y548228D01*
G03X1594368Y548366I-129J152D01*
G01X1594389Y548654D01*
G03X1594340Y548800I-200J14D01*
G01X1594339Y548801D01*
G02X1593958Y549800I1121J1000D01*
G37*
G36*
G01X1165400Y551798D02*
G02Y554802I0J1502D01*
G02X1166387Y554432I0J-1501D01*
G01X1166388D01*
Y554431D01*
G03X1166518Y554383I130J152D01*
G01X1166782D01*
G03X1166912Y554431I0J200D01*
G01X1166913Y554432D01*
G02X1167900Y554802I987J-1131D01*
G02Y551798I0J-1502D01*
G02X1166913Y552168I0J1501D01*
G01X1166912D01*
Y552169D01*
G03X1166782Y552217I-130J-152D01*
G01X1166518D01*
G03X1166388Y552169I0J-200D01*
G01X1166387Y552168D01*
G02X1165400Y551798I-987J1131D01*
G37*
G36*
G01X1616689Y619054D02*
X1625207Y639619D01*
G03X1625222Y639696I-185J76D01*
G01Y643252D01*
G02X1629226I2002J0D01*
G01Y639258D01*
G02X1629073Y638492I-2002J2D01*
G01X1620555Y617927D01*
G03X1620540Y617850I185J-76D01*
G01Y560585D01*
G02X1619953Y559170I-2002J1D01*
G01X1613799Y553015D01*
G03X1613740Y552873I141J-142D01*
G01Y453135D01*
G03X1613799Y452993I200J0D01*
G01X1618858Y447933D01*
G03X1619000Y447874I142J141D01*
G01X1625938D01*
G02Y443872I0J-2001D01*
G01X1625786D01*
G03X1625626Y443793I-1J-200D01*
G01X1625434Y443538D01*
G03X1625401Y443363I159J-121D01*
G02X1625457Y442957I-1446J-406D01*
G01Y442956D01*
G02X1622453I-1502J0D01*
G01Y442957D01*
G02X1622509Y443363I1502J0D01*
G03X1622476Y443538I-192J54D01*
G01X1622284Y443793D01*
G03X1622124Y443872I-159J-121D01*
G01X1618088D01*
G02X1616673Y444458I0J2001D01*
G01X1610323Y450808D01*
G02X1609736Y452223I1415J1416D01*
G01Y553785D01*
G02X1610323Y555200I2002J-1D01*
G01X1616477Y561355D01*
G03X1616536Y561497I-141J142D01*
G01Y618288D01*
G02X1616689Y619054I2002J-2D01*
G37*
G36*
G01X1161133Y700623D02*
X1161134Y700622D01*
G03X1161264Y700574I130J152D01*
G01X1161528D01*
G03X1161658Y700622I0J200D01*
G01X1161659Y700623D01*
G02X1162646Y700993I987J-1131D01*
G02Y697989I0J-1502D01*
G02X1161659Y698359I0J1501D01*
G01X1161658D01*
Y698360D01*
G03X1161528Y698408I-130J-152D01*
G01X1161264D01*
G03X1161134Y698360I0J-200D01*
G01X1161133Y698359D01*
G02X1159159I-987J1131D01*
G01X1159158D01*
Y698360D01*
G03X1159028Y698408I-130J-152D01*
G01X1158764D01*
G03X1158634Y698360I0J-200D01*
G01X1158633Y698359D01*
G02X1156659I-987J1131D01*
G01X1156658D01*
Y698360D01*
G03X1156528Y698408I-130J-152D01*
G01X1156264D01*
G03X1156134Y698360I0J-200D01*
G01X1156133Y698359D01*
G02X1155146Y697989I-987J1131D01*
G02Y700993I0J1502D01*
G02X1156133Y700623I0J-1501D01*
G01X1156134D01*
Y700622D01*
G03X1156264Y700574I130J152D01*
G01X1156528D01*
G03X1156658Y700622I0J200D01*
G01X1156659Y700623D01*
G02X1158633I987J-1131D01*
G01X1158634D01*
Y700622D01*
G03X1158764Y700574I130J152D01*
G01X1159028D01*
G03X1159158Y700622I0J200D01*
G01X1159159Y700623D01*
G02X1161133I987J-1131D01*
G37*
G36*
G01X1178225Y886197D02*
G02X1181229I1502J0D01*
G02X1180817Y885164I-1501J0D01*
G01X1180789Y885134D01*
X1180761Y885058D01*
X1180777Y884728D01*
G03X1180845Y884587I200J9D01*
G02X1181360Y883455I-987J-1132D01*
G02X1178356I-1502J0D01*
G02X1178768Y884488I1501J0D01*
G01X1178796Y884518D01*
X1178824Y884594D01*
X1178808Y884924D01*
G03X1178740Y885065I-200J-9D01*
G02X1178225Y886197I987J1132D01*
G37*
G36*
G01X1746557Y899314D02*
X1746243D01*
G03X1746085Y899237I0J-200D01*
G02X1744900Y898658I-1185J923D01*
G02Y901662I0J1502D01*
G02X1746085Y901083I0J-1502D01*
G03X1746243Y901006I158J123D01*
G01X1746557D01*
G03X1746715Y901083I0J200D01*
G02X1747900Y901662I1185J-923D01*
G02Y898658I0J-1502D01*
G02X1746715Y899237I0J1502D01*
G03X1746557Y899314I-158J-123D01*
G37*
G36*
G01X1772943Y929006D02*
Y929320D01*
G03X1772866Y929478I-200J0D01*
G02X1772287Y930663I923J1185D01*
G02X1775291I1502J0D01*
G02X1774712Y929478I-1502J0D01*
G03X1774635Y929320I123J-158D01*
G01Y929006D01*
G03X1774712Y928848I200J0D01*
G02X1775291Y927663I-923J-1185D01*
G02X1772287I-1502J0D01*
G02X1772866Y928848I1502J0D01*
G03X1772943Y929006I-123J158D01*
G37*
G36*
G01X1781411Y957047D02*
X1781705D01*
G03X1781852Y957112I-1J200D01*
G02X1784064I1106J-1017D01*
G03X1784211Y957047I148J135D01*
G01X1784505D01*
G03X1784652Y957112I-1J200D01*
G02X1785758Y957597I1106J-1019D01*
G02X1787260Y956095I0J-1502D01*
G02X1786775Y954989I-1504J0D01*
G03X1786710Y954842I135J-148D01*
G01Y954548D01*
G03X1786775Y954401I200J1D01*
G02X1787260Y953295I-1019J-1106D01*
G02X1785758Y951793I-1502J0D01*
G02X1784652Y952278I0J1504D01*
G03X1784505Y952343I-148J-135D01*
G01X1784211D01*
G03X1784064Y952278I1J-200D01*
G02X1781852I-1106J1017D01*
G03X1781705Y952343I-148J-135D01*
G01X1781411D01*
G03X1781264Y952278I1J-200D01*
G02X1780158Y951793I-1106J1019D01*
G02X1778656Y953295I0J1502D01*
G02X1779141Y954401I1504J0D01*
G03X1779206Y954548I-135J148D01*
G01Y954842D01*
G03X1779141Y954989I-200J-1D01*
G02X1778656Y956095I1019J1106D01*
G02X1780158Y957597I1502J0D01*
G02X1781264Y957112I0J-1504D01*
G03X1781411Y957047I148J135D01*
G37*
G36*
G01X1806711Y965113D02*
Y965407D01*
G03X1806646Y965554I-200J-1D01*
G02X1806161Y966660I1019J1106D01*
G02X1809165I1502J0D01*
G02X1808680Y965554I-1504J0D01*
G03X1808615Y965407I135J-148D01*
G01Y965113D01*
G03X1808680Y964966I200J1D01*
G02X1809165Y963860I-1019J-1106D01*
G02X1806161I-1502J0D01*
G02X1806646Y964966I1504J0D01*
G03X1806711Y965113I-135J148D01*
G37*
G36*
G01X1652351Y992416D02*
G02X1651442Y993796I593J1380D01*
G02X1654446I1502J0D01*
G02X1653908Y992644I-1502J0D01*
G03X1654007Y991970I257J-307D01*
G02X1654916Y990590I-593J-1380D01*
G02X1651912I-1502J0D01*
G02X1652450Y991742I1502J0D01*
G03X1652351Y992416I-257J307D01*
G37*
G36*
G01X1316443Y523058D02*
G02X1317945Y524560I1502J0D01*
G02X1319198Y523886I0J-1502D01*
G03X1319369Y523796I167J110D01*
G01X1319708Y523804D01*
G03X1319875Y523901I-4J200D01*
G02X1321164Y524632I1289J-771D01*
G02X1322666Y523130I0J-1502D01*
G02X1322255Y522098I-1501J0D01*
G01X1322254Y522097D01*
G03X1322201Y521940I146J-137D01*
G01X1322235Y521596D01*
X1322279Y521521D01*
X1322315Y521496D01*
G02X1322952Y520268I-865J-1228D01*
G02X1321450Y518766I-1502J0D01*
G02X1320200Y519436I0J1501D01*
G01X1320170Y519481D01*
X1320075Y519528D01*
X1319674Y519502D01*
G03X1319508Y519390I14J-200D01*
G02X1318160Y518551I-1348J663D01*
G02X1316658Y520053I0J1502D01*
G02X1317160Y521174I1503J0D01*
G01X1317161D01*
G03X1317227Y521338I-134J149D01*
G01X1317201Y521701D01*
X1317154Y521780D01*
X1317115Y521806D01*
G02X1316443Y523058I830J1252D01*
G37*
G36*
G01X1282904Y472834D02*
X1279653D01*
G03X1279511Y472775I0J-200D01*
G01X1268069Y461332D01*
G03X1268014Y461157I142J-141D01*
G01X1268070Y460834D01*
G03X1268180Y460688I197J34D01*
G01X1268181D01*
G02X1269042Y459330I-640J-1358D01*
G02X1267540Y457828I-1502J0D01*
G02X1266182Y458688I0J1502D01*
G01Y458690D01*
X1266161Y458733D01*
X1266084Y458791D01*
X1265713Y458856D01*
G03X1265538Y458801I-34J-197D01*
G01X1260706Y453969D01*
G03X1260657Y453889I141J-142D01*
G01Y453888D01*
G02X1259223Y452832I-1434J446D01*
G02X1257721Y454334I0J1502D01*
G02X1258776Y455768I1502J0D01*
G01X1258778D01*
G03X1258858Y455817I-62J190D01*
G01X1277400Y474359D01*
G03X1277455Y474536I-142J141D01*
G01X1277387Y474909D01*
X1277327Y474985D01*
X1277281Y475006D01*
G02X1276395Y476376I616J1370D01*
G02X1276765Y477363I1501J0D01*
G01Y477364D01*
X1276766D01*
G03X1276814Y477494I-152J130D01*
G01Y477758D01*
G03X1276766Y477888I-200J0D01*
G01X1276765Y477889D01*
G02X1276395Y478876I1131J987D01*
G02X1277897Y480378I1502J0D01*
G02X1278582Y480212I-1J-1502D01*
G01X1278584D01*
G03X1278761Y480210I91J178D01*
G01X1279092Y480369D01*
X1279149Y480443D01*
X1279158Y480489D01*
G02X1280631Y481696I1473J-295D01*
G02X1282133Y480194I0J-1502D01*
G02X1281763Y479207I-1501J0D01*
G01Y479206D01*
X1281762D01*
G03X1281714Y479076I152J-130D01*
G01Y478812D01*
G03X1281762Y478682I200J0D01*
G01X1281763Y478681D01*
G02X1282133Y477694I-1131J-987D01*
G02X1280631Y476192I-1502J0D01*
G02X1279946Y476358I1J1502D01*
G01X1279944D01*
G03X1279767Y476360I-91J-178D01*
G01X1279436Y476201D01*
X1279379Y476127D01*
X1279370Y476081D01*
G02X1279340Y475958I-1473J294D01*
G03X1279372Y475782I192J-56D01*
G01X1279564Y475526D01*
G03X1279724Y475446I160J120D01*
G01X1282278D01*
G03X1282420Y475505I0J200D01*
G01X1290486Y483572D01*
G03X1290542Y483749I-141J142D01*
G01X1290485Y484071D01*
G03X1290372Y484218I-197J-34D01*
G02X1290018Y484448I633J1362D01*
G01X1290017D01*
Y484449D01*
G03X1289887Y484497I-130J-152D01*
G01X1289623D01*
G03X1289493Y484449I0J-200D01*
G01X1289492Y484448D01*
G02X1287518I-987J1131D01*
G01X1287517D01*
Y484449D01*
G03X1287387Y484497I-130J-152D01*
G01X1287123D01*
G03X1286993Y484449I0J-200D01*
G01X1286992Y484448D01*
G02X1286005Y484078I-987J1131D01*
G02Y487082I0J1502D01*
G02X1286992Y486712I0J-1501D01*
G01X1286993D01*
Y486711D01*
G03X1287123Y486663I130J152D01*
G01X1287387D01*
G03X1287517Y486711I0J200D01*
G01X1287518Y486712D01*
G02X1289492I987J-1131D01*
G01X1289493D01*
Y486711D01*
G03X1289623Y486663I130J152D01*
G01X1289887D01*
G03X1290017Y486711I0J200D01*
G01X1290018Y486712D01*
G02X1291005Y487082I987J-1131D01*
G02X1292367Y486213I0J-1502D01*
G03X1292514Y486100I181J84D01*
G01X1292836Y486043D01*
G03X1293013Y486099I35J197D01*
G01X1295220Y488306D01*
G02X1296142Y488688I923J-924D01*
G01X1298512D01*
G03X1298605Y488711I0J200D01*
G02X1299304Y488884I700J-1329D01*
G02X1300806Y487382I0J-1502D01*
G01Y487381D01*
G02X1300727Y486901I-1502J1D01*
G03X1300760Y486712I189J-64D01*
G01X1301004Y486408D01*
X1301098Y486369D01*
X1301149Y486375D01*
G02X1301312Y486384I164J-1493D01*
G01X1301314D01*
G02X1299812Y484882I0J-1502D01*
G01Y484883D01*
G02X1299891Y485363I1502J-1D01*
G03X1299858Y485552I-189J64D01*
G01X1299614Y485856D01*
X1299520Y485895D01*
X1299469Y485889D01*
G02X1299306Y485880I-164J1493D01*
G01X1299304D01*
G02X1298605Y486053I1J1502D01*
G03X1298512Y486076I-93J-177D01*
G01X1296768D01*
G03X1296626Y486017I0J-200D01*
G01X1283826Y473216D01*
G02X1282904Y472834I-923J924D01*
G37*
G36*
G01X832331Y483240D02*
G02X831057Y482534I-1274J796D01*
G02Y485538I0J1502D01*
G02X832277Y484912I0J-1502D01*
G03X832941Y484934I325J234D01*
G02X834215Y485640I1274J-796D01*
G02Y482636I0J-1502D01*
G02X832995Y483262I0J1502D01*
G03X832331Y483240I-325J-234D01*
G37*
G36*
G01X842433Y480881D02*
G02X840974Y482382I43J1501D01*
G02X843978I1502J0D01*
G01Y482380D01*
G02X843902Y481909I-1502J1D01*
G03X844270Y481383I380J-126D01*
G02X845729Y479882I-43J-1501D01*
G02X842725I-1502J0D01*
G01Y479884D01*
G02X842801Y480355I1502J-1D01*
G03X842433Y480881I-380J126D01*
G37*
G36*
G01X817328Y473555D02*
G02X818830Y472053I0J-1502D01*
G02X818131Y470783I-1503J0D01*
G03X818038Y470611I107J-169D01*
G01X818043Y470270D01*
G03X818142Y470101I200J4D01*
G02X818882Y468806I-763J-1295D01*
G02X817380Y467304I-1502J0D01*
G02X816274Y467789I0J1504D01*
G03X816127Y467854I-148J-135D01*
G01X815833D01*
G03X815686Y467789I1J-200D01*
G02X814580Y467304I-1106J1019D01*
G02X813078Y468806I0J1502D01*
G02X813904Y470147I1502J0D01*
G03X814014Y470311I-90J179D01*
G01X814043Y470705D01*
X813999Y470800D01*
X813956Y470830D01*
G02X813326Y472053I872J1223D01*
G02X814828Y473555I1502J0D01*
G02X815815Y473185I0J-1501D01*
G01X815816D01*
Y473184D01*
G03X815946Y473136I130J152D01*
G01X816210D01*
G03X816340Y473184I0J200D01*
G01X816341Y473185D01*
G02X817328Y473555I987J-1131D01*
G37*
G36*
G01X1731357Y450937D02*
X1731671D01*
G03X1731829Y451014I0J200D01*
G02X1733014Y451593I1185J-923D01*
G02Y448589I0J-1502D01*
G02X1731829Y449168I0J1502D01*
G03X1731671Y449245I-158J-123D01*
G01X1731356D01*
G03X1731199Y449168I1J-200D01*
G02X1731127Y449083I-1181J928D01*
G01X1731097Y449050D01*
X1731071Y448966D01*
X1731119Y448619D01*
G03X1731209Y448477I198J26D01*
G02X1731906Y447209I-805J-1268D01*
G02X1730404Y445707I-1502J0D01*
G02X1729219Y446286I0J1502D01*
G03X1729061Y446363I-158J-123D01*
G01X1728747D01*
G03X1728589Y446286I0J-200D01*
G02X1727404Y445707I-1185J923D01*
G02X1725902Y447209I0J1502D01*
G01Y447229D01*
G03X1725821Y447392I-200J2D01*
G01X1725521Y447614D01*
X1725427Y447629D01*
X1725380Y447614D01*
G02X1724924Y447543I-456J1431D01*
G01X1724923D01*
G02X1726425Y449045I0J1502D01*
G01Y449025D01*
G03X1726506Y448862I200J-2D01*
G01X1726806Y448640D01*
X1726900Y448625D01*
X1726947Y448640D01*
G02X1727403Y448711I456J-1431D01*
G01X1727404D01*
G02X1728589Y448132I0J-1502D01*
G03X1728747Y448055I158J123D01*
G01X1729062D01*
G03X1729219Y448132I-1J200D01*
G02X1729291Y448217I1181J-928D01*
G01X1729321Y448250D01*
X1729347Y448334D01*
X1729299Y448681D01*
G03X1729209Y448823I-198J-26D01*
G02X1728512Y450091I805J1268D01*
G02X1730014Y451593I1502J0D01*
G02X1731199Y451014I0J-1502D01*
G03X1731357Y450937I158J123D01*
G37*
G36*
G01X1274270D02*
X1274584D01*
G03X1274742Y451014I0J200D01*
G02X1275927Y451593I1185J-923D01*
G02Y448589I0J-1502D01*
G02X1274742Y449168I0J1502D01*
G03X1274584Y449245I-158J-123D01*
G01X1274270D01*
G03X1274112Y449168I0J-200D01*
G02X1274001Y449041I-1185J923D01*
G01X1273968Y449008D01*
X1273939Y448918D01*
X1273997Y448553D01*
G03X1274100Y448408I197J31D01*
G02X1274899Y447081I-702J-1327D01*
G02X1273397Y445579I-1502J0D01*
G02X1272212Y446158I0J1502D01*
G03X1272054Y446235I-158J-123D01*
G01X1271740D01*
G03X1271582Y446158I0J-200D01*
G02X1270397Y445579I-1185J923D01*
G02X1268895Y447081I0J1502D01*
G02X1268902Y447226I1502J0D01*
G01X1268907Y447277D01*
X1268866Y447372D01*
X1268555Y447610D01*
G03X1268363Y447639I-122J-158D01*
G02X1267836Y447543I-528J1406D01*
G02X1269338Y449045I0J1502D01*
G02X1269331Y448900I-1502J0D01*
G01X1269326Y448849D01*
X1269367Y448754D01*
X1269678Y448516D01*
G03X1269870Y448487I122J158D01*
G02X1270397Y448583I528J-1406D01*
G02X1271582Y448004I0J-1502D01*
G03X1271740Y447927I158J123D01*
G01X1272054D01*
G03X1272212Y448004I0J200D01*
G02X1272323Y448131I1185J-923D01*
G01X1272356Y448164D01*
X1272385Y448254D01*
X1272327Y448619D01*
G03X1272224Y448764I-197J-31D01*
G02X1271425Y450091I702J1327D01*
G02X1272927Y451593I1502J0D01*
G02X1274112Y451014I0J-1502D01*
G03X1274270Y450937I158J123D01*
G37*
G36*
G01X1794554Y443889D02*
G02X1793483Y443327I-1071J739D01*
G02Y445931I0J1302D01*
G02X1794554Y445369I0J-1301D01*
G03X1795212I329J228D01*
G02X1796283Y445931I1071J-739D01*
G02Y443327I0J-1302D01*
G02X1795212Y443889I0J1301D01*
G03X1794554I-329J-228D01*
G37*
G36*
G01X1337467D02*
G02X1336396Y443327I-1071J739D01*
G02Y445931I0J1302D01*
G02X1337467Y445369I0J-1301D01*
G03X1338125I329J228D01*
G02X1339196Y445931I1071J-739D01*
G02Y443327I0J-1302D01*
G02X1338125Y443889I0J1301D01*
G03X1337467I-329J-228D01*
G37*
G36*
G01X817183Y444937D02*
X817497D01*
G03X817655Y445014I0J200D01*
G02X818840Y445593I1185J-923D01*
G02Y442589I0J-1502D01*
G02X817655Y443168I0J1502D01*
G03X817497Y443245I-158J-123D01*
G01X817183D01*
G03X817025Y443168I0J-200D01*
G02X816972Y443104I-1183J926D01*
G03X816925Y442948I151J-131D01*
G01X816940Y442821D01*
G03X817026Y442681I198J25D01*
G02X817679Y441442I-849J-1239D01*
G02X816177Y439940I-1502J0D01*
G02X815090Y440405I0J1503D01*
G01X815062Y440435D01*
X814989Y440466D01*
X814661Y440470D01*
G03X814519Y440413I-2J-200D01*
G01X814518Y440412D01*
G02X813456Y439972I-1062J1062D01*
G02X811959Y441355I0J1502D01*
G01Y441357D01*
G03X811860Y441513I-199J-17D01*
G01X811575Y441678D01*
G03X811389Y441686I-101J-173D01*
G02X810750Y441543I-640J1359D01*
G01X810749D01*
G02Y444547I0J1502D01*
G02X812246Y443164I0J-1502D01*
G01Y443162D01*
G03X812345Y443006I199J17D01*
G01X812630Y442841D01*
G03X812816Y442833I101J173D01*
G02X813455Y442976I640J-1359D01*
G01X813456D01*
G02X814612Y442433I0J-1502D01*
G03X814763Y442361I154J128D01*
G01X814891Y442359D01*
G03X815044Y442428I2J200D01*
G01X815045Y442429D01*
G03X815093Y442585I-151J132D01*
G01X815077Y442712D01*
G03X814991Y442852I-198J-25D01*
G02X814338Y444091I849J1239D01*
G02X815840Y445593I1502J0D01*
G02X817025Y445014I0J-1502D01*
G03X817183Y444937I158J123D01*
G37*
G36*
G01X1794554Y440346D02*
G02X1793483Y439784I-1071J739D01*
G02Y442388I0J1302D01*
G02X1794554Y441826I0J-1301D01*
G03X1795212I329J228D01*
G02X1796283Y442388I1071J-739D01*
G02Y439784I0J-1302D01*
G02X1795212Y440346I0J1301D01*
G03X1794554I-329J-228D01*
G37*
G36*
G01X1337467D02*
G02X1336396Y439784I-1071J739D01*
G02Y442388I0J1302D01*
G02X1337467Y441826I0J-1301D01*
G03X1338125I329J228D01*
G02X1339196Y442388I1071J-739D01*
G02Y439784I0J-1302D01*
G02X1338125Y440346I0J1301D01*
G03X1337467I-329J-228D01*
G37*
G36*
G01X1794554Y436803D02*
G02X1793483Y436241I-1071J739D01*
G02Y438845I0J1302D01*
G02X1794554Y438283I0J-1301D01*
G03X1795212I329J228D01*
G02X1796283Y438845I1071J-739D01*
G02Y436241I0J-1302D01*
G02X1795212Y436803I0J1301D01*
G03X1794554I-329J-228D01*
G37*
G36*
G01X1337467D02*
G02X1336396Y436241I-1071J739D01*
G02Y438845I0J1302D01*
G02X1337467Y438283I0J-1301D01*
G03X1338125I329J228D01*
G02X1339196Y438845I1071J-739D01*
G02Y436241I0J-1302D01*
G02X1338125Y436803I0J1301D01*
G03X1337467I-329J-228D01*
G37*
G36*
G01X1794554Y433259D02*
G02X1793483Y432697I-1071J739D01*
G02Y435301I0J1302D01*
G02X1794554Y434739I0J-1301D01*
G03X1795212I329J228D01*
G02X1796283Y435301I1071J-739D01*
G02Y432697I0J-1302D01*
G02X1795212Y433259I0J1301D01*
G03X1794554I-329J-228D01*
G37*
G36*
G01X1337467D02*
G02X1336396Y432697I-1071J739D01*
G02Y435301I0J1302D01*
G02X1337467Y434739I0J-1301D01*
G03X1338125I329J228D01*
G02X1339196Y435301I1071J-739D01*
G02Y432697I0J-1302D01*
G02X1338125Y433259I0J1301D01*
G03X1337467I-329J-228D01*
G37*
G36*
G01X784105Y427380D02*
G02X783400Y428653I797J1273D01*
G02X786404I1502J0D01*
G02X785621Y427334I-1502J0D01*
G03X785601Y426644I192J-351D01*
G02X786306Y425371I-797J-1273D01*
G02X783302I-1502J0D01*
G02X784085Y426690I1502J0D01*
G03X784105Y427380I-192J351D01*
G37*
G36*
G01X1751530Y410385D02*
X1751844D01*
G03X1752002Y410462I0J200D01*
G02X1753187Y411041I1185J-923D01*
G02X1754689Y409539I0J-1502D01*
G02X1754319Y408552I-1501J0D01*
G01Y408551D01*
X1754318D01*
G03X1754270Y408421I152J-130D01*
G01Y408157D01*
G03X1754318Y408027I200J0D01*
G01X1754319Y408026D01*
G02X1754689Y407039I-1131J-987D01*
G02X1753187Y405537I-1502J0D01*
G02X1752094Y406009I0J1502D01*
G01X1752093Y406010D01*
G03X1751928Y406071I-145J-138D01*
G01X1751613Y406040D01*
G03X1751463Y405946I20J-199D01*
G02X1750187Y405237I-1276J794D01*
G02X1748685Y406739I0J1502D01*
G02X1749170Y407845I1504J0D01*
G03X1749235Y407992I-135J148D01*
G01Y408286D01*
G03X1749170Y408433I-200J-1D01*
G02X1748685Y409539I1019J1106D01*
G02X1750187Y411041I1502J0D01*
G02X1751372Y410462I0J-1502D01*
G03X1751530Y410385I158J123D01*
G37*
G36*
G01X1294443D02*
X1294757D01*
G03X1294915Y410462I0J200D01*
G02X1296100Y411041I1185J-923D01*
G02X1297602Y409539I0J-1502D01*
G02X1297232Y408552I-1501J0D01*
G01Y408551D01*
X1297231D01*
G03X1297183Y408421I152J-130D01*
G01Y408157D01*
G03X1297231Y408027I200J0D01*
G01X1297232Y408026D01*
G02X1297602Y407039I-1131J-987D01*
G02X1296100Y405537I-1502J0D01*
G02X1295007Y406009I0J1502D01*
G01X1295006Y406010D01*
G03X1294841Y406071I-145J-138D01*
G01X1294526Y406040D01*
G03X1294376Y405946I20J-199D01*
G02X1293100Y405237I-1276J794D01*
G02X1291598Y406739I0J1502D01*
G02X1292083Y407845I1504J0D01*
G03X1292148Y407992I-135J148D01*
G01Y408286D01*
G03X1292083Y408433I-200J-1D01*
G02X1291598Y409539I1019J1106D01*
G02X1293100Y411041I1502J0D01*
G02X1294285Y410462I0J-1502D01*
G03X1294443Y410385I158J123D01*
G37*
G36*
G01X1764004Y379426D02*
G02X1763995Y379589I1493J164D01*
G01Y379591D01*
G02X1765497Y378089I1502J0D01*
G01X1765496D01*
G02X1765016Y378168I1J1502D01*
G03X1764490Y377746I-128J-379D01*
G02X1764499Y377583I-1493J-164D01*
G01Y377581D01*
G02X1762997Y379083I-1502J0D01*
G01X1762998D01*
G02X1763478Y379004I-1J-1502D01*
G03X1764004Y379426I128J379D01*
G37*
G36*
G01X1306917D02*
G02X1306908Y379589I1493J164D01*
G01Y379591D01*
G02X1308410Y378089I1502J0D01*
G01X1308409D01*
G02X1307929Y378168I1J1502D01*
G03X1307403Y377746I-128J-379D01*
G02X1307412Y377583I-1493J-164D01*
G01Y377581D01*
G02X1305910Y379083I-1502J0D01*
G01X1305911D01*
G02X1306391Y379004I-1J-1502D01*
G03X1306917Y379426I128J379D01*
G37*
G36*
G01X1310010Y370003D02*
G02X1309781Y370799I1273J797D01*
G01Y370801D01*
G02X1312785I1502J0D01*
G02X1311678Y369352I-1502J0D01*
G03X1311445Y368754I106J-386D01*
G02X1311674Y367958I-1273J-797D01*
G01Y367956D01*
G02X1308670I-1502J0D01*
G02X1309777Y369405I1502J0D01*
G03X1310010Y370003I-106J386D01*
G37*
G36*
G01X1349068Y313712D02*
X1296124D01*
G02X1295275Y314064I1J1201D01*
G01X1294681Y314659D01*
G03X1294679Y314661I-142J-140D01*
G01X1294536Y314800D01*
G02X1294489Y314868I137J145D01*
G01X1294337Y315245D01*
G02X1294322Y315320I185J76D01*
G01Y320126D01*
G02X1294748Y321042I1201J-2D01*
G03Y321808I-324J383D01*
G02X1294397Y322308I775J917D01*
G03X1294318Y322406I-187J-70D01*
G01X1294221Y322469D01*
G03X1294098Y322501I-109J-167D01*
G02X1294000Y322498I-95J1499D01*
G02X1292498Y324000I0J1502D01*
G02X1293938Y325501I1502J0D01*
G01X1293977Y325502D01*
X1294046Y325534D01*
X1294266Y325762D01*
G03X1294322Y325901I-144J139D01*
G01Y333736D01*
G03X1294193Y333923I-200J0D01*
G01X1293784Y334078D01*
X1293664Y334049D01*
X1293623Y334002D01*
G02X1292500Y333498I-1123J999D01*
G02Y336502I0J1502D01*
G02X1293623Y335998I0J-1503D01*
G01X1293664Y335951D01*
X1293784Y335922D01*
X1294193Y336077D01*
G03X1294322Y336264I-71J187D01*
G01Y336836D01*
G03X1294224Y337008I-200J0D01*
G01X1293926Y337183D01*
G03X1293728Y337186I-102J-172D01*
G02X1293001Y336998I-728J1314D01*
G01X1293000D01*
G02Y340002I0J1502D01*
G01X1293001D01*
G02X1293728Y339814I-1J-1502D01*
G01X1293775Y339788D01*
X1293880Y339789D01*
X1294224Y339992D01*
G03X1294322Y340164I-102J172D01*
G01Y347925D01*
G03X1294269Y348060I-200J-1D01*
G01X1294060Y348288D01*
X1293993Y348320D01*
X1293955Y348323D01*
G02Y351317I125J1497D01*
G01X1293993Y351320D01*
X1294060Y351352D01*
X1294269Y351580D01*
G03X1294322Y351715I-147J136D01*
G01Y358305D01*
G02X1294670Y359150I1201J-1D01*
G01X1299953Y364434D01*
X1299954D01*
G02X1299958Y364439I940J-748D01*
G02X1299968Y364449I146J-136D01*
G02X1300804Y364788I837J-863D01*
G01X1346713D01*
G02X1347558Y364439I-2J-1202D01*
G01X1354522Y357476D01*
G02X1354532Y357466I-845J-855D01*
G02X1354876Y356625I-858J-842D01*
G01Y319714D01*
G02X1354523Y318864I-1202J1D01*
G01X1349729Y314071D01*
G03X1349727Y314069I140J-142D01*
G01X1349588Y313926D01*
G02X1349520Y313879I-145J137D01*
G01X1349143Y313727D01*
G02X1349068Y313712I-76J185D01*
G37*
G36*
G01X907123Y359317D02*
G02X910127I1502J0D01*
G02X909675Y358243I-1502J0D01*
G01X909648Y358216D01*
X909617Y358148D01*
X909604Y357834D01*
G03X909653Y357695I200J-8D01*
G02X910023Y356708I-1131J-987D01*
G02X908521Y355206I-1502J0D01*
G02X907623Y355504I0J1502D01*
G01X907622D01*
G03X907417Y355524I-119J-160D01*
G01X907098Y355373D01*
G03X906984Y355200I86J-181D01*
G02X905483Y353760I-1501J62D01*
G02Y356764I0J1502D01*
G02X906381Y356466I0J-1502D01*
G01X906382D01*
G03X906587Y356446I119J160D01*
G01X906906Y356597D01*
G03X907020Y356770I-86J181D01*
G02X907471Y357782I1501J-62D01*
G01X907498Y357809D01*
X907529Y357877D01*
X907542Y358191D01*
G03X907493Y358330I-200J8D01*
G02X907123Y359317I1131J987D01*
G37*
G36*
G01X1383086Y351440D02*
G02X1382763Y352371I1180J931D01*
G02X1385767I1502J0D01*
G02X1384844Y350985I-1502J0D01*
G03X1384684Y350368I154J-369D01*
G02X1385007Y349437I-1180J-931D01*
G02X1382003I-1502J0D01*
G02X1382926Y350823I1502J0D01*
G03X1383086Y351440I-154J369D01*
G37*
G36*
G01X1572868Y343287D02*
G02X1571625Y342629I-1243J845D01*
G02Y345633I0J1502D01*
G02X1572870Y344971I0J-1502D01*
G03X1573532I331J224D01*
G02X1574775Y345629I1243J-845D01*
G02Y342625I0J-1502D01*
G02X1573530Y343287I0J1502D01*
G03X1572868I-331J-224D01*
G37*
G36*
G01X771241Y313706D02*
G02X770663Y314890I924J1184D01*
G02X773667I1502J0D01*
G02X772912Y313587I-1502J0D01*
G03X772865Y312924I199J-347D01*
G02X773443Y311740I-924J-1184D01*
G02X770439I-1502J0D01*
G02X771194Y313043I1502J0D01*
G03X771241Y313706I-199J347D01*
G37*
G36*
G01X314155D02*
G02X313577Y314890I924J1184D01*
G02X316581I1502J0D01*
G02X315826Y313587I-1502J0D01*
G03X315779Y312924I199J-347D01*
G02X316357Y311740I-924J-1184D01*
G02X313353I-1502J0D01*
G02X314108Y313043I1502J0D01*
G03X314155Y313706I-199J347D01*
G37*
G36*
G01X1750107Y213197D02*
G02X1751609Y211695I0J-1502D01*
G02X1751137Y210602I-1502J0D01*
G01X1751136Y210601D01*
G03X1751075Y210436I138J-145D01*
G01X1751106Y210121D01*
G03X1751200Y209971I199J20D01*
G02X1751909Y208695I-794J-1276D01*
G02X1750407Y207193I-1502J0D01*
G02X1749301Y207678I0J1504D01*
G03X1749154Y207743I-148J-135D01*
G01X1748860D01*
G03X1748713Y207678I1J-200D01*
G02X1747607Y207193I-1106J1019D01*
G02X1746105Y208695I0J1502D01*
G02X1746684Y209880I1502J0D01*
G03X1746761Y210038I-123J158D01*
G01Y210352D01*
G03X1746684Y210510I-200J0D01*
G02X1746105Y211695I923J1185D01*
G02X1747607Y213197I1502J0D01*
G02X1748594Y212827I0J-1501D01*
G01X1748595D01*
Y212826D01*
G03X1748725Y212778I130J152D01*
G01X1748989D01*
G03X1749119Y212826I0J200D01*
G01X1749120Y212827D01*
G02X1750107Y213197I987J-1131D01*
G37*
G36*
G01X1647745D02*
G02X1649247Y211695I0J-1502D01*
G02X1648775Y210602I-1502J0D01*
G01X1648774Y210601D01*
G03X1648713Y210436I138J-145D01*
G01X1648744Y210121D01*
G03X1648838Y209971I199J20D01*
G02X1649547Y208695I-794J-1276D01*
G02X1648045Y207193I-1502J0D01*
G02X1646939Y207678I0J1504D01*
G03X1646792Y207743I-148J-135D01*
G01X1646498D01*
G03X1646351Y207678I1J-200D01*
G02X1645245Y207193I-1106J1019D01*
G02X1643743Y208695I0J1502D01*
G02X1644322Y209880I1502J0D01*
G03X1644399Y210038I-123J158D01*
G01Y210352D01*
G03X1644322Y210510I-200J0D01*
G02X1643743Y211695I923J1185D01*
G02X1645245Y213197I1502J0D01*
G02X1646232Y212827I0J-1501D01*
G01X1646233D01*
Y212826D01*
G03X1646363Y212778I130J152D01*
G01X1646627D01*
G03X1646757Y212826I0J200D01*
G01X1646758Y212827D01*
G02X1647745Y213197I987J-1131D01*
G37*
G36*
G01X1545383D02*
G02X1546885Y211695I0J-1502D01*
G02X1546413Y210602I-1502J0D01*
G01X1546412Y210601D01*
G03X1546351Y210436I138J-145D01*
G01X1546382Y210121D01*
G03X1546476Y209971I199J20D01*
G02X1547185Y208695I-794J-1276D01*
G02X1545683Y207193I-1502J0D01*
G02X1544577Y207678I0J1504D01*
G03X1544430Y207743I-148J-135D01*
G01X1544136D01*
G03X1543989Y207678I1J-200D01*
G02X1542883Y207193I-1106J1019D01*
G02X1541381Y208695I0J1502D01*
G02X1541960Y209880I1502J0D01*
G03X1542037Y210038I-123J158D01*
G01Y210352D01*
G03X1541960Y210510I-200J0D01*
G02X1541381Y211695I923J1185D01*
G02X1542883Y213197I1502J0D01*
G02X1543870Y212827I0J-1501D01*
G01X1543871D01*
Y212826D01*
G03X1544001Y212778I130J152D01*
G01X1544265D01*
G03X1544395Y212826I0J200D01*
G01X1544396Y212827D01*
G02X1545383Y213197I987J-1131D01*
G37*
G36*
G01X1443021D02*
G02X1444523Y211695I0J-1502D01*
G02X1444051Y210602I-1502J0D01*
G01X1444050Y210601D01*
G03X1443989Y210436I138J-145D01*
G01X1444020Y210121D01*
G03X1444114Y209971I199J20D01*
G02X1444823Y208695I-794J-1276D01*
G02X1443321Y207193I-1502J0D01*
G02X1442215Y207678I0J1504D01*
G03X1442068Y207743I-148J-135D01*
G01X1441774D01*
G03X1441627Y207678I1J-200D01*
G02X1440521Y207193I-1106J1019D01*
G02X1439019Y208695I0J1502D01*
G02X1439598Y209880I1502J0D01*
G03X1439675Y210038I-123J158D01*
G01Y210352D01*
G03X1439598Y210510I-200J0D01*
G02X1439019Y211695I923J1185D01*
G02X1440521Y213197I1502J0D01*
G02X1441508Y212827I0J-1501D01*
G01X1441509D01*
Y212826D01*
G03X1441639Y212778I130J152D01*
G01X1441903D01*
G03X1442033Y212826I0J200D01*
G01X1442034Y212827D01*
G02X1443021Y213197I987J-1131D01*
G37*
G36*
G01X1293020D02*
G02X1294522Y211695I0J-1502D01*
G02X1294050Y210602I-1502J0D01*
G01X1294049Y210601D01*
G03X1293988Y210436I138J-145D01*
G01X1294019Y210121D01*
G03X1294113Y209971I199J20D01*
G02X1294822Y208695I-794J-1276D01*
G02X1293320Y207193I-1502J0D01*
G02X1292214Y207678I0J1504D01*
G03X1292067Y207743I-148J-135D01*
G01X1291773D01*
G03X1291626Y207678I1J-200D01*
G02X1290520Y207193I-1106J1019D01*
G02X1289018Y208695I0J1502D01*
G02X1289597Y209880I1502J0D01*
G03X1289674Y210038I-123J158D01*
G01Y210352D01*
G03X1289597Y210510I-200J0D01*
G02X1289018Y211695I923J1185D01*
G02X1290520Y213197I1502J0D01*
G02X1291507Y212827I0J-1501D01*
G01X1291508D01*
Y212826D01*
G03X1291638Y212778I130J152D01*
G01X1291902D01*
G03X1292032Y212826I0J200D01*
G01X1292033Y212827D01*
G02X1293020Y213197I987J-1131D01*
G37*
G36*
G01X1190658D02*
G02X1192160Y211695I0J-1502D01*
G02X1191688Y210602I-1502J0D01*
G01X1191687Y210601D01*
G03X1191626Y210436I138J-145D01*
G01X1191657Y210121D01*
G03X1191751Y209971I199J20D01*
G02X1192460Y208695I-794J-1276D01*
G02X1190958Y207193I-1502J0D01*
G02X1189852Y207678I0J1504D01*
G03X1189705Y207743I-148J-135D01*
G01X1189411D01*
G03X1189264Y207678I1J-200D01*
G02X1188158Y207193I-1106J1019D01*
G02X1186656Y208695I0J1502D01*
G02X1187235Y209880I1502J0D01*
G03X1187312Y210038I-123J158D01*
G01Y210352D01*
G03X1187235Y210510I-200J0D01*
G02X1186656Y211695I923J1185D01*
G02X1188158Y213197I1502J0D01*
G02X1189145Y212827I0J-1501D01*
G01X1189146D01*
Y212826D01*
G03X1189276Y212778I130J152D01*
G01X1189540D01*
G03X1189670Y212826I0J200D01*
G01X1189671Y212827D01*
G02X1190658Y213197I987J-1131D01*
G37*
G36*
G01X1088296D02*
G02X1089798Y211695I0J-1502D01*
G02X1089326Y210602I-1502J0D01*
G01X1089325Y210601D01*
G03X1089264Y210436I138J-145D01*
G01X1089295Y210121D01*
G03X1089389Y209971I199J20D01*
G02X1090098Y208695I-794J-1276D01*
G02X1088596Y207193I-1502J0D01*
G02X1087490Y207678I0J1504D01*
G03X1087343Y207743I-148J-135D01*
G01X1087049D01*
G03X1086902Y207678I1J-200D01*
G02X1085796Y207193I-1106J1019D01*
G02X1084294Y208695I0J1502D01*
G02X1084873Y209880I1502J0D01*
G03X1084950Y210038I-123J158D01*
G01Y210352D01*
G03X1084873Y210510I-200J0D01*
G02X1084294Y211695I923J1185D01*
G02X1085796Y213197I1502J0D01*
G02X1086783Y212827I0J-1501D01*
G01X1086784D01*
Y212826D01*
G03X1086914Y212778I130J152D01*
G01X1087178D01*
G03X1087308Y212826I0J200D01*
G01X1087309Y212827D01*
G02X1088296Y213197I987J-1131D01*
G37*
G36*
G01X985934D02*
G02X987436Y211695I0J-1502D01*
G02X986964Y210602I-1502J0D01*
G01X986963Y210601D01*
G03X986902Y210436I138J-145D01*
G01X986933Y210121D01*
G03X987027Y209971I199J20D01*
G02X987736Y208695I-794J-1276D01*
G02X986234Y207193I-1502J0D01*
G02X985128Y207678I0J1504D01*
G03X984981Y207743I-148J-135D01*
G01X984687D01*
G03X984540Y207678I1J-200D01*
G02X983434Y207193I-1106J1019D01*
G02X981932Y208695I0J1502D01*
G02X982511Y209880I1502J0D01*
G03X982588Y210038I-123J158D01*
G01Y210352D01*
G03X982511Y210510I-200J0D01*
G02X981932Y211695I923J1185D01*
G02X983434Y213197I1502J0D01*
G02X984421Y212827I0J-1501D01*
G01X984422D01*
Y212826D01*
G03X984552Y212778I130J152D01*
G01X984816D01*
G03X984946Y212826I0J200D01*
G01X984947Y212827D01*
G02X985934Y213197I987J-1131D01*
G37*
G36*
G01X835934D02*
G02X837436Y211695I0J-1502D01*
G02X836964Y210602I-1502J0D01*
G01X836963Y210601D01*
G03X836902Y210436I138J-145D01*
G01X836933Y210121D01*
G03X837027Y209971I199J20D01*
G02X837736Y208695I-794J-1276D01*
G02X836234Y207193I-1502J0D01*
G02X835128Y207678I0J1504D01*
G03X834981Y207743I-148J-135D01*
G01X834687D01*
G03X834540Y207678I1J-200D01*
G02X833434Y207193I-1106J1019D01*
G02X831932Y208695I0J1502D01*
G02X832511Y209880I1502J0D01*
G03X832588Y210038I-123J158D01*
G01Y210352D01*
G03X832511Y210510I-200J0D01*
G02X831932Y211695I923J1185D01*
G02X833434Y213197I1502J0D01*
G02X834421Y212827I0J-1501D01*
G01X834422D01*
Y212826D01*
G03X834552Y212778I130J152D01*
G01X834816D01*
G03X834946Y212826I0J200D01*
G01X834947Y212827D01*
G02X835934Y213197I987J-1131D01*
G37*
G36*
G01X733572D02*
G02X735074Y211695I0J-1502D01*
G02X734602Y210602I-1502J0D01*
G01X734601Y210601D01*
G03X734540Y210436I138J-145D01*
G01X734571Y210121D01*
G03X734665Y209971I199J20D01*
G02X735374Y208695I-794J-1276D01*
G02X733872Y207193I-1502J0D01*
G02X732766Y207678I0J1504D01*
G03X732619Y207743I-148J-135D01*
G01X732325D01*
G03X732178Y207678I1J-200D01*
G02X731072Y207193I-1106J1019D01*
G02X729570Y208695I0J1502D01*
G02X730149Y209880I1502J0D01*
G03X730226Y210038I-123J158D01*
G01Y210352D01*
G03X730149Y210510I-200J0D01*
G02X729570Y211695I923J1185D01*
G02X731072Y213197I1502J0D01*
G02X732059Y212827I0J-1501D01*
G01X732060D01*
Y212826D01*
G03X732190Y212778I130J152D01*
G01X732454D01*
G03X732584Y212826I0J200D01*
G01X732585Y212827D01*
G02X733572Y213197I987J-1131D01*
G37*
G36*
G01X631210D02*
G02X632712Y211695I0J-1502D01*
G02X632240Y210602I-1502J0D01*
G01X632239Y210601D01*
G03X632178Y210436I138J-145D01*
G01X632209Y210121D01*
G03X632303Y209971I199J20D01*
G02X633012Y208695I-794J-1276D01*
G02X631510Y207193I-1502J0D01*
G02X630404Y207678I0J1504D01*
G03X630257Y207743I-148J-135D01*
G01X629963D01*
G03X629816Y207678I1J-200D01*
G02X628710Y207193I-1106J1019D01*
G02X627208Y208695I0J1502D01*
G02X627787Y209880I1502J0D01*
G03X627864Y210038I-123J158D01*
G01Y210352D01*
G03X627787Y210510I-200J0D01*
G02X627208Y211695I923J1185D01*
G02X628710Y213197I1502J0D01*
G02X629697Y212827I0J-1501D01*
G01X629698D01*
Y212826D01*
G03X629828Y212778I130J152D01*
G01X630092D01*
G03X630222Y212826I0J200D01*
G01X630223Y212827D01*
G02X631210Y213197I987J-1131D01*
G37*
G36*
G01X528848D02*
G02X530350Y211695I0J-1502D01*
G02X529878Y210602I-1502J0D01*
G01X529877Y210601D01*
G03X529816Y210436I138J-145D01*
G01X529847Y210121D01*
G03X529941Y209971I199J20D01*
G02X530650Y208695I-794J-1276D01*
G02X529148Y207193I-1502J0D01*
G02X528042Y207678I0J1504D01*
G03X527895Y207743I-148J-135D01*
G01X527601D01*
G03X527454Y207678I1J-200D01*
G02X526348Y207193I-1106J1019D01*
G02X524846Y208695I0J1502D01*
G02X525425Y209880I1502J0D01*
G03X525502Y210038I-123J158D01*
G01Y210352D01*
G03X525425Y210510I-200J0D01*
G02X524846Y211695I923J1185D01*
G02X526348Y213197I1502J0D01*
G02X527335Y212827I0J-1501D01*
G01X527336D01*
Y212826D01*
G03X527466Y212778I130J152D01*
G01X527730D01*
G03X527860Y212826I0J200D01*
G01X527861Y212827D01*
G02X528848Y213197I987J-1131D01*
G37*
G36*
G01X378847D02*
G02X380349Y211695I0J-1502D01*
G02X379877Y210602I-1502J0D01*
G01X379876Y210601D01*
G03X379815Y210436I138J-145D01*
G01X379846Y210121D01*
G03X379940Y209971I199J20D01*
G02X380649Y208695I-794J-1276D01*
G02X379147Y207193I-1502J0D01*
G02X378041Y207678I0J1504D01*
G03X377894Y207743I-148J-135D01*
G01X377600D01*
G03X377453Y207678I1J-200D01*
G02X376347Y207193I-1106J1019D01*
G02X374845Y208695I0J1502D01*
G02X375424Y209880I1502J0D01*
G03X375501Y210038I-123J158D01*
G01Y210352D01*
G03X375424Y210510I-200J0D01*
G02X374845Y211695I923J1185D01*
G02X376347Y213197I1502J0D01*
G02X377334Y212827I0J-1501D01*
G01X377335D01*
Y212826D01*
G03X377465Y212778I130J152D01*
G01X377729D01*
G03X377859Y212826I0J200D01*
G01X377860Y212827D01*
G02X378847Y213197I987J-1131D01*
G37*
G36*
G01X276485D02*
G02X277987Y211695I0J-1502D01*
G02X277515Y210602I-1502J0D01*
G01X277514Y210601D01*
G03X277453Y210436I138J-145D01*
G01X277484Y210121D01*
G03X277578Y209971I199J20D01*
G02X278287Y208695I-794J-1276D01*
G02X276785Y207193I-1502J0D01*
G02X275679Y207678I0J1504D01*
G03X275532Y207743I-148J-135D01*
G01X275238D01*
G03X275091Y207678I1J-200D01*
G02X273985Y207193I-1106J1019D01*
G02X272483Y208695I0J1502D01*
G02X273062Y209880I1502J0D01*
G03X273139Y210038I-123J158D01*
G01Y210352D01*
G03X273062Y210510I-200J0D01*
G02X272483Y211695I923J1185D01*
G02X273985Y213197I1502J0D01*
G02X274972Y212827I0J-1501D01*
G01X274973D01*
Y212826D01*
G03X275103Y212778I130J152D01*
G01X275367D01*
G03X275497Y212826I0J200D01*
G01X275498Y212827D01*
G02X276485Y213197I987J-1131D01*
G37*
G36*
G01X174123D02*
G02X175625Y211695I0J-1502D01*
G02X175153Y210602I-1502J0D01*
G01X175152Y210601D01*
G03X175091Y210436I138J-145D01*
G01X175122Y210121D01*
G03X175216Y209971I199J20D01*
G02X175925Y208695I-794J-1276D01*
G02X174423Y207193I-1502J0D01*
G02X173317Y207678I0J1504D01*
G03X173170Y207743I-148J-135D01*
G01X172876D01*
G03X172729Y207678I1J-200D01*
G02X171623Y207193I-1106J1019D01*
G02X170121Y208695I0J1502D01*
G02X170700Y209880I1502J0D01*
G03X170777Y210038I-123J158D01*
G01Y210352D01*
G03X170700Y210510I-200J0D01*
G02X170121Y211695I923J1185D01*
G02X171623Y213197I1502J0D01*
G02X172610Y212827I0J-1501D01*
G01X172611D01*
Y212826D01*
G03X172741Y212778I130J152D01*
G01X173005D01*
G03X173135Y212826I0J200D01*
G01X173136Y212827D01*
G02X174123Y213197I987J-1131D01*
G37*
G36*
G01X1706429Y201748D02*
G02X1707931Y203250I1502J0D01*
G02X1709024Y202778I0J-1502D01*
G01X1709025Y202777D01*
G03X1709190Y202716I145J138D01*
G01X1709505Y202747D01*
G03X1709655Y202841I-20J199D01*
G02X1710931Y203550I1276J-794D01*
G02X1712433Y202048I0J-1502D01*
G02X1711948Y200942I-1504J0D01*
G03X1711883Y200795I135J-148D01*
G01Y200501D01*
G03X1711948Y200354I200J1D01*
G02X1712433Y199248I-1019J-1106D01*
G02X1710931Y197746I-1502J0D01*
G02X1709746Y198325I0J1502D01*
G03X1709588Y198402I-158J-123D01*
G01X1709274D01*
G03X1709116Y198325I0J-200D01*
G02X1707931Y197746I-1185J923D01*
G02X1706429Y199248I0J1502D01*
G02X1706799Y200235I1501J0D01*
G01Y200236D01*
X1706800D01*
G03X1706848Y200366I-152J130D01*
G01Y200630D01*
G03X1706800Y200760I-200J0D01*
G01X1706799Y200761D01*
G02X1706429Y201748I1131J987D01*
G37*
G36*
G01X1604067D02*
G02X1605569Y203250I1502J0D01*
G02X1606662Y202778I0J-1502D01*
G01X1606663Y202777D01*
G03X1606828Y202716I145J138D01*
G01X1607143Y202747D01*
G03X1607293Y202841I-20J199D01*
G02X1608569Y203550I1276J-794D01*
G02X1610071Y202048I0J-1502D01*
G02X1609586Y200942I-1504J0D01*
G03X1609521Y200795I135J-148D01*
G01Y200501D01*
G03X1609586Y200354I200J1D01*
G02X1610071Y199248I-1019J-1106D01*
G02X1608569Y197746I-1502J0D01*
G02X1607384Y198325I0J1502D01*
G03X1607226Y198402I-158J-123D01*
G01X1606912D01*
G03X1606754Y198325I0J-200D01*
G02X1605569Y197746I-1185J923D01*
G02X1604067Y199248I0J1502D01*
G02X1604437Y200235I1501J0D01*
G01Y200236D01*
X1604438D01*
G03X1604486Y200366I-152J130D01*
G01Y200630D01*
G03X1604438Y200760I-200J0D01*
G01X1604437Y200761D01*
G02X1604067Y201748I1131J987D01*
G37*
G36*
G01X1501705D02*
G02X1503207Y203250I1502J0D01*
G02X1504300Y202778I0J-1502D01*
G01X1504301Y202777D01*
G03X1504466Y202716I145J138D01*
G01X1504781Y202747D01*
G03X1504931Y202841I-20J199D01*
G02X1506207Y203550I1276J-794D01*
G02X1507709Y202048I0J-1502D01*
G02X1507224Y200942I-1504J0D01*
G03X1507159Y200795I135J-148D01*
G01Y200501D01*
G03X1507224Y200354I200J1D01*
G02X1507709Y199248I-1019J-1106D01*
G02X1506207Y197746I-1502J0D01*
G02X1505022Y198325I0J1502D01*
G03X1504864Y198402I-158J-123D01*
G01X1504550D01*
G03X1504392Y198325I0J-200D01*
G02X1503207Y197746I-1185J923D01*
G02X1501705Y199248I0J1502D01*
G02X1502075Y200235I1501J0D01*
G01Y200236D01*
X1502076D01*
G03X1502124Y200366I-152J130D01*
G01Y200630D01*
G03X1502076Y200760I-200J0D01*
G01X1502075Y200761D01*
G02X1501705Y201748I1131J987D01*
G37*
G36*
G01X1399343D02*
G02X1400845Y203250I1502J0D01*
G02X1401938Y202778I0J-1502D01*
G01X1401939Y202777D01*
G03X1402104Y202716I145J138D01*
G01X1402419Y202747D01*
G03X1402569Y202841I-20J199D01*
G02X1403845Y203550I1276J-794D01*
G02X1405347Y202048I0J-1502D01*
G02X1404862Y200942I-1504J0D01*
G03X1404797Y200795I135J-148D01*
G01Y200501D01*
G03X1404862Y200354I200J1D01*
G02X1405347Y199248I-1019J-1106D01*
G02X1403845Y197746I-1502J0D01*
G02X1402660Y198325I0J1502D01*
G03X1402502Y198402I-158J-123D01*
G01X1402188D01*
G03X1402030Y198325I0J-200D01*
G02X1400845Y197746I-1185J923D01*
G02X1399343Y199248I0J1502D01*
G02X1399713Y200235I1501J0D01*
G01Y200236D01*
X1399714D01*
G03X1399762Y200366I-152J130D01*
G01Y200630D01*
G03X1399714Y200760I-200J0D01*
G01X1399713Y200761D01*
G02X1399343Y201748I1131J987D01*
G37*
G36*
G01X1249342D02*
G02X1250844Y203250I1502J0D01*
G02X1251937Y202778I0J-1502D01*
G01X1251938Y202777D01*
G03X1252103Y202716I145J138D01*
G01X1252418Y202747D01*
G03X1252568Y202841I-20J199D01*
G02X1253844Y203550I1276J-794D01*
G02X1255346Y202048I0J-1502D01*
G02X1254861Y200942I-1504J0D01*
G03X1254796Y200795I135J-148D01*
G01Y200501D01*
G03X1254861Y200354I200J1D01*
G02X1255346Y199248I-1019J-1106D01*
G02X1253844Y197746I-1502J0D01*
G02X1252659Y198325I0J1502D01*
G03X1252501Y198402I-158J-123D01*
G01X1252187D01*
G03X1252029Y198325I0J-200D01*
G02X1250844Y197746I-1185J923D01*
G02X1249342Y199248I0J1502D01*
G02X1249712Y200235I1501J0D01*
G01Y200236D01*
X1249713D01*
G03X1249761Y200366I-152J130D01*
G01Y200630D01*
G03X1249713Y200760I-200J0D01*
G01X1249712Y200761D01*
G02X1249342Y201748I1131J987D01*
G37*
G36*
G01X1146980D02*
G02X1148482Y203250I1502J0D01*
G02X1149575Y202778I0J-1502D01*
G01X1149576Y202777D01*
G03X1149741Y202716I145J138D01*
G01X1150056Y202747D01*
G03X1150206Y202841I-20J199D01*
G02X1151482Y203550I1276J-794D01*
G02X1152984Y202048I0J-1502D01*
G02X1152499Y200942I-1504J0D01*
G03X1152434Y200795I135J-148D01*
G01Y200501D01*
G03X1152499Y200354I200J1D01*
G02X1152984Y199248I-1019J-1106D01*
G02X1151482Y197746I-1502J0D01*
G02X1150297Y198325I0J1502D01*
G03X1150139Y198402I-158J-123D01*
G01X1149825D01*
G03X1149667Y198325I0J-200D01*
G02X1148482Y197746I-1185J923D01*
G02X1146980Y199248I0J1502D01*
G02X1147350Y200235I1501J0D01*
G01Y200236D01*
X1147351D01*
G03X1147399Y200366I-152J130D01*
G01Y200630D01*
G03X1147351Y200760I-200J0D01*
G01X1147350Y200761D01*
G02X1146980Y201748I1131J987D01*
G37*
G36*
G01X1044618D02*
G02X1046120Y203250I1502J0D01*
G02X1047213Y202778I0J-1502D01*
G01X1047214Y202777D01*
G03X1047379Y202716I145J138D01*
G01X1047694Y202747D01*
G03X1047844Y202841I-20J199D01*
G02X1049120Y203550I1276J-794D01*
G02X1050622Y202048I0J-1502D01*
G02X1050137Y200942I-1504J0D01*
G03X1050072Y200795I135J-148D01*
G01Y200501D01*
G03X1050137Y200354I200J1D01*
G02X1050622Y199248I-1019J-1106D01*
G02X1049120Y197746I-1502J0D01*
G02X1047935Y198325I0J1502D01*
G03X1047777Y198402I-158J-123D01*
G01X1047463D01*
G03X1047305Y198325I0J-200D01*
G02X1046120Y197746I-1185J923D01*
G02X1044618Y199248I0J1502D01*
G02X1044988Y200235I1501J0D01*
G01Y200236D01*
X1044989D01*
G03X1045037Y200366I-152J130D01*
G01Y200630D01*
G03X1044989Y200760I-200J0D01*
G01X1044988Y200761D01*
G02X1044618Y201748I1131J987D01*
G37*
G36*
G01X792256D02*
G02X793758Y203250I1502J0D01*
G02X794851Y202778I0J-1502D01*
G01X794852Y202777D01*
G03X795017Y202716I145J138D01*
G01X795332Y202747D01*
G03X795482Y202841I-20J199D01*
G02X796758Y203550I1276J-794D01*
G02X798260Y202048I0J-1502D01*
G02X797775Y200942I-1504J0D01*
G03X797710Y200795I135J-148D01*
G01Y200501D01*
G03X797775Y200354I200J1D01*
G02X798260Y199248I-1019J-1106D01*
G02X796758Y197746I-1502J0D01*
G02X795573Y198325I0J1502D01*
G03X795415Y198402I-158J-123D01*
G01X795101D01*
G03X794943Y198325I0J-200D01*
G02X793758Y197746I-1185J923D01*
G02X792256Y199248I0J1502D01*
G02X792626Y200235I1501J0D01*
G01Y200236D01*
X792627D01*
G03X792675Y200366I-152J130D01*
G01Y200630D01*
G03X792627Y200760I-200J0D01*
G01X792626Y200761D01*
G02X792256Y201748I1131J987D01*
G37*
G36*
G01X689894D02*
G02X691396Y203250I1502J0D01*
G02X692489Y202778I0J-1502D01*
G01X692490Y202777D01*
G03X692655Y202716I145J138D01*
G01X692970Y202747D01*
G03X693120Y202841I-20J199D01*
G02X694396Y203550I1276J-794D01*
G02X695898Y202048I0J-1502D01*
G02X695413Y200942I-1504J0D01*
G03X695348Y200795I135J-148D01*
G01Y200501D01*
G03X695413Y200354I200J1D01*
G02X695898Y199248I-1019J-1106D01*
G02X694396Y197746I-1502J0D01*
G02X693211Y198325I0J1502D01*
G03X693053Y198402I-158J-123D01*
G01X692739D01*
G03X692581Y198325I0J-200D01*
G02X691396Y197746I-1185J923D01*
G02X689894Y199248I0J1502D01*
G02X690264Y200235I1501J0D01*
G01Y200236D01*
X690265D01*
G03X690313Y200366I-152J130D01*
G01Y200630D01*
G03X690265Y200760I-200J0D01*
G01X690264Y200761D01*
G02X689894Y201748I1131J987D01*
G37*
G36*
G01X587532D02*
G02X589034Y203250I1502J0D01*
G02X590127Y202778I0J-1502D01*
G01X590128Y202777D01*
G03X590293Y202716I145J138D01*
G01X590608Y202747D01*
G03X590758Y202841I-20J199D01*
G02X592034Y203550I1276J-794D01*
G02X593536Y202048I0J-1502D01*
G02X593051Y200942I-1504J0D01*
G03X592986Y200795I135J-148D01*
G01Y200501D01*
G03X593051Y200354I200J1D01*
G02X593536Y199248I-1019J-1106D01*
G02X592034Y197746I-1502J0D01*
G02X590849Y198325I0J1502D01*
G03X590691Y198402I-158J-123D01*
G01X590377D01*
G03X590219Y198325I0J-200D01*
G02X589034Y197746I-1185J923D01*
G02X587532Y199248I0J1502D01*
G02X587902Y200235I1501J0D01*
G01Y200236D01*
X587903D01*
G03X587951Y200366I-152J130D01*
G01Y200630D01*
G03X587903Y200760I-200J0D01*
G01X587902Y200761D01*
G02X587532Y201748I1131J987D01*
G37*
G36*
G01X485170D02*
G02X486672Y203250I1502J0D01*
G02X487765Y202778I0J-1502D01*
G01X487766Y202777D01*
G03X487931Y202716I145J138D01*
G01X488246Y202747D01*
G03X488396Y202841I-20J199D01*
G02X489672Y203550I1276J-794D01*
G02X491174Y202048I0J-1502D01*
G02X490689Y200942I-1504J0D01*
G03X490624Y200795I135J-148D01*
G01Y200501D01*
G03X490689Y200354I200J1D01*
G02X491174Y199248I-1019J-1106D01*
G02X489672Y197746I-1502J0D01*
G02X488487Y198325I0J1502D01*
G03X488329Y198402I-158J-123D01*
G01X488015D01*
G03X487857Y198325I0J-200D01*
G02X486672Y197746I-1185J923D01*
G02X485170Y199248I0J1502D01*
G02X485540Y200235I1501J0D01*
G01Y200236D01*
X485541D01*
G03X485589Y200366I-152J130D01*
G01Y200630D01*
G03X485541Y200760I-200J0D01*
G01X485540Y200761D01*
G02X485170Y201748I1131J987D01*
G37*
G36*
G01X335169D02*
G02X336671Y203250I1502J0D01*
G02X337764Y202778I0J-1502D01*
G01X337765Y202777D01*
G03X337930Y202716I145J138D01*
G01X338245Y202747D01*
G03X338395Y202841I-20J199D01*
G02X339671Y203550I1276J-794D01*
G02X341173Y202048I0J-1502D01*
G02X340688Y200942I-1504J0D01*
G03X340623Y200795I135J-148D01*
G01Y200501D01*
G03X340688Y200354I200J1D01*
G02X341173Y199248I-1019J-1106D01*
G02X339671Y197746I-1502J0D01*
G02X338486Y198325I0J1502D01*
G03X338328Y198402I-158J-123D01*
G01X338014D01*
G03X337856Y198325I0J-200D01*
G02X336671Y197746I-1185J923D01*
G02X335169Y199248I0J1502D01*
G02X335539Y200235I1501J0D01*
G01Y200236D01*
X335540D01*
G03X335588Y200366I-152J130D01*
G01Y200630D01*
G03X335540Y200760I-200J0D01*
G01X335539Y200761D01*
G02X335169Y201748I1131J987D01*
G37*
G36*
G01X232807D02*
G02X234309Y203250I1502J0D01*
G02X235402Y202778I0J-1502D01*
G01X235403Y202777D01*
G03X235568Y202716I145J138D01*
G01X235883Y202747D01*
G03X236033Y202841I-20J199D01*
G02X237309Y203550I1276J-794D01*
G02X238811Y202048I0J-1502D01*
G02X238326Y200942I-1504J0D01*
G03X238261Y200795I135J-148D01*
G01Y200501D01*
G03X238326Y200354I200J1D01*
G02X238811Y199248I-1019J-1106D01*
G02X237309Y197746I-1502J0D01*
G02X236124Y198325I0J1502D01*
G03X235966Y198402I-158J-123D01*
G01X235652D01*
G03X235494Y198325I0J-200D01*
G02X234309Y197746I-1185J923D01*
G02X232807Y199248I0J1502D01*
G02X233177Y200235I1501J0D01*
G01Y200236D01*
X233178D01*
G03X233226Y200366I-152J130D01*
G01Y200630D01*
G03X233178Y200760I-200J0D01*
G01X233177Y200761D01*
G02X232807Y201748I1131J987D01*
G37*
G36*
G01X1011641Y201149D02*
G02X1013116Y202366I1475J-285D01*
G02Y199362I0J-1502D01*
G02X1012360Y199566I0J1503D01*
G03X1011766Y199297I-202J-345D01*
G02X1010291Y198080I-1475J285D01*
G02Y201084I0J1502D01*
G02X1011047Y200880I0J-1503D01*
G03X1011641Y201149I202J345D01*
G37*
G36*
G01X1019992Y175297D02*
Y173279D01*
G02X1019317Y171649I-2306J0D01*
G01X1018702Y171034D01*
G02X1017071Y170358I-1632J1631D01*
G01X1012999D01*
G02Y174972I0J2307D01*
G01X1015180D01*
G03X1015380Y175172I0J200D01*
G01Y185127D01*
G03X1015268Y185307I-200J0D01*
G01X1014945Y185465D01*
G03X1014734Y185443I-88J-180D01*
G02X1014311Y185212I-922J1186D01*
G01X1014310D01*
G03X1014188Y185090I67J-189D01*
G01X1014085Y184796D01*
G03X1014102Y184625I188J-68D01*
G01X1014103Y184624D01*
G02X1014328Y183834I-1277J-791D01*
G02X1011324I-1502J0D01*
G02X1012327Y185251I1502J0D01*
G01X1012328D01*
G03X1012450Y185373I-67J189D01*
G01X1012553Y185667D01*
G03X1012536Y185838I-188J68D01*
G01X1012535Y185839D01*
G02X1012310Y186629I1277J791D01*
G02X1013812Y188131I1502J0D01*
G02X1014734Y187815I0J-1503D01*
G03X1014945Y187793I123J158D01*
G01X1015268Y187951D01*
G03X1015380Y188131I-88J180D01*
G01Y188639D01*
G02X1016055Y190269I2306J0D01*
G01X1020082Y194296D01*
G02X1020757Y194764I1631J-1631D01*
G01X1020759D01*
G03X1020874Y194925I-84J182D01*
G01X1020909Y195270D01*
G03X1020828Y195452I-199J21D01*
G02X1020211Y196665I884J1213D01*
G02X1023215I1502J0D01*
G02X1022598Y195452I-1501J0D01*
G03X1022517Y195270I118J-161D01*
G01X1022552Y194925D01*
G03X1022667Y194764I199J21D01*
G01X1022668D01*
G02X1024020Y192665I-955J-2100D01*
G02X1023344Y191034I-2307J1D01*
G01X1020051Y187742D01*
G03X1019992Y187600I141J-142D01*
G01Y187256D01*
G03X1020384Y187200I200J0D01*
G02X1021826Y188280I1442J-423D01*
G02Y185276I0J-1502D01*
G02X1020694Y185791I0J1502D01*
G01X1020652Y185839D01*
X1020533Y185869D01*
X1020122Y185716D01*
G03X1019992Y185528I70J-187D01*
G01Y178033D01*
G03X1020114Y177849I200J0D01*
G01X1020509Y177682D01*
X1020627Y177704D01*
X1020670Y177746D01*
G02X1021713Y178167I1043J-1081D01*
G02Y175163I0J-1502D01*
G02X1020670Y175584I0J1502D01*
G01X1020627Y175626D01*
X1020509Y175648D01*
X1020114Y175481D01*
G03X1019992Y175297I78J-184D01*
G37*
G36*
G01X297622Y190988D02*
G02Y193992I0J1502D01*
G02X298790Y193434I0J-1501D01*
G01X298822Y193394D01*
X298917Y193356D01*
X299304Y193400D01*
G03X299461Y193512I-23J199D01*
G02X300814Y194361I1353J-654D01*
G02X302316Y192859I0J-1502D01*
G02X302174Y192222I-1502J0D01*
G01X302150Y192171D01*
X302163Y192059D01*
X302452Y191688D01*
X302556Y191649D01*
X302612Y191660D01*
G02X302894Y191687I284J-1475D01*
G01X302897D01*
G02X301395Y190185I0J-1502D01*
G02X301537Y190822I1502J0D01*
G01X301561Y190873D01*
X301548Y190985D01*
X301259Y191356D01*
X301155Y191395D01*
X301099Y191384D01*
G02X300817Y191357I-284J1475D01*
G01X300814D01*
G02X299646Y191915I0J1501D01*
G01X299614Y191955D01*
X299519Y191993D01*
X299132Y191949D01*
G03X298975Y191837I23J-199D01*
G02X297622Y190988I-1353J654D01*
G37*
G36*
G01X942922Y186919D02*
G02X944424Y188421I1502J0D01*
G02X945517Y187949I0J-1502D01*
G01X945518Y187948D01*
G03X945683Y187887I145J138D01*
G01X945998Y187918D01*
G03X946148Y188012I-20J199D01*
G02X947424Y188721I1276J-794D01*
G02X948926Y187219I0J-1502D01*
G02X948441Y186113I-1504J0D01*
G03X948376Y185966I135J-148D01*
G01Y185672D01*
G03X948441Y185525I200J1D01*
G02X948926Y184419I-1019J-1106D01*
G02X947424Y182917I-1502J0D01*
G02X946239Y183496I0J1502D01*
G03X946081Y183573I-158J-123D01*
G01X945767D01*
G03X945609Y183496I0J-200D01*
G02X944424Y182917I-1185J923D01*
G02X942922Y184419I0J1502D01*
G02X943292Y185406I1501J0D01*
G01Y185407D01*
X943293D01*
G03X943341Y185537I-152J130D01*
G01Y185801D01*
G03X943293Y185931I-200J0D01*
G01X943292Y185932D01*
G02X942922Y186919I1131J987D01*
G37*
G36*
G01X1749627Y184221D02*
G02X1751129Y185723I1502J0D01*
G02X1752249Y185222I0J-1502D01*
G01X1752274Y185193D01*
X1752344Y185159D01*
X1752658Y185134D01*
G03X1752799Y185178I15J199D01*
G02X1753746Y185514I947J-1167D01*
G02X1755248Y184012I0J-1502D01*
G02X1754955Y183121I-1501J0D01*
G01Y183120D01*
X1754932Y183089D01*
X1754913Y183013D01*
X1754965Y182657D01*
X1755006Y182588D01*
X1755037Y182565D01*
G02X1755363Y182226I-906J-1198D01*
G03X1755502Y182142I164J114D01*
G01X1755838Y182099D01*
X1755919Y182123D01*
X1755951Y182151D01*
G02X1756927Y182511I976J-1143D01*
G02Y179507I0J-1502D01*
G02X1755696Y180149I0J1501D01*
G03X1755557Y180233I-164J-114D01*
G01X1755221Y180276D01*
X1755140Y180252D01*
X1755108Y180224D01*
G02X1754132Y179864I-976J1143D01*
G02X1752849Y180585I0J1502D01*
G01X1752822Y180629D01*
X1752734Y180680D01*
X1752292Y180688D01*
X1752202Y180641D01*
X1752174Y180598D01*
G02X1750921Y179924I-1253J828D01*
G02X1749419Y181426I0J1502D01*
G02X1749990Y182605I1503J0D01*
G01X1750023Y182631D01*
X1750062Y182705D01*
X1750091Y183084D01*
X1750063Y183162D01*
X1750034Y183193D01*
G02X1749627Y184221I1095J1028D01*
G37*
G36*
G01X1647265D02*
G02X1648767Y185723I1502J0D01*
G02X1649887Y185222I0J-1502D01*
G01X1649912Y185193D01*
X1649982Y185159D01*
X1650296Y185134D01*
G03X1650437Y185178I15J199D01*
G02X1651384Y185514I947J-1167D01*
G02X1652886Y184012I0J-1502D01*
G02X1652593Y183121I-1501J0D01*
G01Y183120D01*
X1652570Y183089D01*
X1652551Y183013D01*
X1652603Y182657D01*
X1652644Y182588D01*
X1652675Y182565D01*
G02X1653001Y182226I-906J-1198D01*
G03X1653140Y182142I164J114D01*
G01X1653476Y182099D01*
X1653557Y182123D01*
X1653589Y182151D01*
G02X1654565Y182511I976J-1143D01*
G02Y179507I0J-1502D01*
G02X1653334Y180149I0J1501D01*
G03X1653195Y180233I-164J-114D01*
G01X1652859Y180276D01*
X1652778Y180252D01*
X1652746Y180224D01*
G02X1651770Y179864I-976J1143D01*
G02X1650487Y180585I0J1502D01*
G01X1650460Y180629D01*
X1650372Y180680D01*
X1649930Y180688D01*
X1649840Y180641D01*
X1649812Y180598D01*
G02X1648559Y179924I-1253J828D01*
G02X1647057Y181426I0J1502D01*
G02X1647628Y182605I1503J0D01*
G01X1647661Y182631D01*
X1647700Y182705D01*
X1647729Y183084D01*
X1647701Y183162D01*
X1647672Y183193D01*
G02X1647265Y184221I1095J1028D01*
G37*
G36*
G01X1544903D02*
G02X1546405Y185723I1502J0D01*
G02X1547525Y185222I0J-1502D01*
G01X1547550Y185193D01*
X1547620Y185159D01*
X1547934Y185134D01*
G03X1548075Y185178I15J199D01*
G02X1549022Y185514I947J-1167D01*
G02X1550524Y184012I0J-1502D01*
G02X1550231Y183121I-1501J0D01*
G01Y183120D01*
X1550208Y183089D01*
X1550189Y183013D01*
X1550241Y182657D01*
X1550282Y182588D01*
X1550313Y182565D01*
G02X1550639Y182226I-906J-1198D01*
G03X1550778Y182142I164J114D01*
G01X1551114Y182099D01*
X1551195Y182123D01*
X1551227Y182151D01*
G02X1552203Y182511I976J-1143D01*
G02Y179507I0J-1502D01*
G02X1550972Y180149I0J1501D01*
G03X1550833Y180233I-164J-114D01*
G01X1550497Y180276D01*
X1550416Y180252D01*
X1550384Y180224D01*
G02X1549408Y179864I-976J1143D01*
G02X1548125Y180585I0J1502D01*
G01X1548098Y180629D01*
X1548010Y180680D01*
X1547568Y180688D01*
X1547478Y180641D01*
X1547450Y180598D01*
G02X1546197Y179924I-1253J828D01*
G02X1544695Y181426I0J1502D01*
G02X1545266Y182605I1503J0D01*
G01X1545299Y182631D01*
X1545338Y182705D01*
X1545367Y183084D01*
X1545339Y183162D01*
X1545310Y183193D01*
G02X1544903Y184221I1095J1028D01*
G37*
G36*
G01X1442541D02*
G02X1444043Y185723I1502J0D01*
G02X1445163Y185222I0J-1502D01*
G01X1445188Y185193D01*
X1445258Y185159D01*
X1445572Y185134D01*
G03X1445713Y185178I15J199D01*
G02X1446660Y185514I947J-1167D01*
G02X1448162Y184012I0J-1502D01*
G02X1447869Y183121I-1501J0D01*
G01Y183120D01*
X1447846Y183089D01*
X1447827Y183013D01*
X1447879Y182657D01*
X1447920Y182588D01*
X1447951Y182565D01*
G02X1448277Y182226I-906J-1198D01*
G03X1448416Y182142I164J114D01*
G01X1448752Y182099D01*
X1448833Y182123D01*
X1448865Y182151D01*
G02X1449841Y182511I976J-1143D01*
G02Y179507I0J-1502D01*
G02X1448610Y180149I0J1501D01*
G03X1448471Y180233I-164J-114D01*
G01X1448135Y180276D01*
X1448054Y180252D01*
X1448022Y180224D01*
G02X1447046Y179864I-976J1143D01*
G02X1445763Y180585I0J1502D01*
G01X1445736Y180629D01*
X1445648Y180680D01*
X1445206Y180688D01*
X1445116Y180641D01*
X1445088Y180598D01*
G02X1443835Y179924I-1253J828D01*
G02X1442333Y181426I0J1502D01*
G02X1442904Y182605I1503J0D01*
G01X1442937Y182631D01*
X1442976Y182705D01*
X1443005Y183084D01*
X1442977Y183162D01*
X1442948Y183193D01*
G02X1442541Y184221I1095J1028D01*
G37*
G36*
G01X1292540D02*
G02X1294042Y185723I1502J0D01*
G02X1295162Y185222I0J-1502D01*
G01X1295187Y185193D01*
X1295257Y185159D01*
X1295571Y185134D01*
G03X1295712Y185178I15J199D01*
G02X1296659Y185514I947J-1167D01*
G02X1298161Y184012I0J-1502D01*
G02X1297868Y183121I-1501J0D01*
G01Y183120D01*
X1297845Y183089D01*
X1297826Y183013D01*
X1297878Y182657D01*
X1297919Y182588D01*
X1297950Y182565D01*
G02X1298276Y182226I-906J-1198D01*
G03X1298415Y182142I164J114D01*
G01X1298751Y182099D01*
X1298832Y182123D01*
X1298864Y182151D01*
G02X1299840Y182511I976J-1143D01*
G02Y179507I0J-1502D01*
G02X1298609Y180149I0J1501D01*
G03X1298470Y180233I-164J-114D01*
G01X1298134Y180276D01*
X1298053Y180252D01*
X1298021Y180224D01*
G02X1297045Y179864I-976J1143D01*
G02X1295762Y180585I0J1502D01*
G01X1295735Y180629D01*
X1295647Y180680D01*
X1295205Y180688D01*
X1295115Y180641D01*
X1295087Y180598D01*
G02X1293834Y179924I-1253J828D01*
G02X1292332Y181426I0J1502D01*
G02X1292903Y182605I1503J0D01*
G01X1292936Y182631D01*
X1292975Y182705D01*
X1293004Y183084D01*
X1292976Y183162D01*
X1292947Y183193D01*
G02X1292540Y184221I1095J1028D01*
G37*
G36*
G01X1190178D02*
G02X1191680Y185723I1502J0D01*
G02X1192800Y185222I0J-1502D01*
G01X1192825Y185193D01*
X1192895Y185159D01*
X1193209Y185134D01*
G03X1193350Y185178I15J199D01*
G02X1194297Y185514I947J-1167D01*
G02X1195799Y184012I0J-1502D01*
G02X1195506Y183121I-1501J0D01*
G01Y183120D01*
X1195483Y183089D01*
X1195464Y183013D01*
X1195516Y182657D01*
X1195557Y182588D01*
X1195588Y182565D01*
G02X1195914Y182226I-906J-1198D01*
G03X1196053Y182142I164J114D01*
G01X1196389Y182099D01*
X1196470Y182123D01*
X1196502Y182151D01*
G02X1197478Y182511I976J-1143D01*
G02Y179507I0J-1502D01*
G02X1196247Y180149I0J1501D01*
G03X1196108Y180233I-164J-114D01*
G01X1195772Y180276D01*
X1195691Y180252D01*
X1195659Y180224D01*
G02X1194683Y179864I-976J1143D01*
G02X1193400Y180585I0J1502D01*
G01X1193373Y180629D01*
X1193285Y180680D01*
X1192843Y180688D01*
X1192753Y180641D01*
X1192725Y180598D01*
G02X1191472Y179924I-1253J828D01*
G02X1189970Y181426I0J1502D01*
G02X1190541Y182605I1503J0D01*
G01X1190574Y182631D01*
X1190613Y182705D01*
X1190642Y183084D01*
X1190614Y183162D01*
X1190585Y183193D01*
G02X1190178Y184221I1095J1028D01*
G37*
G36*
G01X1087816D02*
G02X1089318Y185723I1502J0D01*
G02X1090438Y185222I0J-1502D01*
G01X1090463Y185193D01*
X1090533Y185159D01*
X1090847Y185134D01*
G03X1090988Y185178I15J199D01*
G02X1091935Y185514I947J-1167D01*
G02X1093437Y184012I0J-1502D01*
G02X1093144Y183121I-1501J0D01*
G01Y183120D01*
X1093121Y183089D01*
X1093102Y183013D01*
X1093154Y182657D01*
X1093195Y182588D01*
X1093226Y182565D01*
G02X1093552Y182226I-906J-1198D01*
G03X1093691Y182142I164J114D01*
G01X1094027Y182099D01*
X1094108Y182123D01*
X1094140Y182151D01*
G02X1095116Y182511I976J-1143D01*
G02Y179507I0J-1502D01*
G02X1093885Y180149I0J1501D01*
G03X1093746Y180233I-164J-114D01*
G01X1093410Y180276D01*
X1093329Y180252D01*
X1093297Y180224D01*
G02X1092321Y179864I-976J1143D01*
G02X1091038Y180585I0J1502D01*
G01X1091011Y180629D01*
X1090923Y180680D01*
X1090481Y180688D01*
X1090391Y180641D01*
X1090363Y180598D01*
G02X1089110Y179924I-1253J828D01*
G02X1087608Y181426I0J1502D01*
G02X1088179Y182605I1503J0D01*
G01X1088212Y182631D01*
X1088251Y182705D01*
X1088280Y183084D01*
X1088252Y183162D01*
X1088223Y183193D01*
G02X1087816Y184221I1095J1028D01*
G37*
G36*
G01X985454D02*
G02X986956Y185723I1502J0D01*
G02X988076Y185222I0J-1502D01*
G01X988101Y185193D01*
X988171Y185159D01*
X988485Y185134D01*
G03X988626Y185178I15J199D01*
G02X989573Y185514I947J-1167D01*
G02X991075Y184012I0J-1502D01*
G02X990782Y183121I-1501J0D01*
G01Y183120D01*
X990759Y183089D01*
X990740Y183013D01*
X990792Y182657D01*
X990833Y182588D01*
X990864Y182565D01*
G02X991190Y182226I-906J-1198D01*
G03X991329Y182142I164J114D01*
G01X991665Y182099D01*
X991746Y182123D01*
X991778Y182151D01*
G02X992754Y182511I976J-1143D01*
G02Y179507I0J-1502D01*
G02X991523Y180149I0J1501D01*
G03X991384Y180233I-164J-114D01*
G01X991048Y180276D01*
X990967Y180252D01*
X990935Y180224D01*
G02X989959Y179864I-976J1143D01*
G02X988676Y180585I0J1502D01*
G01X988649Y180629D01*
X988561Y180680D01*
X988119Y180688D01*
X988029Y180641D01*
X988001Y180598D01*
G02X986748Y179924I-1253J828D01*
G02X985246Y181426I0J1502D01*
G02X985817Y182605I1503J0D01*
G01X985850Y182631D01*
X985889Y182705D01*
X985918Y183084D01*
X985890Y183162D01*
X985861Y183193D01*
G02X985454Y184221I1095J1028D01*
G37*
G36*
G01X835454D02*
G02X836956Y185723I1502J0D01*
G02X838076Y185222I0J-1502D01*
G01X838101Y185193D01*
X838171Y185159D01*
X838485Y185134D01*
G03X838626Y185178I15J199D01*
G02X839573Y185514I947J-1167D01*
G02X841075Y184012I0J-1502D01*
G02X840782Y183121I-1501J0D01*
G01Y183120D01*
X840759Y183089D01*
X840740Y183013D01*
X840792Y182657D01*
X840833Y182588D01*
X840864Y182565D01*
G02X841190Y182226I-906J-1198D01*
G03X841329Y182142I164J114D01*
G01X841665Y182099D01*
X841746Y182123D01*
X841778Y182151D01*
G02X842754Y182511I976J-1143D01*
G02Y179507I0J-1502D01*
G02X841523Y180149I0J1501D01*
G03X841384Y180233I-164J-114D01*
G01X841048Y180276D01*
X840967Y180252D01*
X840935Y180224D01*
G02X839959Y179864I-976J1143D01*
G02X838676Y180585I0J1502D01*
G01X838649Y180629D01*
X838561Y180680D01*
X838119Y180688D01*
X838029Y180641D01*
X838001Y180598D01*
G02X836748Y179924I-1253J828D01*
G02X835246Y181426I0J1502D01*
G02X835817Y182605I1503J0D01*
G01X835850Y182631D01*
X835889Y182705D01*
X835918Y183084D01*
X835890Y183162D01*
X835861Y183193D01*
G02X835454Y184221I1095J1028D01*
G37*
G36*
G01X733092D02*
G02X734594Y185723I1502J0D01*
G02X735714Y185222I0J-1502D01*
G01X735739Y185193D01*
X735809Y185159D01*
X736123Y185134D01*
G03X736264Y185178I15J199D01*
G02X737211Y185514I947J-1167D01*
G02X738713Y184012I0J-1502D01*
G02X738420Y183121I-1501J0D01*
G01Y183120D01*
X738397Y183089D01*
X738378Y183013D01*
X738430Y182657D01*
X738471Y182588D01*
X738502Y182565D01*
G02X738828Y182226I-906J-1198D01*
G03X738967Y182142I164J114D01*
G01X739303Y182099D01*
X739384Y182123D01*
X739416Y182151D01*
G02X740392Y182511I976J-1143D01*
G02Y179507I0J-1502D01*
G02X739161Y180149I0J1501D01*
G03X739022Y180233I-164J-114D01*
G01X738686Y180276D01*
X738605Y180252D01*
X738573Y180224D01*
G02X737597Y179864I-976J1143D01*
G02X736314Y180585I0J1502D01*
G01X736287Y180629D01*
X736199Y180680D01*
X735757Y180688D01*
X735667Y180641D01*
X735639Y180598D01*
G02X734386Y179924I-1253J828D01*
G02X732884Y181426I0J1502D01*
G02X733455Y182605I1503J0D01*
G01X733488Y182631D01*
X733527Y182705D01*
X733556Y183084D01*
X733528Y183162D01*
X733499Y183193D01*
G02X733092Y184221I1095J1028D01*
G37*
G36*
G01X630730D02*
G02X632232Y185723I1502J0D01*
G02X633352Y185222I0J-1502D01*
G01X633377Y185193D01*
X633447Y185159D01*
X633761Y185134D01*
G03X633902Y185178I15J199D01*
G02X634849Y185514I947J-1167D01*
G02X636351Y184012I0J-1502D01*
G02X636058Y183121I-1501J0D01*
G01Y183120D01*
X636035Y183089D01*
X636016Y183013D01*
X636068Y182657D01*
X636109Y182588D01*
X636140Y182565D01*
G02X636466Y182226I-906J-1198D01*
G03X636605Y182142I164J114D01*
G01X636941Y182099D01*
X637022Y182123D01*
X637054Y182151D01*
G02X638030Y182511I976J-1143D01*
G02Y179507I0J-1502D01*
G02X636799Y180149I0J1501D01*
G03X636660Y180233I-164J-114D01*
G01X636324Y180276D01*
X636243Y180252D01*
X636211Y180224D01*
G02X635235Y179864I-976J1143D01*
G02X633952Y180585I0J1502D01*
G01X633925Y180629D01*
X633837Y180680D01*
X633395Y180688D01*
X633305Y180641D01*
X633277Y180598D01*
G02X632024Y179924I-1253J828D01*
G02X630522Y181426I0J1502D01*
G02X631093Y182605I1503J0D01*
G01X631126Y182631D01*
X631165Y182705D01*
X631194Y183084D01*
X631166Y183162D01*
X631137Y183193D01*
G02X630730Y184221I1095J1028D01*
G37*
G36*
G01X528368D02*
G02X529870Y185723I1502J0D01*
G02X530990Y185222I0J-1502D01*
G01X531015Y185193D01*
X531085Y185159D01*
X531399Y185134D01*
G03X531540Y185178I15J199D01*
G02X532487Y185514I947J-1167D01*
G02X533989Y184012I0J-1502D01*
G02X533696Y183121I-1501J0D01*
G01Y183120D01*
X533673Y183089D01*
X533654Y183013D01*
X533706Y182657D01*
X533747Y182588D01*
X533778Y182565D01*
G02X534104Y182226I-906J-1198D01*
G03X534243Y182142I164J114D01*
G01X534579Y182099D01*
X534660Y182123D01*
X534692Y182151D01*
G02X535668Y182511I976J-1143D01*
G02Y179507I0J-1502D01*
G02X534437Y180149I0J1501D01*
G03X534298Y180233I-164J-114D01*
G01X533962Y180276D01*
X533881Y180252D01*
X533849Y180224D01*
G02X532873Y179864I-976J1143D01*
G02X531590Y180585I0J1502D01*
G01X531563Y180629D01*
X531475Y180680D01*
X531033Y180688D01*
X530943Y180641D01*
X530915Y180598D01*
G02X529662Y179924I-1253J828D01*
G02X528160Y181426I0J1502D01*
G02X528731Y182605I1503J0D01*
G01X528764Y182631D01*
X528803Y182705D01*
X528832Y183084D01*
X528804Y183162D01*
X528775Y183193D01*
G02X528368Y184221I1095J1028D01*
G37*
G36*
G01X378367D02*
G02X379869Y185723I1502J0D01*
G02X380989Y185222I0J-1502D01*
G01X381014Y185193D01*
X381084Y185159D01*
X381398Y185134D01*
G03X381539Y185178I15J199D01*
G02X382486Y185514I947J-1167D01*
G02X383988Y184012I0J-1502D01*
G02X383695Y183121I-1501J0D01*
G01Y183120D01*
X383672Y183089D01*
X383653Y183013D01*
X383705Y182657D01*
X383746Y182588D01*
X383777Y182565D01*
G02X384103Y182226I-906J-1198D01*
G03X384242Y182142I164J114D01*
G01X384578Y182099D01*
X384659Y182123D01*
X384691Y182151D01*
G02X385667Y182511I976J-1143D01*
G02Y179507I0J-1502D01*
G02X384436Y180149I0J1501D01*
G03X384297Y180233I-164J-114D01*
G01X383961Y180276D01*
X383880Y180252D01*
X383848Y180224D01*
G02X382872Y179864I-976J1143D01*
G02X381589Y180585I0J1502D01*
G01X381562Y180629D01*
X381474Y180680D01*
X381032Y180688D01*
X380942Y180641D01*
X380914Y180598D01*
G02X379661Y179924I-1253J828D01*
G02X378159Y181426I0J1502D01*
G02X378730Y182605I1503J0D01*
G01X378763Y182631D01*
X378802Y182705D01*
X378831Y183084D01*
X378803Y183162D01*
X378774Y183193D01*
G02X378367Y184221I1095J1028D01*
G37*
G36*
G01X276005D02*
G02X277507Y185723I1502J0D01*
G02X278627Y185222I0J-1502D01*
G01X278652Y185193D01*
X278722Y185159D01*
X279036Y185134D01*
G03X279177Y185178I15J199D01*
G02X280124Y185514I947J-1167D01*
G02X281626Y184012I0J-1502D01*
G02X281333Y183121I-1501J0D01*
G01Y183120D01*
X281310Y183089D01*
X281291Y183013D01*
X281343Y182657D01*
X281384Y182588D01*
X281415Y182565D01*
G02X281741Y182226I-906J-1198D01*
G03X281880Y182142I164J114D01*
G01X282216Y182099D01*
X282297Y182123D01*
X282329Y182151D01*
G02X283305Y182511I976J-1143D01*
G02Y179507I0J-1502D01*
G02X282074Y180149I0J1501D01*
G03X281935Y180233I-164J-114D01*
G01X281599Y180276D01*
X281518Y180252D01*
X281486Y180224D01*
G02X280510Y179864I-976J1143D01*
G02X279227Y180585I0J1502D01*
G01X279200Y180629D01*
X279112Y180680D01*
X278670Y180688D01*
X278580Y180641D01*
X278552Y180598D01*
G02X277299Y179924I-1253J828D01*
G02X275797Y181426I0J1502D01*
G02X276368Y182605I1503J0D01*
G01X276401Y182631D01*
X276440Y182705D01*
X276469Y183084D01*
X276441Y183162D01*
X276412Y183193D01*
G02X276005Y184221I1095J1028D01*
G37*
G36*
G01X173643D02*
G02X175145Y185723I1502J0D01*
G02X176265Y185222I0J-1502D01*
G01X176290Y185193D01*
X176360Y185159D01*
X176674Y185134D01*
G03X176815Y185178I15J199D01*
G02X177762Y185514I947J-1167D01*
G02X179264Y184012I0J-1502D01*
G02X178971Y183121I-1501J0D01*
G01Y183120D01*
X178948Y183089D01*
X178929Y183013D01*
X178981Y182657D01*
X179022Y182588D01*
X179053Y182565D01*
G02X179379Y182226I-906J-1198D01*
G03X179518Y182142I164J114D01*
G01X179854Y182099D01*
X179935Y182123D01*
X179967Y182151D01*
G02X180943Y182511I976J-1143D01*
G02Y179507I0J-1502D01*
G02X179712Y180149I0J1501D01*
G03X179573Y180233I-164J-114D01*
G01X179237Y180276D01*
X179156Y180252D01*
X179124Y180224D01*
G02X178148Y179864I-976J1143D01*
G02X176865Y180585I0J1502D01*
G01X176838Y180629D01*
X176750Y180680D01*
X176308Y180688D01*
X176218Y180641D01*
X176190Y180598D01*
G02X174937Y179924I-1253J828D01*
G02X173435Y181426I0J1502D01*
G02X174006Y182605I1503J0D01*
G01X174039Y182631D01*
X174078Y182705D01*
X174107Y183084D01*
X174079Y183162D01*
X174050Y183193D01*
G02X173643Y184221I1095J1028D01*
G37*
G36*
G01X1672089Y151610D02*
G02X1670795Y150871I-1294J763D01*
G02Y153875I0J1502D01*
G02X1671989Y153285I0J-1503D01*
G03X1672651Y153325I318J243D01*
G02X1673945Y154064I1294J-763D01*
G02Y151060I0J-1502D01*
G02X1672751Y151650I0J1503D01*
G03X1672089Y151610I-318J-243D01*
G37*
G36*
G01X1569727D02*
G02X1568433Y150871I-1294J763D01*
G02Y153875I0J1502D01*
G02X1569627Y153285I0J-1503D01*
G03X1570289Y153325I318J243D01*
G02X1571583Y154064I1294J-763D01*
G02Y151060I0J-1502D01*
G02X1570389Y151650I0J1503D01*
G03X1569727Y151610I-318J-243D01*
G37*
G36*
G01X1467365D02*
G02X1466071Y150871I-1294J763D01*
G02Y153875I0J1502D01*
G02X1467265Y153285I0J-1503D01*
G03X1467927Y153325I318J243D01*
G02X1469221Y154064I1294J-763D01*
G02Y151060I0J-1502D01*
G02X1468027Y151650I0J1503D01*
G03X1467365Y151610I-318J-243D01*
G37*
G36*
G01X1365003D02*
G02X1363709Y150871I-1294J763D01*
G02Y153875I0J1502D01*
G02X1364903Y153285I0J-1503D01*
G03X1365565Y153325I318J243D01*
G02X1366859Y154064I1294J-763D01*
G02Y151060I0J-1502D01*
G02X1365665Y151650I0J1503D01*
G03X1365003Y151610I-318J-243D01*
G37*
G36*
G01X1215002D02*
G02X1213708Y150871I-1294J763D01*
G02Y153875I0J1502D01*
G02X1214902Y153285I0J-1503D01*
G03X1215564Y153325I318J243D01*
G02X1216858Y154064I1294J-763D01*
G02Y151060I0J-1502D01*
G02X1215664Y151650I0J1503D01*
G03X1215002Y151610I-318J-243D01*
G37*
G36*
G01X1112640D02*
G02X1111346Y150871I-1294J763D01*
G02Y153875I0J1502D01*
G02X1112540Y153285I0J-1503D01*
G03X1113202Y153325I318J243D01*
G02X1114496Y154064I1294J-763D01*
G02Y151060I0J-1502D01*
G02X1113302Y151650I0J1503D01*
G03X1112640Y151610I-318J-243D01*
G37*
G36*
G01X1010278D02*
G02X1008984Y150871I-1294J763D01*
G02Y153875I0J1502D01*
G02X1010178Y153285I0J-1503D01*
G03X1010840Y153325I318J243D01*
G02X1012134Y154064I1294J-763D01*
G02Y151060I0J-1502D01*
G02X1010940Y151650I0J1503D01*
G03X1010278Y151610I-318J-243D01*
G37*
G36*
G01X907916D02*
G02X906622Y150871I-1294J763D01*
G02Y153875I0J1502D01*
G02X907816Y153285I0J-1503D01*
G03X908478Y153325I318J243D01*
G02X909772Y154064I1294J-763D01*
G02Y151060I0J-1502D01*
G02X908578Y151650I0J1503D01*
G03X907916Y151610I-318J-243D01*
G37*
G36*
G01X757916D02*
G02X756622Y150871I-1294J763D01*
G02Y153875I0J1502D01*
G02X757816Y153285I0J-1503D01*
G03X758478Y153325I318J243D01*
G02X759772Y154064I1294J-763D01*
G02Y151060I0J-1502D01*
G02X758578Y151650I0J1503D01*
G03X757916Y151610I-318J-243D01*
G37*
G36*
G01X655554D02*
G02X654260Y150871I-1294J763D01*
G02Y153875I0J1502D01*
G02X655454Y153285I0J-1503D01*
G03X656116Y153325I318J243D01*
G02X657410Y154064I1294J-763D01*
G02Y151060I0J-1502D01*
G02X656216Y151650I0J1503D01*
G03X655554Y151610I-318J-243D01*
G37*
G36*
G01X553192D02*
G02X551898Y150871I-1294J763D01*
G02Y153875I0J1502D01*
G02X553092Y153285I0J-1503D01*
G03X553754Y153325I318J243D01*
G02X555048Y154064I1294J-763D01*
G02Y151060I0J-1502D01*
G02X553854Y151650I0J1503D01*
G03X553192Y151610I-318J-243D01*
G37*
G36*
G01X450830D02*
G02X449536Y150871I-1294J763D01*
G02Y153875I0J1502D01*
G02X450730Y153285I0J-1503D01*
G03X451392Y153325I318J243D01*
G02X452686Y154064I1294J-763D01*
G02Y151060I0J-1502D01*
G02X451492Y151650I0J1503D01*
G03X450830Y151610I-318J-243D01*
G37*
G36*
G01X300829D02*
G02X299535Y150871I-1294J763D01*
G02Y153875I0J1502D01*
G02X300729Y153285I0J-1503D01*
G03X301391Y153325I318J243D01*
G02X302685Y154064I1294J-763D01*
G02Y151060I0J-1502D01*
G02X301491Y151650I0J1503D01*
G03X300829Y151610I-318J-243D01*
G37*
G36*
G01X198467D02*
G02X197173Y150871I-1294J763D01*
G02Y153875I0J1502D01*
G02X198367Y153285I0J-1503D01*
G03X199029Y153325I318J243D01*
G02X200323Y154064I1294J-763D01*
G02Y151060I0J-1502D01*
G02X199129Y151650I0J1503D01*
G03X198467Y151610I-318J-243D01*
G37*
G36*
G01X44280Y1255138D02*
X44616D01*
X44683Y1255163D01*
X44711Y1255187D01*
G02X46685I987J-1131D01*
G01X46713Y1255163D01*
X46780Y1255138D01*
X47116D01*
X47183Y1255163D01*
X47211Y1255187D01*
G02X48198Y1255557I987J-1131D01*
G02X49700Y1254055I0J-1502D01*
G02X49330Y1253068I-1501J0D01*
G01X49306Y1253040D01*
X49281Y1252973D01*
Y1252637D01*
X49306Y1252570D01*
X49330Y1252542D01*
G02X49700Y1251555I-1131J-987D01*
G02X48198Y1250053I-1502J0D01*
G02X47211Y1250423I0J1501D01*
G01X47183Y1250447D01*
X47116Y1250472D01*
X46780D01*
X46713Y1250447D01*
X46685Y1250423D01*
G02X44711I-987J1131D01*
G01X44683Y1250447D01*
X44616Y1250472D01*
X44280D01*
X44213Y1250447D01*
X44185Y1250423D01*
G02X43198Y1250053I-987J1131D01*
G02X41696Y1251555I0J1502D01*
G02X42066Y1252542I1501J0D01*
G01X42090Y1252570D01*
X42115Y1252637D01*
Y1252973D01*
X42090Y1253040D01*
X42066Y1253068D01*
G02X41696Y1254055I1131J987D01*
G02X43198Y1255557I1502J0D01*
G02X44185Y1255187I0J-1501D01*
G01X44213Y1255163D01*
X44280Y1255138D01*
G37*
G36*
G01X22089Y160416D02*
Y160730D01*
G03X22012Y160888I-200J0D01*
G02X21433Y162073I923J1185D01*
G02X24437I1502J0D01*
G02X23858Y160888I-1502J0D01*
G03X23781Y160730I123J-158D01*
G01Y160416D01*
G03X23858Y160258I200J0D01*
G02X24437Y159073I-923J-1185D01*
G02X21433I-1502J0D01*
G02X22012Y160258I1502J0D01*
G03X22089Y160416I-123J158D01*
G37*
G36*
G01X31554Y196308D02*
X31555Y196307D01*
G03X31685Y196259I130J152D01*
G01X31949D01*
G03X32079Y196307I0J200D01*
G01X32080Y196308D01*
G02X33067Y196678I987J-1131D01*
G02Y193674I0J-1502D01*
G02X32080Y194044I0J1501D01*
G01X32079D01*
Y194045D01*
G03X31949Y194093I-130J-152D01*
G01X31685D01*
G03X31555Y194045I0J-200D01*
G01X31554Y194044D01*
G02X29580I-987J1131D01*
G01X29579D01*
Y194045D01*
G03X29449Y194093I-130J-152D01*
G01X29185D01*
G03X29055Y194045I0J-200D01*
G01X29054Y194044D01*
G02X27080I-987J1131D01*
G01X27079D01*
Y194045D01*
G03X26949Y194093I-130J-152D01*
G01X26685D01*
G03X26555Y194045I0J-200D01*
G01X26554Y194044D01*
G02X25567Y193674I-987J1131D01*
G02Y196678I0J1502D01*
G02X26554Y196308I0J-1501D01*
G01X26555D01*
Y196307D01*
G03X26685Y196259I130J152D01*
G01X26949D01*
G03X27079Y196307I0J200D01*
G01X27080Y196308D01*
G02X29054I987J-1131D01*
G01X29055D01*
Y196307D01*
G03X29185Y196259I130J152D01*
G01X29449D01*
G03X29579Y196307I0J200D01*
G01X29580Y196308D01*
G02X31554I987J-1131D01*
G37*
G36*
G01X27421Y205304D02*
G02Y208308I0J1502D01*
G02X28408Y207938I0J-1501D01*
G01X28409D01*
Y207937D01*
G03X28539Y207889I130J152D01*
G01X28803D01*
G03X28933Y207937I0J200D01*
G01X28934Y207938D01*
G02X29921Y208308I987J-1131D01*
G02Y205304I0J-1502D01*
G02X28934Y205674I0J1501D01*
G01X28933D01*
Y205675D01*
G03X28803Y205723I-130J-152D01*
G01X28539D01*
G03X28409Y205675I0J-200D01*
G01X28408Y205674D01*
G02X27421Y205304I-987J1131D01*
G37*
G36*
G01X25648Y209007D02*
G02Y212011I0J1502D01*
G02X26635Y211641I0J-1501D01*
G01X26636D01*
Y211640D01*
G03X26766Y211592I130J152D01*
G01X27030D01*
G03X27160Y211640I0J200D01*
G01X27161Y211641D01*
G02X28148Y212011I987J-1131D01*
G02Y209007I0J-1502D01*
G02X27161Y209377I0J1501D01*
G01X27160D01*
Y209378D01*
G03X27030Y209426I-130J-152D01*
G01X26766D01*
G03X26636Y209378I0J-200D01*
G01X26635Y209377D01*
G02X25648Y209007I-987J1131D01*
G37*
G36*
G01X18070Y221970D02*
G02X21074I1502J0D01*
G02X20704Y220983I-1501J0D01*
G01Y220982D01*
X20703D01*
G03X20655Y220852I152J-130D01*
G01Y220588D01*
G03X20703Y220458I200J0D01*
G01X20704Y220457D01*
G02Y218483I-1131J-987D01*
G01Y218482D01*
X20703D01*
G03X20655Y218352I152J-130D01*
G01Y218088D01*
G03X20703Y217958I200J0D01*
G01X20704Y217957D01*
G02X21074Y216970I-1131J-987D01*
G02X19572Y215468I-1502J0D01*
G02X18717Y215735I0J1502D01*
G01X18683Y215758D01*
X18602Y215775D01*
X18235Y215695D01*
X18168Y215647D01*
X18147Y215612D01*
G02X16859Y214883I-1288J773D01*
G02Y217887I0J1502D01*
G02X17714Y217620I0J-1502D01*
G01X17748Y217597D01*
X17829Y217580D01*
X18196Y217660D01*
X18263Y217708D01*
X18284Y217743D01*
G02X18440Y217956I1285J-777D01*
G03X18441Y217958I-173J88D01*
G03X18489Y218088I-152J130D01*
G01Y218352D01*
G03X18441Y218482I-200J0D01*
G01X18440Y218483D01*
G02Y220457I1131J987D01*
G01Y220458D01*
X18441D01*
G03X18489Y220588I-152J130D01*
G01Y220852D01*
G03X18441Y220982I-200J0D01*
G01X18440Y220983D01*
G02X18070Y221970I1131J987D01*
G37*
G36*
G01X28083Y201748D02*
G02X29585Y203250I1502J0D01*
G02X30678Y202778I0J-1502D01*
G01X30679Y202777D01*
G03X30844Y202716I145J138D01*
G01X31159Y202747D01*
G03X31309Y202841I-20J199D01*
G02X32585Y203550I1276J-794D01*
G02X34087Y202048I0J-1502D01*
G02X33602Y200942I-1504J0D01*
G03X33537Y200795I135J-148D01*
G01Y200501D01*
G03X33602Y200354I200J1D01*
G02X34087Y199248I-1019J-1106D01*
G02X32585Y197746I-1502J0D01*
G02X31400Y198325I0J1502D01*
G03X31242Y198402I-158J-123D01*
G01X30928D01*
G03X30770Y198325I0J-200D01*
G02X29585Y197746I-1185J923D01*
G02X28083Y199248I0J1502D01*
G02X28453Y200235I1501J0D01*
G01Y200236D01*
X28454D01*
G03X28502Y200366I-152J130D01*
G01Y200630D01*
G03X28454Y200760I-200J0D01*
G01X28453Y200761D01*
G02X28083Y201748I1131J987D01*
G37*
G36*
G01X63878Y160866D02*
G02Y163870I0J1502D01*
G02X64905Y163464I0J-1502D01*
G01X64932Y163438D01*
X65003Y163410D01*
X65353D01*
X65424Y163438D01*
X65451Y163464D01*
G02X66478Y163870I1027J-1096D01*
G02Y160866I0J-1502D01*
G02X65451Y161272I0J1502D01*
G01X65424Y161298D01*
X65353Y161326D01*
X65003D01*
X64932Y161298D01*
X64905Y161272D01*
G02X63878Y160866I-1027J1096D01*
G37*
G36*
G01X72076Y170493D02*
G02X75080I1502J0D01*
G02X74710Y169506I-1501J0D01*
G01Y169505D01*
X74709D01*
G03X74661Y169375I152J-130D01*
G01Y169111D01*
G03X74709Y168981I200J0D01*
G01X74710Y168980D01*
G02X75080Y167993I-1131J-987D01*
G02X74674Y166966I-1502J0D01*
G01X74648Y166939D01*
X74620Y166868D01*
Y166518D01*
X74648Y166447D01*
X74674Y166420D01*
G02Y164366I-1096J-1027D01*
G01X74648Y164339D01*
X74620Y164268D01*
Y163918D01*
X74648Y163847D01*
X74674Y163820D01*
G02X75080Y162793I-1096J-1027D01*
G02X72076I-1502J0D01*
G02X72482Y163820I1502J0D01*
G01X72508Y163847D01*
X72536Y163918D01*
Y164268D01*
X72508Y164339D01*
X72482Y164366D01*
G02Y166420I1096J1027D01*
G01X72508Y166447D01*
X72536Y166518D01*
Y166868D01*
X72508Y166939D01*
X72482Y166966D01*
G02X72076Y167993I1096J1027D01*
G02X72446Y168980I1501J0D01*
G01Y168981D01*
X72447D01*
G03X72495Y169111I-152J130D01*
G01Y169375D01*
G03X72447Y169505I-200J0D01*
G01X72446Y169506D01*
G02X72076Y170493I1131J987D01*
G37*
G36*
G01X98137Y186629D02*
G02X101141I1502J0D01*
G02X100138Y185212I-1502J0D01*
G01X100137D01*
G03X100015Y185090I67J-189D01*
G01X99912Y184796D01*
G03X99929Y184625I188J-68D01*
G01X99930Y184624D01*
G02X100155Y183834I-1277J-791D01*
G02X97151I-1502J0D01*
G02X98154Y185251I1502J0D01*
G01X98155D01*
G03X98277Y185373I-67J189D01*
G01X98380Y185667D01*
G03X98363Y185838I-188J68D01*
G01X98362Y185839D01*
G02X98137Y186629I1277J791D01*
G37*
G36*
G01X133916Y196308D02*
X133917Y196307D01*
G03X134047Y196259I130J152D01*
G01X134311D01*
G03X134441Y196307I0J200D01*
G01X134442Y196308D01*
G02X135429Y196678I987J-1131D01*
G02Y193674I0J-1502D01*
G02X134442Y194044I0J1501D01*
G01X134441D01*
Y194045D01*
G03X134311Y194093I-130J-152D01*
G01X134047D01*
G03X133917Y194045I0J-200D01*
G01X133916Y194044D01*
G02X131942I-987J1131D01*
G01X131941D01*
Y194045D01*
G03X131811Y194093I-130J-152D01*
G01X131547D01*
G03X131417Y194045I0J-200D01*
G01X131416Y194044D01*
G02X129442I-987J1131D01*
G01X129441D01*
Y194045D01*
G03X129311Y194093I-130J-152D01*
G01X129047D01*
G03X128917Y194045I0J-200D01*
G01X128916Y194044D01*
G02X127929Y193674I-987J1131D01*
G02Y196678I0J1502D01*
G02X128916Y196308I0J-1501D01*
G01X128917D01*
Y196307D01*
G03X129047Y196259I130J152D01*
G01X129311D01*
G03X129441Y196307I0J200D01*
G01X129442Y196308D01*
G02X131416I987J-1131D01*
G01X131417D01*
Y196307D01*
G03X131547Y196259I130J152D01*
G01X131811D01*
G03X131941Y196307I0J200D01*
G01X131942Y196308D01*
G02X133916I987J-1131D01*
G37*
G36*
G01X90340Y207899D02*
X90341Y207898D01*
G03X90471Y207850I130J152D01*
G01X90735D01*
G03X90865Y207898I0J200D01*
G01X90866Y207899D01*
G02X91853Y208269I987J-1131D01*
G02Y205265I0J-1502D01*
G02X90866Y205635I0J1501D01*
G01X90865D01*
Y205636D01*
G03X90735Y205684I-130J-152D01*
G01X90471D01*
G03X90341Y205636I0J-200D01*
G01X90340Y205635D01*
G02X88366I-987J1131D01*
G01X88365D01*
Y205636D01*
G03X88235Y205684I-130J-152D01*
G01X87971D01*
G03X87841Y205636I0J-200D01*
G01X87840Y205635D01*
G02X86853Y205265I-987J1131D01*
G02Y208269I0J1502D01*
G02X87840Y207899I0J-1501D01*
G01X87841D01*
Y207898D01*
G03X87971Y207850I130J152D01*
G01X88235D01*
G03X88365Y207898I0J200D01*
G01X88366Y207899D01*
G02X90340I987J-1131D01*
G37*
G36*
G01X129783Y205304D02*
G02Y208308I0J1502D01*
G02X130770Y207938I0J-1501D01*
G01X130771D01*
Y207937D01*
G03X130901Y207889I130J152D01*
G01X131165D01*
G03X131295Y207937I0J200D01*
G01X131296Y207938D01*
G02X132283Y208308I987J-1131D01*
G02Y205304I0J-1502D01*
G02X131296Y205674I0J1501D01*
G01X131295D01*
Y205675D01*
G03X131165Y205723I-130J-152D01*
G01X130901D01*
G03X130771Y205675I0J-200D01*
G01X130770Y205674D01*
G02X129783Y205304I-987J1131D01*
G37*
G36*
G01X128010Y209007D02*
G02Y212011I0J1502D01*
G02X128997Y211641I0J-1501D01*
G01X128998D01*
Y211640D01*
G03X129128Y211592I130J152D01*
G01X129392D01*
G03X129522Y211640I0J200D01*
G01X129523Y211641D01*
G02X130510Y212011I987J-1131D01*
G02Y209007I0J-1502D01*
G02X129523Y209377I0J1501D01*
G01X129522D01*
Y209378D01*
G03X129392Y209426I-130J-152D01*
G01X129128D01*
G03X128998Y209378I0J-200D01*
G01X128997Y209377D01*
G02X128010Y209007I-987J1131D01*
G37*
G36*
G01X75317Y213859D02*
G02X78321I1502J0D01*
G02X77951Y212872I-1501J0D01*
G01Y212871D01*
X77950D01*
G03X77902Y212741I152J-130D01*
G01Y212477D01*
G03X77950Y212347I200J0D01*
G01X77951Y212346D01*
G02X78321Y211359I-1131J-987D01*
G02X75317I-1502J0D01*
G02X75687Y212346I1501J0D01*
G01Y212347D01*
X75688D01*
G03X75736Y212477I-152J130D01*
G01Y212741D01*
G03X75688Y212871I-200J0D01*
G01X75687Y212872D01*
G02X75317Y213859I1131J987D01*
G37*
G36*
G01X53231Y215478D02*
G02X56235I1502J0D01*
G02X55865Y214491I-1501J0D01*
G01Y214490D01*
X55864D01*
G03X55816Y214360I152J-130D01*
G01Y214096D01*
G03X55864Y213966I200J0D01*
G01X55865Y213965D01*
G02Y211991I-1131J-987D01*
G01Y211990D01*
X55864D01*
G03X55816Y211860I152J-130D01*
G01Y211596D01*
G03X55864Y211466I200J0D01*
G01X55865Y211465D01*
G02Y209491I-1131J-987D01*
G01Y209490D01*
X55864D01*
G03X55816Y209360I152J-130D01*
G01Y209096D01*
G03X55864Y208966I200J0D01*
G01X55865Y208965D01*
G02X56235Y207978I-1131J-987D01*
G02X53231I-1502J0D01*
G02X53601Y208965I1501J0D01*
G01Y208966D01*
X53602D01*
G03X53650Y209096I-152J130D01*
G01Y209360D01*
G03X53602Y209490I-200J0D01*
G01X53601Y209491D01*
G02Y211465I1131J987D01*
G01Y211466D01*
X53602D01*
G03X53650Y211596I-152J130D01*
G01Y211860D01*
G03X53602Y211990I-200J0D01*
G01X53601Y211991D01*
G02Y213965I1131J987D01*
G01Y213966D01*
X53602D01*
G03X53650Y214096I-152J130D01*
G01Y214360D01*
G03X53602Y214490I-200J0D01*
G01X53601Y214491D01*
G02X53231Y215478I1131J987D01*
G37*
G36*
G01X79020Y215632D02*
G02X82024I1502J0D01*
G02X81654Y214645I-1501J0D01*
G01Y214644D01*
X81653D01*
G03X81605Y214514I152J-130D01*
G01Y214250D01*
G03X81653Y214120I200J0D01*
G01X81654Y214119D01*
G02X82024Y213132I-1131J-987D01*
G02X79020I-1502J0D01*
G02X79390Y214119I1501J0D01*
G01Y214120D01*
X79391D01*
G03X79439Y214250I-152J130D01*
G01Y214514D01*
G03X79391Y214644I-200J0D01*
G01X79390Y214645D01*
G02X79020Y215632I1131J987D01*
G37*
G36*
G01X63687Y215713D02*
G02X66691I1502J0D01*
G02X66321Y214726I-1501J0D01*
G01Y214725D01*
X66320D01*
G03X66272Y214595I152J-130D01*
G01Y214331D01*
G03X66320Y214201I200J0D01*
G01X66321Y214200D01*
G02Y212226I-1131J-987D01*
G01Y212225D01*
X66320D01*
G03X66272Y212095I152J-130D01*
G01Y211831D01*
G03X66320Y211701I200J0D01*
G01X66321Y211700D01*
G02Y209726I-1131J-987D01*
G01Y209725D01*
X66320D01*
G03X66272Y209595I152J-130D01*
G01Y209331D01*
G03X66320Y209201I200J0D01*
G01X66321Y209200D01*
G02X66691Y208213I-1131J-987D01*
G02X63687I-1502J0D01*
G02X64057Y209200I1501J0D01*
G01Y209201D01*
X64058D01*
G03X64106Y209331I-152J130D01*
G01Y209595D01*
G03X64058Y209725I-200J0D01*
G01X64057Y209726D01*
G02Y211700I1131J987D01*
G01Y211701D01*
X64058D01*
G03X64106Y211831I-152J130D01*
G01Y212095D01*
G03X64058Y212225I-200J0D01*
G01X64057Y212226D01*
G02Y214200I1131J987D01*
G01Y214201D01*
X64058D01*
G03X64106Y214331I-152J130D01*
G01Y214595D01*
G03X64058Y214725I-200J0D01*
G01X64057Y214726D01*
G02X63687Y215713I1131J987D01*
G37*
G36*
G01X120432Y221970D02*
G02X123436I1502J0D01*
G02X123066Y220983I-1501J0D01*
G01Y220982D01*
X123065D01*
G03X123017Y220852I152J-130D01*
G01Y220588D01*
G03X123065Y220458I200J0D01*
G01X123066Y220457D01*
G02Y218483I-1131J-987D01*
G01Y218482D01*
X123065D01*
G03X123017Y218352I152J-130D01*
G01Y218088D01*
G03X123065Y217958I200J0D01*
G01X123066Y217957D01*
G02X123436Y216970I-1131J-987D01*
G02X121934Y215468I-1502J0D01*
G02X121079Y215735I0J1502D01*
G01X121045Y215758D01*
X120964Y215775D01*
X120597Y215695D01*
X120530Y215647D01*
X120509Y215612D01*
G02X119221Y214883I-1288J773D01*
G02Y217887I0J1502D01*
G02X120076Y217620I0J-1502D01*
G01X120110Y217597D01*
X120191Y217580D01*
X120558Y217660D01*
X120625Y217708D01*
X120646Y217743D01*
G02X120802Y217956I1285J-777D01*
G03X120803Y217958I-173J88D01*
G03X120851Y218088I-152J130D01*
G01Y218352D01*
G03X120803Y218482I-200J0D01*
G01X120802Y218483D01*
G02Y220457I1131J987D01*
G01Y220458D01*
X120803D01*
G03X120851Y220588I-152J130D01*
G01Y220852D01*
G03X120803Y220982I-200J0D01*
G01X120802Y220983D01*
G02X120432Y221970I1131J987D01*
G37*
G36*
G01X84896Y224421D02*
G02X87900I1502J0D01*
G02X87633Y223566I-1502J0D01*
G01X87610Y223532D01*
X87593Y223451D01*
X87673Y223084D01*
X87721Y223017D01*
X87756Y222996D01*
G02X87969Y222840I-777J-1285D01*
G03X87971Y222839I88J173D01*
G03X88101Y222791I130J152D01*
G01X88365D01*
G03X88495Y222839I0J200D01*
G01X88496Y222840D01*
G02X90470I987J-1131D01*
G01X90471D01*
Y222839D01*
G03X90601Y222791I130J152D01*
G01X90865D01*
G03X90995Y222839I0J200D01*
G01X90996Y222840D01*
G02X91983Y223210I987J-1131D01*
G02Y220206I0J-1502D01*
G02X90996Y220576I0J1501D01*
G01X90995D01*
Y220577D01*
G03X90865Y220625I-130J-152D01*
G01X90601D01*
G03X90471Y220577I0J-200D01*
G01X90470Y220576D01*
G02X88496I-987J1131D01*
G01X88495D01*
Y220577D01*
G03X88365Y220625I-130J-152D01*
G01X88101D01*
G03X87971Y220577I0J-200D01*
G01X87970Y220576D01*
G02X86983Y220206I-987J1131D01*
G02X85481Y221708I0J1502D01*
G02X85748Y222563I1502J0D01*
G01X85771Y222597D01*
X85788Y222678D01*
X85708Y223045D01*
X85660Y223112D01*
X85625Y223133D01*
G02X84896Y224421I773J1288D01*
G37*
G36*
G01X87146Y229474D02*
Y229768D01*
G03X87081Y229915I-200J-1D01*
G02X86596Y231021I1019J1106D01*
G02X89600I1502J0D01*
G02X89115Y229915I-1504J0D01*
G03X89050Y229768I135J-148D01*
G01Y229474D01*
G03X89115Y229327I200J1D01*
G02X89600Y228221I-1019J-1106D01*
G02X86596I-1502J0D01*
G02X87081Y229327I1504J0D01*
G03X87146Y229474I-135J148D01*
G37*
G36*
G01X92136Y237321D02*
X92137Y237320D01*
G03X92267Y237272I130J152D01*
G01X92531D01*
G03X92661Y237320I0J200D01*
G01X92662Y237321D01*
G02X93649Y237691I987J-1131D01*
G02Y234687I0J-1502D01*
G02X92662Y235057I0J1501D01*
G01X92661D01*
Y235058D01*
G03X92531Y235106I-130J-152D01*
G01X92267D01*
G03X92137Y235058I0J-200D01*
G01X92136Y235057D01*
G02X90162I-987J1131D01*
G01X90161D01*
Y235058D01*
G03X90031Y235106I-130J-152D01*
G01X89767D01*
G03X89637Y235058I0J-200D01*
G01X89636Y235057D01*
G02X88649Y234687I-987J1131D01*
G02Y237691I0J1502D01*
G02X89636Y237321I0J-1501D01*
G01X89637D01*
Y237320D01*
G03X89767Y237272I130J152D01*
G01X90031D01*
G03X90161Y237320I0J200D01*
G01X90162Y237321D01*
G02X92136I987J-1131D01*
G37*
G36*
G01X92077Y249897D02*
X92078Y249896D01*
G03X92208Y249848I130J152D01*
G01X92472D01*
G03X92602Y249896I0J200D01*
G01X92603Y249897D01*
G02X93590Y250267I987J-1131D01*
G02Y247263I0J-1502D01*
G02X92603Y247633I0J1501D01*
G01X92602D01*
Y247634D01*
G03X92472Y247682I-130J-152D01*
G01X92208D01*
G03X92078Y247634I0J-200D01*
G01X92077Y247633D01*
G02X90103I-987J1131D01*
G01X90102D01*
Y247634D01*
G03X89972Y247682I-130J-152D01*
G01X89708D01*
G03X89578Y247634I0J-200D01*
G01X89577Y247633D01*
G02X88590Y247263I-987J1131D01*
G02Y250267I0J1502D01*
G02X89577Y249897I0J-1501D01*
G01X89578D01*
Y249896D01*
G03X89708Y249848I130J152D01*
G01X89972D01*
G03X90102Y249896I0J200D01*
G01X90103Y249897D01*
G02X92077I987J-1131D01*
G37*
G36*
G01X58062Y262678D02*
G02Y265682I0J1502D01*
G02X59049Y265312I0J-1501D01*
G01X59050D01*
Y265311D01*
G03X59180Y265263I130J152D01*
G01X59444D01*
G03X59574Y265311I0J200D01*
G01X59575Y265312D01*
G02X60562Y265682I987J-1131D01*
G02Y262678I0J-1502D01*
G02X59575Y263048I0J1501D01*
G01X59574D01*
Y263049D01*
G03X59444Y263097I-130J-152D01*
G01X59180D01*
G03X59050Y263049I0J-200D01*
G01X59049Y263048D01*
G02X58062Y262678I-987J1131D01*
G37*
G36*
G01X97747Y264395D02*
G02Y267399I0J1502D01*
G02X98734Y267029I0J-1501D01*
G01X98735D01*
Y267028D01*
G03X98865Y266980I130J152D01*
G01X99129D01*
G03X99259Y267028I0J200D01*
G01X99260Y267029D01*
G02X100247Y267399I987J-1131D01*
G02Y264395I0J-1502D01*
G02X99260Y264765I0J1501D01*
G01X99259D01*
Y264766D01*
G03X99129Y264814I-130J-152D01*
G01X98865D01*
G03X98735Y264766I0J-200D01*
G01X98734Y264765D01*
G02X97747Y264395I-987J1131D01*
G37*
G36*
G01X68209Y270978D02*
X68503D01*
G03X68650Y271043I-1J200D01*
G02X69756Y271528I1106J-1019D01*
G02X70743Y271158I0J-1501D01*
G01X70744D01*
Y271157D01*
G03X70874Y271109I130J152D01*
G01X71138D01*
G03X71268Y271157I0J200D01*
G01X71269Y271158D01*
G02X72256Y271528I987J-1131D01*
G02X73758Y270026I0J-1502D01*
G02X73388Y269039I-1501J0D01*
G01Y269038D01*
X73387D01*
G03X73339Y268908I152J-130D01*
G01Y268644D01*
G03X73387Y268514I200J0D01*
G01X73388Y268513D01*
G02X73758Y267526I-1131J-987D01*
G02X72256Y266024I-1502J0D01*
G02X71269Y266394I0J1501D01*
G01X71268D01*
Y266395D01*
G03X71138Y266443I-130J-152D01*
G01X70874D01*
G03X70744Y266395I0J-200D01*
G01X70743Y266394D01*
G02X69756Y266024I-987J1131D01*
G02X68650Y266509I0J1504D01*
G03X68503Y266574I-148J-135D01*
G01X68209D01*
G03X68062Y266509I1J-200D01*
G02X66956Y266024I-1106J1019D01*
G02X65454Y267526I0J1502D01*
G02X65824Y268513I1501J0D01*
G01Y268514D01*
X65825D01*
G03X65873Y268644I-152J130D01*
G01Y268908D01*
G03X65825Y269038I-200J0D01*
G01X65824Y269039D01*
G02X65454Y270026I1131J987D01*
G02X66956Y271528I1502J0D01*
G02X68062Y271043I0J-1504D01*
G03X68209Y270978I148J135D01*
G37*
G36*
G01X91287Y272197D02*
G02X92393Y271712I0J-1504D01*
G03X92540Y271647I148J135D01*
G01X92834D01*
G03X92981Y271712I-1J200D01*
G02X94087Y272197I1106J-1019D01*
G02X95589Y270695I0J-1502D01*
G02X95219Y269708I-1501J0D01*
G01Y269707D01*
X95218D01*
G03X95170Y269577I152J-130D01*
G01Y269313D01*
G03X95218Y269183I200J0D01*
G01X95219Y269182D01*
G02X95589Y268195I-1131J-987D01*
G02X94087Y266693I-1502J0D01*
G02X92981Y267178I0J1504D01*
G03X92834Y267243I-148J-135D01*
G01X92540D01*
G03X92393Y267178I1J-200D01*
G02X91287Y266693I-1106J1019D01*
G02X90300Y267063I0J1501D01*
G01X90299D01*
Y267064D01*
G03X90169Y267112I-130J-152D01*
G01X89905D01*
G03X89775Y267064I0J-200D01*
G01X89774Y267063D01*
G02X88787Y266693I-987J1131D01*
G02X87285Y268195I0J1502D01*
G02X87655Y269182I1501J0D01*
G01Y269183D01*
X87656D01*
G03X87704Y269313I-152J130D01*
G01Y269577D01*
G03X87656Y269707I-200J0D01*
G01X87655Y269708D01*
G02X87285Y270695I1131J987D01*
G02X88787Y272197I1502J0D01*
G02X89774Y271827I0J-1501D01*
G01X89775D01*
Y271826D01*
G03X89905Y271778I130J152D01*
G01X90169D01*
G03X90299Y271826I0J200D01*
G01X90300Y271827D01*
G02X91287Y272197I987J-1131D01*
G37*
G36*
G01X96105Y151610D02*
G02X94811Y150871I-1294J763D01*
G02Y153875I0J1502D01*
G02X96005Y153285I0J-1503D01*
G03X96667Y153325I318J243D01*
G02X97961Y154064I1294J-763D01*
G02Y151060I0J-1502D01*
G02X96767Y151650I0J1503D01*
G03X96105Y151610I-318J-243D01*
G37*
G36*
G01X71281Y184221D02*
G02X72783Y185723I1502J0D01*
G02X73903Y185222I0J-1502D01*
G01X73928Y185193D01*
X73998Y185159D01*
X74312Y185134D01*
G03X74453Y185178I15J199D01*
G02X75400Y185514I947J-1167D01*
G02X76902Y184012I0J-1502D01*
G02X76609Y183121I-1501J0D01*
G01Y183120D01*
X76586Y183089D01*
X76567Y183013D01*
X76619Y182657D01*
X76660Y182588D01*
X76691Y182565D01*
G02X77017Y182226I-906J-1198D01*
G03X77156Y182142I164J114D01*
G01X77492Y182099D01*
X77573Y182123D01*
X77605Y182151D01*
G02X78581Y182511I976J-1143D01*
G02Y179507I0J-1502D01*
G02X77350Y180149I0J1501D01*
G03X77211Y180233I-164J-114D01*
G01X76875Y180276D01*
X76794Y180252D01*
X76762Y180224D01*
G02X75786Y179864I-976J1143D01*
G02X74503Y180585I0J1502D01*
G01X74476Y180629D01*
X74388Y180680D01*
X73946Y180688D01*
X73856Y180641D01*
X73828Y180598D01*
G02X72575Y179924I-1253J828D01*
G02X71073Y181426I0J1502D01*
G02X71644Y182605I1503J0D01*
G01X71677Y182631D01*
X71716Y182705D01*
X71745Y183084D01*
X71717Y183162D01*
X71688Y183193D01*
G02X71281Y184221I1095J1028D01*
G37*
G36*
G01X130445Y201748D02*
G02X131947Y203250I1502J0D01*
G02X133040Y202778I0J-1502D01*
G01X133041Y202777D01*
G03X133206Y202716I145J138D01*
G01X133521Y202747D01*
G03X133671Y202841I-20J199D01*
G02X134947Y203550I1276J-794D01*
G02X136449Y202048I0J-1502D01*
G02X135964Y200942I-1504J0D01*
G03X135899Y200795I135J-148D01*
G01Y200501D01*
G03X135964Y200354I200J1D01*
G02X136449Y199248I-1019J-1106D01*
G02X134947Y197746I-1502J0D01*
G02X133762Y198325I0J1502D01*
G03X133604Y198402I-158J-123D01*
G01X133290D01*
G03X133132Y198325I0J-200D01*
G02X131947Y197746I-1185J923D01*
G02X130445Y199248I0J1502D01*
G02X130815Y200235I1501J0D01*
G01Y200236D01*
X130816D01*
G03X130864Y200366I-152J130D01*
G01Y200630D01*
G03X130816Y200760I-200J0D01*
G01X130815Y200761D01*
G02X130445Y201748I1131J987D01*
G37*
G36*
G01X71761Y213197D02*
G02X73263Y211695I0J-1502D01*
G02X72791Y210602I-1502J0D01*
G01X72790Y210601D01*
G03X72729Y210436I138J-145D01*
G01X72760Y210121D01*
G03X72854Y209971I199J20D01*
G02X73563Y208695I-794J-1276D01*
G02X72061Y207193I-1502J0D01*
G02X70955Y207678I0J1504D01*
G03X70808Y207743I-148J-135D01*
G01X70514D01*
G03X70367Y207678I1J-200D01*
G02X69261Y207193I-1106J1019D01*
G02X67759Y208695I0J1502D01*
G02X68338Y209880I1502J0D01*
G03X68415Y210038I-123J158D01*
G01Y210352D01*
G03X68338Y210510I-200J0D01*
G02X67759Y211695I923J1185D01*
G02X69261Y213197I1502J0D01*
G02X70248Y212827I0J-1501D01*
G01X70249D01*
Y212826D01*
G03X70379Y212778I130J152D01*
G01X70643D01*
G03X70773Y212826I0J200D01*
G01X70774Y212827D01*
G02X71761Y213197I987J-1131D01*
G37*
G36*
G01X56722Y465004D02*
G02X59726I1502J0D01*
G02X58367Y463509I-1502J0D01*
G03X58213Y463411I19J-199D01*
G01X58050Y463131D01*
G03X58040Y462948I173J-101D01*
G02X58169Y462339I-1373J-609D01*
G02X57799Y461352I-1501J0D01*
G01Y461351D01*
X57798D01*
G03X57750Y461221I152J-130D01*
G01Y460957D01*
G03X57798Y460827I200J0D01*
G01X57799Y460826D01*
G02Y458852I-1131J-987D01*
G01Y458851D01*
X57798D01*
G03X57750Y458721I152J-130D01*
G01Y458457D01*
G03X57798Y458327I200J0D01*
G01X57799Y458326D01*
G02X58169Y457339I-1131J-987D01*
G02X56667Y455837I-1502J0D01*
G02X55680Y456207I0J1501D01*
G01X55679D01*
Y456208D01*
G03X55549Y456256I-130J-152D01*
G01X55285D01*
G03X55155Y456208I0J-200D01*
G01X55154Y456207D01*
G02X54167Y455837I-987J1131D01*
G02X52665Y457339I0J1502D01*
G02X53035Y458326I1501J0D01*
G01Y458327D01*
X53036D01*
G03X53084Y458457I-152J130D01*
G01Y458721D01*
G03X53036Y458851I-200J0D01*
G01X53035Y458852D01*
G02Y460826I1131J987D01*
G01Y460827D01*
X53036D01*
G03X53084Y460957I-152J130D01*
G01Y461221D01*
G03X53036Y461351I-200J0D01*
G01X53035Y461352D01*
G02X52665Y462339I1131J987D01*
G02X54167Y463841I1502J0D01*
G02X55154Y463471I0J-1501D01*
G01X55155D01*
Y463470D01*
G03X55285Y463422I130J152D01*
G01X55549D01*
G03X55679Y463470I0J200D01*
G01X55680Y463471D01*
G02X56524Y463834I987J-1132D01*
G03X56678Y463932I-19J199D01*
G01X56841Y464212D01*
G03X56851Y464395I-173J101D01*
G02X56722Y465004I1373J609D01*
G37*
G36*
G01X38358Y530446D02*
G02Y533450I0J1502D01*
G02X39582Y532819I0J-1503D01*
G01X39609Y532780D01*
X39693Y532736D01*
X40061Y532728D01*
G03X40223Y532805I4J200D01*
G02X41408Y533384I1185J-923D01*
G02X42395Y533014I0J-1501D01*
G01X42396D01*
Y533013D01*
G03X42526Y532965I130J152D01*
G01X42790D01*
G03X42920Y533013I0J200D01*
G01X42921Y533014D01*
G02X44895I987J-1131D01*
G01X44896D01*
Y533013D01*
G03X45026Y532965I130J152D01*
G01X45290D01*
G03X45420Y533013I0J200D01*
G01X45421Y533014D01*
G02X46408Y533384I987J-1131D01*
G02X47910Y531882I0J-1502D01*
G02X47643Y531027I-1502J0D01*
G01X47620Y530993D01*
X47603Y530912D01*
X47683Y530545D01*
X47731Y530478D01*
X47766Y530457D01*
G02X48495Y529169I-773J-1288D01*
G02X45491I-1502J0D01*
G02X45758Y530024I1502J0D01*
G01X45781Y530058D01*
X45798Y530139D01*
X45718Y530506D01*
X45670Y530573D01*
X45635Y530594D01*
G02X45422Y530750I777J1285D01*
G03X45420Y530751I-88J-173D01*
G03X45290Y530799I-130J-152D01*
G01X45026D01*
G03X44896Y530751I0J-200D01*
G01X44895Y530750D01*
G02X42921I-987J1131D01*
G01X42920D01*
Y530751D01*
G03X42790Y530799I-130J-152D01*
G01X42526D01*
G03X42396Y530751I0J-200D01*
G01X42395Y530750D01*
G02X41408Y530380I-987J1131D01*
G02X40184Y531011I0J1503D01*
G01X40157Y531050D01*
X40073Y531094D01*
X39705Y531102D01*
G03X39543Y531025I-4J-200D01*
G02X38358Y530446I-1185J923D01*
G37*
G36*
G01X62583Y545847D02*
X62877D01*
G03X63024Y545912I-1J200D01*
G02X64130Y546397I1106J-1019D01*
G02X65632Y544895I0J-1502D01*
G02X65053Y543710I-1502J0D01*
G03X64976Y543552I123J-158D01*
G01Y543238D01*
G03X65053Y543080I200J0D01*
G02X65632Y541895I-923J-1185D01*
G02X64130Y540393I-1502J0D01*
G02X63143Y540763I0J1501D01*
G01X63142D01*
Y540764D01*
G03X63012Y540812I-130J-152D01*
G01X62748D01*
G03X62618Y540764I0J-200D01*
G01X62617Y540763D01*
G02X61630Y540393I-987J1131D01*
G02X60128Y541895I0J1502D01*
G02X60600Y542988I1502J0D01*
G01X60601Y542989D01*
G03X60662Y543154I-138J145D01*
G01X60631Y543469D01*
G03X60537Y543619I-199J-20D01*
G02X59828Y544895I794J1276D01*
G02X61330Y546397I1502J0D01*
G02X62436Y545912I0J-1504D01*
G03X62583Y545847I148J135D01*
G37*
G36*
G01X73838Y576484D02*
G02X76842I1502J0D01*
G02X76200Y575253I-1501J0D01*
G03X76116Y575114I114J-164D01*
G01X76073Y574778D01*
X76097Y574697D01*
X76125Y574665D01*
G02X76485Y573689I-1143J-976D01*
G02X75764Y572406I-1502J0D01*
G01X75720Y572379D01*
X75669Y572291D01*
X75661Y571849D01*
X75708Y571759D01*
X75751Y571731D01*
G02X76425Y570478I-828J-1253D01*
G02X74923Y568976I-1502J0D01*
G02X73744Y569547I0J1503D01*
G01X73718Y569580D01*
X73644Y569619D01*
X73265Y569648D01*
X73187Y569620D01*
X73156Y569591D01*
G02X72128Y569184I-1028J1095D01*
G02X70626Y570686I0J1502D01*
G02X71127Y571806I1502J0D01*
G01X71156Y571831D01*
X71190Y571901D01*
X71215Y572215D01*
G03X71171Y572356I-199J15D01*
G02X70835Y573303I1167J947D01*
G02X72337Y574805I1502J0D01*
G02X73228Y574512I0J-1501D01*
G01X73229D01*
X73260Y574489D01*
X73336Y574470D01*
X73692Y574522D01*
X73761Y574563D01*
X73784Y574594D01*
G02X74123Y574920I1198J-906D01*
G03X74207Y575059I-114J164D01*
G01X74250Y575395D01*
X74226Y575476D01*
X74198Y575508D01*
G02X73838Y576484I1143J976D01*
G37*
G36*
G01X43924Y619590D02*
G02X43362Y620661I739J1071D01*
G02X45966I1302J0D01*
G02X45404Y619590I-1301J0D01*
G03Y618932I228J-329D01*
G02X45966Y617861I-739J-1071D01*
G02X43362I-1302J0D01*
G02X43924Y618932I1301J0D01*
G03Y619590I-228J329D01*
G37*
G36*
G01X47467D02*
G02X46905Y620661I739J1071D01*
G02X49509I1302J0D01*
G02X48947Y619590I-1301J0D01*
G03Y618932I228J-329D01*
G02X49509Y617861I-739J-1071D01*
G02X46905I-1302J0D01*
G02X47467Y618932I1301J0D01*
G03Y619590I-228J329D01*
G37*
G36*
G01X51010D02*
G02X50448Y620661I739J1071D01*
G02X53052I1302J0D01*
G02X52490Y619590I-1301J0D01*
G03Y618932I228J-329D01*
G02X53052Y617861I-739J-1071D01*
G02X50448I-1302J0D01*
G02X51010Y618932I1301J0D01*
G03Y619590I-228J329D01*
G37*
G36*
G01X54554D02*
G02X53992Y620661I739J1071D01*
G02X56596I1302J0D01*
G02X56034Y619590I-1301J0D01*
G03Y618932I228J-329D01*
G02X56596Y617861I-739J-1071D01*
G02X53992I-1302J0D01*
G02X54554Y618932I1301J0D01*
G03Y619590I-228J329D01*
G37*
G36*
G01X49249Y839220D02*
G02X50473Y838588I0J-1501D01*
G03X50636Y838504I163J116D01*
G01X50962D01*
G03X51125Y838588I0J200D01*
G02X52349Y839220I1224J-869D01*
G02Y836216I0J-1502D01*
G02X51125Y836848I0J1501D01*
G03X50962Y836932I-163J-116D01*
G01X50636D01*
G03X50473Y836848I0J-200D01*
G02X49249Y836216I-1224J869D01*
G02X47986Y836906I0J1501D01*
G03X47817Y836998I-168J-108D01*
G01X47481D01*
G03X47312Y836906I-1J-200D01*
G02X46049Y836216I-1263J811D01*
G02Y839220I0J1502D01*
G02X47312Y838530I0J-1501D01*
G03X47481Y838438I168J108D01*
G01X47817D01*
G03X47986Y838530I1J200D01*
G02X49249Y839220I1263J-811D01*
G37*
G36*
G01X73397Y823171D02*
Y823465D01*
G03X73332Y823612I-200J-1D01*
G02X72847Y824718I1019J1106D01*
G02X75851I1502J0D01*
G02X75366Y823612I-1504J0D01*
G03X75301Y823465I135J-148D01*
G01Y823171D01*
G03X75366Y823024I200J1D01*
G02X75851Y821918I-1019J-1106D01*
G02X72847I-1502J0D01*
G02X73332Y823024I1504J0D01*
G03X73397Y823171I-135J148D01*
G37*
G36*
G01X35818Y700034D02*
X36112D01*
G03X36259Y700099I-1J200D01*
G02X38471I1106J-1017D01*
G03X38618Y700034I148J135D01*
G01X38912D01*
G03X39059Y700099I-1J200D01*
G02X40165Y700584I1106J-1019D01*
G02Y697580I0J-1502D01*
G02X39059Y698065I0J1504D01*
G03X38912Y698130I-148J-135D01*
G01X38618D01*
G03X38471Y698065I1J-200D01*
G02X36259I-1106J1017D01*
G03X36112Y698130I-148J-135D01*
G01X35818D01*
G03X35671Y698065I1J-200D01*
G02X34565Y697580I-1106J1019D01*
G02Y700584I0J1502D01*
G02X35671Y700099I0J-1504D01*
G03X35818Y700034I148J135D01*
G37*
G36*
G01X36910Y680606D02*
G02Y683610I0J1502D01*
G02X37952Y683190I0J-1503D01*
G01X37981Y683162D01*
X38051Y683134D01*
X38408D01*
X38478Y683162D01*
X38507Y683190D01*
G02X39549Y683610I1042J-1083D01*
G02Y680606I0J-1502D01*
G02X38507Y681026I0J1503D01*
G01X38478Y681054D01*
X38408Y681082D01*
X38051D01*
X37981Y681054D01*
X37952Y681026D01*
G02X36910Y680606I-1042J1083D01*
G37*
G36*
G01X35250Y670006D02*
G02Y673010I0J1502D01*
G02X36258Y672621I-1J-1502D01*
G01X36259Y672620D01*
G03X36393Y672569I133J149D01*
G01X36661D01*
G03X36795Y672620I1J200D01*
G01X36796Y672621D01*
G02X37804Y673010I1009J-1113D01*
G02Y670006I0J-1502D01*
G02X36796Y670395I1J1502D01*
G01X36795Y670396D01*
G03X36661Y670447I-133J-149D01*
G01X36393D01*
G03X36259Y670396I-1J-200D01*
G01X36258Y670395D01*
G02X35250Y670006I-1009J1113D01*
G37*
G36*
G01X35293Y661450D02*
G02Y664454I0J1502D01*
G02X36320Y664048I0J-1502D01*
G01X36347Y664023D01*
X36415Y663995D01*
X36723Y663990D01*
G03X36857Y664039I3J200D01*
G02X37847Y664412I991J-1129D01*
G02Y661408I0J-1502D01*
G02X36820Y661814I0J1502D01*
G01X36793Y661839D01*
X36725Y661867D01*
X36417Y661872D01*
G03X36283Y661823I-3J-200D01*
G02X35293Y661450I-991J1129D01*
G37*
G36*
G01X60902Y619106D02*
Y619400D01*
G03X60837Y619547I-200J-1D01*
G02X60352Y620653I1019J1106D01*
G02X63356I1502J0D01*
G02X62871Y619547I-1504J0D01*
G03X62806Y619400I135J-148D01*
G01Y619106D01*
G03X62871Y618959I200J1D01*
G02X63356Y617853I-1019J-1106D01*
G02X60352I-1502J0D01*
G02X60837Y618959I1504J0D01*
G03X60902Y619106I-135J148D01*
G37*
G36*
G01X80788Y618211D02*
Y618505D01*
G03X80723Y618652I-200J-1D01*
G02X80238Y619758I1019J1106D01*
G02X83242I1502J0D01*
G02X82757Y618652I-1504J0D01*
G03X82692Y618505I135J-148D01*
G01Y618211D01*
G03X82757Y618064I200J1D01*
G02Y615852I-1017J-1106D01*
G03X82692Y615705I135J-148D01*
G01Y615411D01*
G03X82757Y615264I200J1D01*
G02X83242Y614158I-1019J-1106D01*
G02X80238I-1502J0D01*
G02X80723Y615264I1504J0D01*
G03X80788Y615411I-135J148D01*
G01Y615705D01*
G03X80723Y615852I-200J-1D01*
G02Y618064I1017J1106D01*
G03X80788Y618211I-135J148D01*
G37*
G36*
G01X68718Y617966D02*
Y618260D01*
G03X68653Y618407I-200J-1D01*
G02X68168Y619513I1019J1106D01*
G02X71172I1502J0D01*
G02X70687Y618407I-1504J0D01*
G03X70622Y618260I135J-148D01*
G01Y617966D01*
G03X70687Y617819I200J1D01*
G02Y615607I-1017J-1106D01*
G03X70622Y615460I135J-148D01*
G01Y615166D01*
G03X70687Y615019I200J1D01*
G02X71172Y613913I-1019J-1106D01*
G02X68168I-1502J0D01*
G02X68653Y615019I1504J0D01*
G03X68718Y615166I-135J148D01*
G01Y615460D01*
G03X68653Y615607I-200J-1D01*
G02Y617819I1017J1106D01*
G03X68718Y617966I-135J148D01*
G37*
G36*
G01X49625Y611514D02*
X49919D01*
G03X50066Y611579I-1J200D01*
G02X52278I1106J-1017D01*
G03X52425Y611514I148J135D01*
G01X52719D01*
G03X52866Y611579I-1J200D01*
G02X53972Y612064I1106J-1019D01*
G02X55474Y610562I0J-1502D01*
G02X54989Y609456I-1504J0D01*
G03X54924Y609309I135J-148D01*
G01Y609015D01*
G03X54989Y608868I200J1D01*
G02X55474Y607762I-1019J-1106D01*
G02X53972Y606260I-1502J0D01*
G02X52866Y606745I0J1504D01*
G03X52719Y606810I-148J-135D01*
G01X52425D01*
G03X52278Y606745I1J-200D01*
G02X50066I-1106J1017D01*
G03X49919Y606810I-148J-135D01*
G01X49625D01*
G03X49478Y606745I1J-200D01*
G02X47266I-1106J1017D01*
G03X47119Y606810I-148J-135D01*
G01X46825D01*
G03X46678Y606745I1J-200D01*
G02X45572Y606260I-1106J1019D01*
G02X44070Y607762I0J1502D01*
G02X44555Y608868I1504J0D01*
G03X44620Y609015I-135J148D01*
G01Y609309D01*
G03X44555Y609456I-200J-1D01*
G02X44070Y610562I1019J1106D01*
G02X45572Y612064I1502J0D01*
G02X46678Y611579I0J-1504D01*
G03X46825Y611514I148J135D01*
G01X47119D01*
G03X47266Y611579I-1J200D01*
G02X49478I1106J-1017D01*
G03X49625Y611514I148J135D01*
G37*
G36*
G01X46653Y592167D02*
X46947D01*
G03X47094Y592232I-1J200D01*
G02X49306I1106J-1017D01*
G03X49453Y592167I148J135D01*
G01X49747D01*
G03X49894Y592232I-1J200D01*
G02X51000Y592717I1106J-1019D01*
G02Y589713I0J-1502D01*
G02X49894Y590198I0J1504D01*
G03X49747Y590263I-148J-135D01*
G01X49453D01*
G03X49306Y590198I1J-200D01*
G02X47094I-1106J1017D01*
G03X46947Y590263I-148J-135D01*
G01X46653D01*
G03X46506Y590198I1J-200D01*
G02X45400Y589713I-1106J1019D01*
G02Y592717I0J1502D01*
G02X46506Y592232I0J-1504D01*
G03X46653Y592167I148J135D01*
G37*
G36*
G01Y582174D02*
X46947D01*
G03X47094Y582239I-1J200D01*
G02X49306I1106J-1017D01*
G03X49453Y582174I148J135D01*
G01X49747D01*
G03X49894Y582239I-1J200D01*
G02X51000Y582724I1106J-1019D01*
G02Y579720I0J-1502D01*
G02X49894Y580205I0J1504D01*
G03X49747Y580270I-148J-135D01*
G01X49453D01*
G03X49306Y580205I1J-200D01*
G02X47094I-1106J1017D01*
G03X46947Y580270I-148J-135D01*
G01X46653D01*
G03X46506Y580205I1J-200D01*
G02X45400Y579720I-1106J1019D01*
G02Y582724I0J1502D01*
G02X46506Y582239I0J-1504D01*
G03X46653Y582174I148J135D01*
G37*
G36*
G01X45390Y570242D02*
X45096D01*
G03X44949Y570177I1J-200D01*
G02X43843Y569692I-1106J1019D01*
G02Y572696I0J1502D01*
G02X44949Y572211I0J-1504D01*
G03X45096Y572146I148J135D01*
G01X45390D01*
G03X45537Y572211I-1J200D01*
G02X46643Y572696I1106J-1019D01*
G02Y569692I0J-1502D01*
G02X45537Y570177I0J1504D01*
G03X45390Y570242I-148J-135D01*
G37*
G36*
G01X77232Y564994D02*
Y565300D01*
G03X77161Y565452I-200J-1D01*
G02X76631Y566597I972J1145D01*
G02X79635I1502J0D01*
G02X79105Y565452I-1502J0D01*
G03X79034Y565300I129J-153D01*
G01Y564994D01*
G03X79105Y564842I200J1D01*
G02X79635Y563697I-972J-1145D01*
G02X79229Y562670I-1502J0D01*
G01X79203Y562643D01*
X79175Y562572D01*
Y562222D01*
X79203Y562151D01*
X79229Y562124D01*
G02Y560070I-1096J-1027D01*
G01X79203Y560043D01*
X79175Y559972D01*
Y559622D01*
X79203Y559551D01*
X79229Y559524D01*
G02Y557470I-1096J-1027D01*
G01X79203Y557443D01*
X79175Y557372D01*
Y557022D01*
X79203Y556951D01*
X79229Y556924D01*
G02Y554870I-1096J-1027D01*
G01X79203Y554843D01*
X79175Y554772D01*
Y554422D01*
X79203Y554351D01*
X79229Y554324D01*
G02X79635Y553297I-1096J-1027D01*
G02X76631I-1502J0D01*
G02X77037Y554324I1502J0D01*
G01X77063Y554351D01*
X77091Y554422D01*
Y554772D01*
X77063Y554843D01*
X77037Y554870D01*
G02Y556924I1096J1027D01*
G01X77063Y556951D01*
X77091Y557022D01*
Y557372D01*
X77063Y557443D01*
X77037Y557470D01*
G02Y559524I1096J1027D01*
G01X77063Y559551D01*
X77091Y559622D01*
Y559972D01*
X77063Y560043D01*
X77037Y560070D01*
G02Y562124I1096J1027D01*
G01X77063Y562151D01*
X77091Y562222D01*
Y562572D01*
X77063Y562643D01*
X77037Y562670D01*
G02X76631Y563697I1096J1027D01*
G02X77161Y564842I1502J0D01*
G03X77232Y564994I-129J153D01*
G37*
G36*
G01X45390Y562242D02*
X45096D01*
G03X44949Y562177I1J-200D01*
G02X43843Y561692I-1106J1019D01*
G02Y564696I0J1502D01*
G02X44949Y564211I0J-1504D01*
G03X45096Y564146I148J135D01*
G01X45390D01*
G03X45537Y564211I-1J200D01*
G02X46643Y564696I1106J-1019D01*
G02Y561692I0J-1502D01*
G02X45537Y562177I0J1504D01*
G03X45390Y562242I-148J-135D01*
G37*
G36*
G01Y554242D02*
X45096D01*
G03X44949Y554177I1J-200D01*
G02X43843Y553692I-1106J1019D01*
G02Y556696I0J1502D01*
G02X44949Y556211I0J-1504D01*
G03X45096Y556146I148J135D01*
G01X45390D01*
G03X45537Y556211I-1J200D01*
G02X46643Y556696I1106J-1019D01*
G02Y553692I0J-1502D01*
G02X45537Y554177I0J1504D01*
G03X45390Y554242I-148J-135D01*
G37*
G36*
G01X74175Y549490D02*
X74176Y549489D01*
G03X74306Y549441I130J152D01*
G01X74570D01*
G03X74700Y549489I0J200D01*
G01X74701Y549490D01*
G02X75688Y549860I987J-1131D01*
G02Y546856I0J-1502D01*
G02X74701Y547226I0J1501D01*
G01X74700D01*
Y547227D01*
G03X74570Y547275I-130J-152D01*
G01X74306D01*
G03X74176Y547227I0J-200D01*
G01X74175Y547226D01*
G02X72201I-987J1131D01*
G01X72200D01*
Y547227D01*
G03X72070Y547275I-130J-152D01*
G01X71806D01*
G03X71676Y547227I0J-200D01*
G01X71675Y547226D01*
G02X69701I-987J1131D01*
G01X69700D01*
Y547227D01*
G03X69570Y547275I-130J-152D01*
G01X69306D01*
G03X69176Y547227I0J-200D01*
G01X69175Y547226D01*
G02X69127Y547185I-999J1121D01*
G01X69091Y547157D01*
X69051Y547074D01*
X69053Y546714D01*
G03X69129Y546558I200J1D01*
G02X69704Y545377I-927J-1182D01*
G02X69334Y544390I-1501J0D01*
G01Y544389D01*
X69333D01*
G03X69285Y544259I152J-130D01*
G01Y543995D01*
G03X69333Y543865I200J0D01*
G01X69334Y543864D01*
G02Y541890I-1131J-987D01*
G01Y541889D01*
X69333D01*
G03X69285Y541759I152J-130D01*
G01Y541495D01*
G03X69333Y541365I200J0D01*
G01X69334Y541364D01*
G02Y539390I-1131J-987D01*
G01Y539389D01*
X69333D01*
G03X69285Y539259I152J-130D01*
G01Y538995D01*
G03X69333Y538865I200J0D01*
G01X69334Y538864D01*
G02X69704Y537877I-1131J-987D01*
G02X66700I-1502J0D01*
G02X67070Y538864I1501J0D01*
G01Y538865D01*
X67071D01*
G03X67119Y538995I-152J130D01*
G01Y539259D01*
G03X67071Y539389I-200J0D01*
G01X67070Y539390D01*
G02Y541364I1131J987D01*
G01Y541365D01*
X67071D01*
G03X67119Y541495I-152J130D01*
G01Y541759D01*
G03X67071Y541889I-200J0D01*
G01X67070Y541890D01*
G02Y543864I1131J987D01*
G01Y543865D01*
X67071D01*
G03X67119Y543995I-152J130D01*
G01Y544259D01*
G03X67071Y544389I-200J0D01*
G01X67070Y544390D01*
G02X66700Y545377I1131J987D01*
G01Y545378D01*
G02X67263Y546550I1502J0D01*
G01X67299Y546578D01*
X67339Y546661D01*
X67337Y547021D01*
G03X67261Y547177I-200J-1D01*
G02X66686Y548358I927J1182D01*
G02X68188Y549860I1502J0D01*
G02X69175Y549490I0J-1501D01*
G01X69176D01*
Y549489D01*
G03X69306Y549441I130J152D01*
G01X69570D01*
G03X69700Y549489I0J200D01*
G01X69701Y549490D01*
G02X71675I987J-1131D01*
G01X71676D01*
Y549489D01*
G03X71806Y549441I130J152D01*
G01X72070D01*
G03X72200Y549489I0J200D01*
G01X72201Y549490D01*
G02X74175I987J-1131D01*
G37*
G36*
G01X55070Y542231D02*
G02X58074I1502J0D01*
G02X57704Y541244I-1501J0D01*
G01Y541243D01*
X57703D01*
G03X57655Y541113I152J-130D01*
G01Y540849D01*
G03X57703Y540719I200J0D01*
G01X57704Y540718D01*
G02X58074Y539731I-1131J-987D01*
G02X55070I-1502J0D01*
G02X55440Y540718I1501J0D01*
G01Y540719D01*
X55441D01*
G03X55489Y540849I-152J130D01*
G01Y541113D01*
G03X55441Y541243I-200J0D01*
G01X55440Y541244D01*
G02X55070Y542231I1131J987D01*
G37*
G36*
G01X51367Y540458D02*
G02X54371I1502J0D01*
G02X54001Y539471I-1501J0D01*
G01Y539470D01*
X54000D01*
G03X53952Y539340I152J-130D01*
G01Y539076D01*
G03X54000Y538946I200J0D01*
G01X54001Y538945D01*
G02X54371Y537958I-1131J-987D01*
G02X51367I-1502J0D01*
G02X51737Y538945I1501J0D01*
G01Y538946D01*
X51738D01*
G03X51786Y539076I-152J130D01*
G01Y539340D01*
G03X51738Y539470I-200J0D01*
G01X51737Y539471D01*
G02X51367Y540458I1131J987D01*
G37*
G36*
G01X44341Y523822D02*
Y524116D01*
G03X44276Y524263I-200J-1D01*
G02X43791Y525369I1019J1106D01*
G02X46795I1502J0D01*
G02X46310Y524263I-1504J0D01*
G03X46245Y524116I135J-148D01*
G01Y523822D01*
G03X46310Y523675I200J1D01*
G02X46795Y522569I-1019J-1106D01*
G02X43791I-1502J0D01*
G02X44276Y523675I1504J0D01*
G03X44341Y523822I-135J148D01*
G37*
G36*
G01X43229Y518533D02*
X43230Y518532D01*
G03X43360Y518484I130J152D01*
G01X43624D01*
G03X43754Y518532I0J200D01*
G01X43755Y518533D01*
G02X44742Y518903I987J-1131D01*
G02Y515899I0J-1502D01*
G02X43755Y516269I0J1501D01*
G01X43754D01*
Y516270D01*
G03X43624Y516318I-130J-152D01*
G01X43360D01*
G03X43230Y516270I0J-200D01*
G01X43229Y516269D01*
G02X41255I-987J1131D01*
G01X41254D01*
Y516270D01*
G03X41124Y516318I-130J-152D01*
G01X40860D01*
G03X40730Y516270I0J-200D01*
G01X40729Y516269D01*
G02X39742Y515899I-987J1131D01*
G02Y518903I0J1502D01*
G02X40729Y518533I0J-1501D01*
G01X40730D01*
Y518532D01*
G03X40860Y518484I130J152D01*
G01X41124D01*
G03X41254Y518532I0J200D01*
G01X41255Y518533D01*
G02X43229I987J-1131D01*
G37*
G36*
G01X43288Y505957D02*
X43289Y505956D01*
G03X43419Y505908I130J152D01*
G01X43683D01*
G03X43813Y505956I0J200D01*
G01X43814Y505957D01*
G02X44801Y506327I987J-1131D01*
G02Y503323I0J-1502D01*
G02X43814Y503693I0J1501D01*
G01X43813D01*
Y503694D01*
G03X43683Y503742I-130J-152D01*
G01X43419D01*
G03X43289Y503694I0J-200D01*
G01X43288Y503693D01*
G02X41314I-987J1131D01*
G01X41313D01*
Y503694D01*
G03X41183Y503742I-130J-152D01*
G01X40919D01*
G03X40789Y503694I0J-200D01*
G01X40788Y503693D01*
G02X39801Y503323I-987J1131D01*
G02Y506327I0J1502D01*
G02X40788Y505957I0J-1501D01*
G01X40789D01*
Y505956D01*
G03X40919Y505908I130J152D01*
G01X41183D01*
G03X41313Y505956I0J200D01*
G01X41314Y505957D01*
G02X43288I987J-1131D01*
G37*
G36*
G01X76531Y498633D02*
G02X79535I1502J0D01*
G02X79165Y497646I-1501J0D01*
G01Y497645D01*
X79164D01*
G03X79116Y497515I152J-130D01*
G01Y497251D01*
G03X79164Y497121I200J0D01*
G01X79165Y497120D01*
G02Y495146I-1131J-987D01*
G01Y495145D01*
X79164D01*
G03X79116Y495015I152J-130D01*
G01Y494751D01*
G03X79164Y494621I200J0D01*
G01X79165Y494620D01*
G02Y492646I-1131J-987D01*
G01Y492645D01*
X79164D01*
G03X79116Y492515I152J-130D01*
G01Y492251D01*
G03X79164Y492121I200J0D01*
G01X79165Y492120D01*
G02X79535Y491133I-1131J-987D01*
G02X76531I-1502J0D01*
G02X76901Y492120I1501J0D01*
G01Y492121D01*
X76902D01*
G03X76950Y492251I-152J130D01*
G01Y492515D01*
G03X76902Y492645I-200J0D01*
G01X76901Y492646D01*
G02Y494620I1131J987D01*
G01Y494621D01*
X76902D01*
G03X76950Y494751I-152J130D01*
G01Y495015D01*
G03X76902Y495145I-200J0D01*
G01X76901Y495146D01*
G02Y497120I1131J987D01*
G01Y497121D01*
X76902D01*
G03X76950Y497251I-152J130D01*
G01Y497515D01*
G03X76902Y497645I-200J0D01*
G01X76901Y497646D01*
G02X76531Y498633I1131J987D01*
G37*
G36*
G01X70615Y496494D02*
Y496808D01*
G03X70538Y496966I-200J0D01*
G02X69959Y498151I923J1185D01*
G02X71461Y499653I1502J0D01*
G02X72448Y499283I0J-1501D01*
G01X72449D01*
Y499282D01*
G03X72579Y499234I130J152D01*
G01X72843D01*
G03X72973Y499282I0J200D01*
G01X72974Y499283D01*
G02X73961Y499653I987J-1131D01*
G02X75463Y498151I0J-1502D01*
G02X74884Y496966I-1502J0D01*
G03X74807Y496808I123J-158D01*
G01Y496494D01*
G03X74884Y496336I200J0D01*
G02X75463Y495151I-923J-1185D01*
G02X73961Y493649I-1502J0D01*
G02X72974Y494019I0J1501D01*
G01X72973D01*
Y494020D01*
G03X72843Y494068I-130J-152D01*
G01X72579D01*
G03X72449Y494020I0J-200D01*
G01X72448Y494019D01*
G02X71461Y493649I-987J1131D01*
G02X69959Y495151I0J1502D01*
G02X70538Y496336I1502J0D01*
G03X70615Y496494I-123J158D01*
G37*
G36*
G01X64901Y495487D02*
G02X67905I1502J0D01*
G02X67535Y494500I-1501J0D01*
G01Y494499D01*
X67534D01*
G03X67486Y494369I152J-130D01*
G01Y494105D01*
G03X67534Y493975I200J0D01*
G01X67535Y493974D01*
G02X67905Y492987I-1131J-987D01*
G02X64901I-1502J0D01*
G02X65271Y493974I1501J0D01*
G01Y493975D01*
X65272D01*
G03X65320Y494105I-152J130D01*
G01Y494369D01*
G03X65272Y494499I-200J0D01*
G01X65271Y494500D01*
G02X64901Y495487I1131J987D01*
G37*
G36*
G01X61198Y493714D02*
G02X64202I1502J0D01*
G02X63832Y492727I-1501J0D01*
G01Y492726D01*
X63831D01*
G03X63783Y492596I152J-130D01*
G01Y492332D01*
G03X63831Y492202I200J0D01*
G01X63832Y492201D01*
G02X64202Y491214I-1131J-987D01*
G02X61198I-1502J0D01*
G02X61568Y492201I1501J0D01*
G01Y492202D01*
X61569D01*
G03X61617Y492332I-152J130D01*
G01Y492596D01*
G03X61569Y492726I-200J0D01*
G01X61568Y492727D01*
G02X61198Y493714I1131J987D01*
G37*
G36*
G01X54726Y486270D02*
X54727Y486269D01*
G03X54857Y486221I130J152D01*
G01X55121D01*
G03X55251Y486269I0J200D01*
G01X55252Y486270D01*
G02X56239Y486640I987J-1131D01*
G02X57741Y485138I0J-1502D01*
G02X57474Y484283I-1502J0D01*
G01X57451Y484249D01*
X57434Y484168D01*
X57514Y483801D01*
X57562Y483734D01*
X57597Y483713D01*
G02X58326Y482425I-773J-1288D01*
G02X55322I-1502J0D01*
G02X55589Y483280I1502J0D01*
G01X55612Y483314D01*
X55629Y483395D01*
X55549Y483762D01*
X55501Y483829D01*
X55466Y483850D01*
G02X55253Y484006I777J1285D01*
G03X55251Y484007I-88J-173D01*
G03X55121Y484055I-130J-152D01*
G01X54857D01*
G03X54727Y484007I0J-200D01*
G01X54726Y484006D01*
G02X52752I-987J1131D01*
G01X52751D01*
Y484007D01*
G03X52621Y484055I-130J-152D01*
G01X52357D01*
G03X52227Y484007I0J-200D01*
G01X52226Y484006D01*
G02X51239Y483636I-987J1131D01*
G02X50118Y484139I0J1501D01*
G01X50089Y484172D01*
X50012Y484206D01*
X49667Y484204D01*
G03X49519Y484138I0J-200D01*
G01X49518Y484137D01*
G02X48390Y483626I-1129J991D01*
G02Y486630I0J1502D01*
G02X49511Y486127I0J-1501D01*
G01X49540Y486094D01*
X49617Y486060D01*
X49962Y486062D01*
G03X50110Y486128I0J200D01*
G01X50111Y486129D01*
G02X51239Y486640I1129J-991D01*
G02X52226Y486270I0J-1501D01*
G01X52227D01*
Y486269D01*
G03X52357Y486221I130J152D01*
G01X52621D01*
G03X52751Y486269I0J200D01*
G01X52752Y486270D01*
G02X54726I987J-1131D01*
G37*
G36*
G01X54172Y477078D02*
Y477372D01*
G03X54107Y477519I-200J-1D01*
G02X53622Y478625I1019J1106D01*
G02X56626I1502J0D01*
G02X56141Y477519I-1504J0D01*
G03X56076Y477372I135J-148D01*
G01Y477078D01*
G03X56141Y476931I200J1D01*
G02X56626Y475825I-1019J-1106D01*
G02X53622I-1502J0D01*
G02X54107Y476931I1504J0D01*
G03X54172Y477078I-135J148D01*
G37*
G36*
G01X69628Y464652D02*
G02X71130Y466154I1502J0D01*
G02X72117Y465784I0J-1501D01*
G01X72118D01*
Y465783D01*
G03X72248Y465735I130J152D01*
G01X72512D01*
G03X72642Y465783I0J200D01*
G01X72643Y465784D01*
G02X73630Y466154I987J-1131D01*
G02X75132Y464652I0J-1502D01*
G02X74762Y463665I-1501J0D01*
G01Y463664D01*
X74761D01*
G03X74713Y463534I152J-130D01*
G01Y463270D01*
G03X74761Y463140I200J0D01*
G01X74762Y463139D01*
G02Y461165I-1131J-987D01*
G01Y461164D01*
X74761D01*
G03X74713Y461034I152J-130D01*
G01Y460770D01*
G03X74761Y460640I200J0D01*
G01X74762Y460639D01*
G02X75132Y459652I-1131J-987D01*
G02X73630Y458150I-1502J0D01*
G02X72643Y458520I0J1501D01*
G01X72642D01*
Y458521D01*
G03X72512Y458569I-130J-152D01*
G01X72248D01*
G03X72118Y458521I0J-200D01*
G01X72117Y458520D01*
G02X71130Y458150I-987J1131D01*
G02X69628Y459652I0J1502D01*
G02X69998Y460639I1501J0D01*
G01Y460640D01*
X69999D01*
G03X70047Y460770I-152J130D01*
G01Y461034D01*
G03X69999Y461164I-200J0D01*
G01X69998Y461165D01*
G02Y463139I1131J987D01*
G01Y463140D01*
X69999D01*
G03X70047Y463270I-152J130D01*
G01Y463534D01*
G03X69999Y463664I-200J0D01*
G01X69998Y463665D01*
G02X69628Y464652I1131J987D01*
G37*
G36*
G01X61263Y1085998D02*
Y1086314D01*
G03X61186Y1086471I-200J-1D01*
G02X60607Y1087656I923J1185D01*
G02X63611I1502J0D01*
G02X63032Y1086471I-1502J0D01*
G03X62955Y1086314I123J-158D01*
G01Y1085998D01*
G03X63032Y1085841I200J1D01*
G02X63611Y1084656I-923J-1185D01*
G02X60607I-1502J0D01*
G02X61186Y1085841I1502J0D01*
G03X61263Y1085998I-123J158D01*
G37*
G36*
G01X60105Y1106142D02*
X60457D01*
X60526Y1106170D01*
X60554Y1106196D01*
G02X61581Y1106602I1027J-1096D01*
G02X62647Y1106158I0J-1502D01*
G01X62675Y1106129D01*
X62749Y1106099D01*
X63113D01*
X63187Y1106129D01*
X63215Y1106158D01*
G02X64281Y1106602I1066J-1058D01*
G02Y1103598I0J-1502D01*
G02X63215Y1104042I0J1502D01*
G01X63187Y1104071D01*
X63113Y1104101D01*
X62749D01*
X62675Y1104071D01*
X62647Y1104042D01*
G02X61581Y1103598I-1066J1058D01*
G02X60554Y1104004I0J1502D01*
G01X60526Y1104030D01*
X60457Y1104058D01*
X60105D01*
X60036Y1104030D01*
X60008Y1104004D01*
G02X57954I-1027J1096D01*
G01X57926Y1104030D01*
X57857Y1104058D01*
X57505D01*
X57436Y1104030D01*
X57408Y1104004D01*
G02X56381Y1103598I-1027J1096D01*
G02Y1106602I0J1502D01*
G02X57408Y1106196I0J-1502D01*
G01X57436Y1106170D01*
X57505Y1106142D01*
X57857D01*
X57926Y1106170D01*
X57954Y1106196D01*
G02X60008I1027J-1096D01*
G01X60036Y1106170D01*
X60105Y1106142D01*
G37*
G36*
G01X12620Y1112632D02*
X12984D01*
X13058Y1112662D01*
X13086Y1112691D01*
G02X14152Y1113135I1066J-1058D01*
G02X15139Y1112765I0J-1501D01*
G01X15167Y1112741D01*
X15234Y1112716D01*
X15570D01*
X15637Y1112741D01*
X15665Y1112765D01*
G02X16652Y1113135I987J-1131D01*
G02Y1110131I0J-1502D01*
G02X15665Y1110501I0J1501D01*
G01X15637Y1110525D01*
X15570Y1110550D01*
X15234D01*
X15167Y1110525D01*
X15139Y1110501D01*
G02X14152Y1110131I-987J1131D01*
G02X13086Y1110575I0J1502D01*
G01X13058Y1110604D01*
X12984Y1110634D01*
X12620D01*
X12546Y1110604D01*
X12518Y1110575D01*
G02X11452Y1110131I-1066J1058D01*
G02X10425Y1110537I0J1502D01*
G01X10397Y1110563D01*
X10328Y1110591D01*
X9976D01*
X9907Y1110563D01*
X9879Y1110537D01*
G02X8852Y1110131I-1027J1096D01*
G02Y1113135I0J1502D01*
G02X9879Y1112729I0J-1502D01*
G01X9907Y1112703D01*
X9976Y1112675D01*
X10328D01*
X10397Y1112703D01*
X10425Y1112729D01*
G02X11452Y1113135I1027J-1096D01*
G02X12518Y1112691I0J-1502D01*
G01X12546Y1112662D01*
X12620Y1112632D01*
G37*
G36*
G01X60205Y1115842D02*
X60557D01*
X60626Y1115870D01*
X60654Y1115896D01*
G02X61681Y1116302I1027J-1096D01*
G02X62747Y1115858I0J-1502D01*
G01X62775Y1115829D01*
X62849Y1115799D01*
X63213D01*
X63287Y1115829D01*
X63315Y1115858D01*
G02X64381Y1116302I1066J-1058D01*
G02Y1113298I0J-1502D01*
G02X63315Y1113742I0J1502D01*
G01X63287Y1113771D01*
X63213Y1113801D01*
X62849D01*
X62775Y1113771D01*
X62747Y1113742D01*
G02X61681Y1113298I-1066J1058D01*
G02X60654Y1113704I0J1502D01*
G01X60626Y1113730D01*
X60557Y1113758D01*
X60205D01*
X60136Y1113730D01*
X60108Y1113704D01*
G02X58054I-1027J1096D01*
G01X58026Y1113730D01*
X57957Y1113758D01*
X57605D01*
X57536Y1113730D01*
X57508Y1113704D01*
G02X56481Y1113298I-1027J1096D01*
G02Y1116302I0J1502D01*
G02X57508Y1115896I0J-1502D01*
G01X57536Y1115870D01*
X57605Y1115842D01*
X57957D01*
X58026Y1115870D01*
X58054Y1115896D01*
G02X60108I1027J-1096D01*
G01X60136Y1115870D01*
X60205Y1115842D01*
G37*
G36*
G01X12720Y1122332D02*
X13084D01*
X13158Y1122362D01*
X13186Y1122391D01*
G02X14252Y1122835I1066J-1058D01*
G02X15239Y1122465I0J-1501D01*
G01X15267Y1122441D01*
X15334Y1122416D01*
X15670D01*
X15737Y1122441D01*
X15765Y1122465D01*
G02X16752Y1122835I987J-1131D01*
G02Y1119831I0J-1502D01*
G02X15765Y1120201I0J1501D01*
G01X15737Y1120225D01*
X15670Y1120250D01*
X15334D01*
X15267Y1120225D01*
X15239Y1120201D01*
G02X14252Y1119831I-987J1131D01*
G02X13186Y1120275I0J1502D01*
G01X13158Y1120304D01*
X13084Y1120334D01*
X12720D01*
X12646Y1120304D01*
X12618Y1120275D01*
G02X11552Y1119831I-1066J1058D01*
G02X10525Y1120237I0J1502D01*
G01X10497Y1120263D01*
X10428Y1120291D01*
X10076D01*
X10007Y1120263D01*
X9979Y1120237D01*
G02X8952Y1119831I-1027J1096D01*
G02Y1122835I0J1502D01*
G02X9979Y1122429I0J-1502D01*
G01X10007Y1122403D01*
X10076Y1122375D01*
X10428D01*
X10497Y1122403D01*
X10525Y1122429D01*
G02X11552Y1122835I1027J-1096D01*
G02X12618Y1122391I0J-1502D01*
G01X12646Y1122362D01*
X12720Y1122332D01*
G37*
G36*
G01X15670Y1129250D02*
X15334D01*
X15267Y1129225D01*
X15239Y1129201D01*
G02X14252Y1128831I-987J1131D01*
G02Y1131835I0J1502D01*
G02X15239Y1131465I0J-1501D01*
G01X15267Y1131441D01*
X15334Y1131416D01*
X15670D01*
X15737Y1131441D01*
X15765Y1131465D01*
G02X16752Y1131835I987J-1131D01*
G02Y1128831I0J-1502D01*
G02X15765Y1129201I0J1501D01*
G01X15737Y1129225D01*
X15670Y1129250D01*
G37*
G36*
G01X56815Y1132605D02*
X56479D01*
X56412Y1132580D01*
X56384Y1132556D01*
G02X55397Y1132186I-987J1131D01*
G02Y1135190I0J1502D01*
G02X56384Y1134820I0J-1501D01*
G01X56412Y1134796D01*
X56479Y1134771D01*
X56815D01*
X56882Y1134796D01*
X56910Y1134820D01*
G02X57897Y1135190I987J-1131D01*
G02Y1132186I0J-1502D01*
G02X56910Y1132556I0J1501D01*
G01X56882Y1132580D01*
X56815Y1132605D01*
G37*
G36*
G01X15724Y1137622D02*
X15388D01*
X15321Y1137597D01*
X15293Y1137573D01*
G02X14306Y1137203I-987J1131D01*
G02Y1140207I0J1502D01*
G02X15293Y1139837I0J-1501D01*
G01X15321Y1139813D01*
X15388Y1139788D01*
X15724D01*
X15791Y1139813D01*
X15819Y1139837D01*
G02X16806Y1140207I987J-1131D01*
G02Y1137203I0J-1502D01*
G02X15819Y1137573I0J1501D01*
G01X15791Y1137597D01*
X15724Y1137622D01*
G37*
G36*
G01X39710Y1466927D02*
G02X39494Y1467703I1286J776D01*
G02X42498I1502J0D01*
G02X41160Y1466210I-1502J0D01*
G01X41112Y1466205D01*
X41031Y1466150D01*
X40826Y1465778D01*
X40823Y1465681D01*
X40845Y1465637D01*
G02X41028Y1464846I-1620J-791D01*
G02X39225Y1463044I-1803J1D01*
G01X35825D01*
G02X34022Y1464846I-1J1802D01*
G02X34130Y1465459I1803J-2D01*
G01X34148Y1465509D01*
X34131Y1465610D01*
X33855Y1465959D01*
X33760Y1465999D01*
X33708Y1465993D01*
G02X33536Y1465983I-173J1492D01*
G02X35038Y1467485I0J1502D01*
G02X34989Y1467104I-1502J0D01*
G01X34975Y1467053D01*
X35001Y1466953D01*
X35308Y1466631D01*
X35406Y1466600D01*
X35457Y1466611D01*
G02X35825Y1466648I363J-1765D01*
G01X39225D01*
G02X39507Y1466626I1J-1802D01*
G03X39710Y1466927I32J198D01*
G37*
G36*
G01X7117Y1531225D02*
X7075Y1531254D01*
G02X6420Y1532494I846J1240D01*
G02X9424I1502J0D01*
G02X8812Y1531284I-1502J0D01*
G01X8771Y1531254D01*
X8728Y1531161D01*
X8756Y1530723D01*
X8810Y1530637D01*
X8855Y1530612D01*
G02X9784Y1529035I-874J-1577D01*
G01Y1525635D01*
G02X8924Y1524098I-1802J-1D01*
G01X8880Y1524071D01*
X8830Y1523985D01*
X8817Y1523548D01*
X8862Y1523459D01*
X8903Y1523429D01*
G02X9544Y1522199I-860J-1230D01*
G02X6540I-1502J0D01*
G02X7138Y1523399I1503J0D01*
G01X7179Y1523429D01*
X7221Y1523520D01*
X7192Y1523956D01*
X7139Y1524041D01*
X7094Y1524066D01*
G02X6180Y1525635I888J1568D01*
G01Y1529035D01*
G02X7055Y1530581I1803J0D01*
G01X7099Y1530607D01*
X7150Y1530695D01*
X7163Y1531134D01*
X7117Y1531225D01*
G37*
G36*
G01X98334Y980330D02*
G02X101338I1502J0D01*
G02X100983Y979360I-1503J0D01*
G01X100957Y979330D01*
X100933Y979254D01*
X100962Y978893D01*
X100999Y978822D01*
X101029Y978797D01*
G02X101560Y977651I-971J-1146D01*
G02X98556I-1502J0D01*
G02X98911Y978621I1503J0D01*
G01X98937Y978651D01*
X98961Y978727D01*
X98932Y979088D01*
X98895Y979159D01*
X98865Y979184D01*
G02X98334Y980330I971J1146D01*
G37*
G36*
G01X102334D02*
G02X105338I1502J0D01*
G02X104937Y979308I-1503J0D01*
G03X104883Y979161I146J-137D01*
G01X104898Y978876D01*
G03X104965Y978736I200J10D01*
G02X105474Y977609I-993J-1127D01*
G02X102470I-1502J0D01*
G02X102871Y978631I1503J0D01*
G03X102925Y978778I-146J137D01*
G01X102910Y979063D01*
G03X102843Y979203I-200J-10D01*
G02X102334Y980330I993J1127D01*
G37*
G36*
G01X102572Y1008703D02*
X102278D01*
G03X102131Y1008638I1J-200D01*
G02X101025Y1008153I-1106J1019D01*
G02Y1011157I0J1502D01*
G02X102131Y1010672I0J-1504D01*
G03X102278Y1010607I148J135D01*
G01X102572D01*
G03X102719Y1010672I-1J200D01*
G02X103825Y1011157I1106J-1019D01*
G02Y1008153I0J-1502D01*
G02X102719Y1008638I0J1504D01*
G03X102572Y1008703I-148J-135D01*
G37*
G36*
G01X135024Y1012354D02*
G02X138028I1502J0D01*
G02X137467Y1011183I-1503J0D01*
G01X137431Y1011154D01*
X137392Y1011071D01*
X137397Y1010709D01*
G03X137476Y1010552I200J2D01*
G02X138073Y1009354I-905J-1199D01*
G02X135069I-1502J0D01*
G02X135630Y1010525I1503J0D01*
G01X135666Y1010554D01*
X135705Y1010637D01*
X135700Y1010999D01*
G03X135621Y1011156I-200J-2D01*
G02X135024Y1012354I905J1199D01*
G37*
G36*
G01X124059Y1103374D02*
X124053Y1103783D01*
X124012Y1103864D01*
X123975Y1103893D01*
G02X123378Y1105091I905J1199D01*
G02X126382I1502J0D01*
G02X125821Y1103920I-1503J0D01*
G01X125785Y1103891D01*
X125746Y1103808D01*
X125752Y1103399D01*
X125793Y1103318D01*
X125830Y1103289D01*
G02X126427Y1102091I-905J-1199D01*
G02X123423I-1502J0D01*
G02X123984Y1103262I1503J0D01*
G01X124020Y1103291D01*
X124059Y1103374D01*
G37*
G36*
G01Y1115974D02*
X124053Y1116383D01*
X124012Y1116464D01*
X123975Y1116493D01*
G02X123378Y1117691I905J1199D01*
G02X126382I1502J0D01*
G02X125821Y1116520I-1503J0D01*
G01X125785Y1116491D01*
X125746Y1116408D01*
X125752Y1115999D01*
X125793Y1115918D01*
X125830Y1115889D01*
G02X126427Y1114691I-905J-1199D01*
G02X123423I-1502J0D01*
G02X123984Y1115862I1503J0D01*
G01X124020Y1115891D01*
X124059Y1115974D01*
G37*
G36*
G01Y1128574D02*
X124053Y1128983D01*
X124012Y1129064D01*
X123975Y1129093D01*
G02X123378Y1130291I905J1199D01*
G02X126382I1502J0D01*
G02X125821Y1129120I-1503J0D01*
G01X125785Y1129091D01*
X125746Y1129008D01*
X125752Y1128599D01*
X125793Y1128518D01*
X125830Y1128489D01*
G02X126427Y1127291I-905J-1199D01*
G02X123423I-1502J0D01*
G02X123984Y1128462I1503J0D01*
G01X124020Y1128491D01*
X124059Y1128574D01*
G37*
G36*
G01Y1153774D02*
X124053Y1154183D01*
X124012Y1154264D01*
X123975Y1154293D01*
G02X123378Y1155491I905J1199D01*
G02X126382I1502J0D01*
G02X125821Y1154320I-1503J0D01*
G01X125785Y1154291D01*
X125746Y1154208D01*
X125752Y1153799D01*
X125793Y1153718D01*
X125830Y1153689D01*
G02X126427Y1152491I-905J-1199D01*
G02X123423I-1502J0D01*
G02X123984Y1153662I1503J0D01*
G01X124020Y1153691D01*
X124059Y1153774D01*
G37*
G36*
G01X123812Y1141649D02*
G02X122972Y1142997I662J1348D01*
G02X125976I1502J0D01*
G02X125492Y1141893I-1501J0D01*
G03X125587Y1141239I271J-295D01*
G02X126427Y1139891I-662J-1348D01*
G02X123423I-1502J0D01*
G02X123907Y1140995I1501J0D01*
G03X123812Y1141649I-271J295D01*
G37*
G36*
G01Y1166849D02*
G02X122972Y1168197I662J1348D01*
G02X125976I1502J0D01*
G02X125492Y1167093I-1501J0D01*
G03X125587Y1166439I271J-295D01*
G02X126427Y1165091I-662J-1348D01*
G02X123423I-1502J0D01*
G02X123907Y1166195I1501J0D01*
G03X123812Y1166849I-271J295D01*
G37*
G36*
G01X146948Y1135604D02*
X143208D01*
G02Y1138210I0J1303D01*
G01X146948D01*
G02Y1135604I0J-1303D01*
G37*
G36*
G01X165649Y1131864D02*
X161909D01*
G02Y1134470I0J1303D01*
G01X165649D01*
G02Y1131864I0J-1303D01*
G37*
G36*
G01X154429D02*
X150689D01*
G02Y1134470I0J1303D01*
G01X154429D01*
G02Y1131864I0J-1303D01*
G37*
G36*
G01X143207Y1171872D02*
X146947D01*
G02Y1169268I0J-1302D01*
G01X143207D01*
G02X142200Y1169744I0J1303D01*
G01X142172Y1169778D01*
X142095Y1169815D01*
X141748Y1169825D01*
G03X141595Y1169759I-4J-200D01*
G02X140707Y1169367I-888J810D01*
G02Y1171771I0J1202D01*
G02X141595Y1171379I0J-1202D01*
G01X141624Y1171347D01*
X141703Y1171313D01*
X142050Y1171323D01*
G03X142200Y1171396I-4J200D01*
G02X143207Y1171872I1007J-827D01*
G37*
G36*
G01X173351Y1109547D02*
G02X173129Y1109526I-224J1181D01*
G02X174331Y1110728I0J1202D01*
G02X174310Y1110506I-1202J2D01*
G03X174777Y1110039I393J-74D01*
G02X174999Y1110060I224J-1181D01*
G02X173797Y1108858I0J-1202D01*
G02X173818Y1109080I1202J-2D01*
G03X173351Y1109547I-393J74D01*
G37*
G36*
G01X213069Y1110728D02*
G02X215473I1202J0D01*
G02X215452Y1110506I-1202J2D01*
G01X215443Y1110457D01*
X215472Y1110364D01*
X215777Y1110059D01*
X215870Y1110030D01*
X215919Y1110039D01*
G02X216141Y1110060I224J-1181D01*
G02X214939Y1108858I0J-1202D01*
G02X214960Y1109080I1202J-2D01*
G01X214969Y1109129D01*
X214940Y1109222D01*
X214635Y1109527D01*
X214542Y1109556D01*
X214493Y1109547D01*
G02X214271Y1109526I-224J1181D01*
G02X214049Y1109547I2J1202D01*
G01X214000Y1109556D01*
X213907Y1109527D01*
X213602Y1109222D01*
X213573Y1109129D01*
X213582Y1109080D01*
G02X213603Y1108858I-1181J-224D01*
G02X212401Y1110060I-1202J0D01*
G02X212623Y1110039I-2J-1202D01*
G01X212672Y1110030D01*
X212765Y1110059D01*
X213070Y1110364D01*
X213099Y1110457D01*
X213090Y1110506D01*
G02X213069Y1110728I1181J224D01*
G37*
G36*
G01X183148Y1114468D02*
G02X184350Y1113266I1202J0D01*
G02X184128Y1113287I2J1202D01*
G01X184079Y1113296D01*
X183986Y1113267D01*
X183681Y1112962D01*
X183652Y1112869D01*
X183661Y1112820D01*
G02X183682Y1112598I-1181J-224D01*
G02X181278I-1202J0D01*
G02X181299Y1112820I1202J-2D01*
G01X181308Y1112869D01*
X181279Y1112962D01*
X180974Y1113267D01*
X180881Y1113296D01*
X180832Y1113287D01*
G02X180610Y1113266I-224J1181D01*
G02X180388Y1113287I2J1202D01*
G01X180339Y1113296D01*
X180246Y1113267D01*
X179941Y1112962D01*
X179912Y1112869D01*
X179921Y1112820D01*
G02X179942Y1112598I-1181J-224D01*
G02X177538I-1202J0D01*
G02X177559Y1112820I1202J-2D01*
G01X177568Y1112869D01*
X177539Y1112962D01*
X177234Y1113267D01*
X177141Y1113296D01*
X177092Y1113287D01*
G02X176870Y1113266I-224J1181D01*
G02X178072Y1114468I0J1202D01*
G02X178051Y1114246I-1202J2D01*
G01X178042Y1114197D01*
X178071Y1114104D01*
X178376Y1113799D01*
X178469Y1113770D01*
X178518Y1113779D01*
G02X178740Y1113800I224J-1181D01*
G02X178962Y1113779I-2J-1202D01*
G01X179011Y1113770D01*
X179104Y1113799D01*
X179409Y1114104D01*
X179438Y1114197D01*
X179429Y1114246D01*
G02X179408Y1114468I1181J224D01*
G02X181812I1202J0D01*
G02X181791Y1114246I-1202J2D01*
G01X181782Y1114197D01*
X181811Y1114104D01*
X182116Y1113799D01*
X182209Y1113770D01*
X182258Y1113779D01*
G02X182480Y1113800I224J-1181D01*
G02X182702Y1113779I-2J-1202D01*
G01X182751Y1113770D01*
X182844Y1113799D01*
X183149Y1114104D01*
X183178Y1114197D01*
X183169Y1114246D01*
G02X183148Y1114468I1181J224D01*
G37*
G36*
G01X291613Y1140649D02*
G02X292815Y1139447I1202J0D01*
G02X292592Y1139468I1J1202D01*
G01X292543Y1139477D01*
X292450Y1139448D01*
X292180Y1139179D01*
G03X292125Y1139002I142J-141D01*
G01Y1139001D01*
G02X292146Y1138779I-1181J-224D01*
G02X289742I-1202J0D01*
G02X289763Y1139001I1202J-2D01*
G01X289772Y1139050D01*
X289743Y1139143D01*
X289438Y1139448D01*
X289345Y1139477D01*
X289296Y1139468D01*
G02X289074Y1139447I-224J1181D01*
G02X290276Y1140649I0J1202D01*
G02X290255Y1140427I-1202J2D01*
G01X290246Y1140378D01*
X290275Y1140285D01*
X290580Y1139980D01*
X290673Y1139951D01*
X290722Y1139960D01*
G02X290944Y1139981I224J-1181D01*
G02X291167Y1139960I-1J-1202D01*
G01X291216Y1139951D01*
X291309Y1139980D01*
X291579Y1140249D01*
G03X291634Y1140426I-142J141D01*
G01Y1140427D01*
G02X291613Y1140649I1181J224D01*
G37*
G36*
G01X160707Y1178051D02*
G02X161909Y1176849I1202J0D01*
G02X161767Y1176858I5J1202D01*
G01X161765D01*
X161719Y1176863D01*
X161631Y1176831D01*
X161344Y1176531D01*
X161316Y1176441D01*
X161324Y1176395D01*
G02X161342Y1176180I-1285J-216D01*
G02X161324Y1175966I-1303J2D01*
G01X161316Y1175920D01*
X161344Y1175830D01*
X161599Y1175563D01*
G03X161765Y1175503I144J139D01*
G01X161766D01*
G02X161909Y1175512I147J-1193D01*
G02X160707Y1174310I0J-1202D01*
G02X160716Y1174452I1202J-5D01*
G01Y1174454D01*
X160721Y1174500D01*
X160689Y1174588D01*
X160389Y1174875D01*
X160299Y1174903D01*
X160253Y1174895D01*
G02X160039Y1174878I-210J1285D01*
G01X159762D01*
G03X159613Y1174812I0J-200D01*
G01X159386Y1174558D01*
X159360Y1174478D01*
X159364Y1174436D01*
G02X159371Y1174310I-1195J-130D01*
G02X156967I-1202J0D01*
G02X156974Y1174435I1202J-5D01*
G01Y1174437D01*
X156978Y1174478D01*
X156952Y1174558D01*
X156725Y1174812D01*
G03X156576Y1174878I-149J-134D01*
G01X156299D01*
G02X156085Y1174895I-4J1302D01*
G01X156039Y1174903D01*
X155949Y1174875D01*
X155682Y1174620D01*
G03X155622Y1174454I139J-144D01*
G01Y1174453D01*
G02X155631Y1174310I-1193J-147D01*
G02X154429Y1175512I-1202J0D01*
G02X154571Y1175503I-5J-1202D01*
G01X154573D01*
X154619Y1175498D01*
X154707Y1175530D01*
X154994Y1175830D01*
X155022Y1175920D01*
X155014Y1175966D01*
G02X154996Y1176180I1285J216D01*
G02X156299Y1177482I1303J-1D01*
G01X160039D01*
G02X160253Y1177465I4J-1302D01*
G01X160300Y1177457D01*
X160390Y1177485D01*
X160690Y1177772D01*
X160722Y1177860D01*
X160716Y1177907D01*
G02X160707Y1178051I1193J147D01*
G37*
G36*
G01X186888Y1200491D02*
G02X188090Y1199289I1202J0D01*
G02X187868Y1199310I2J1202D01*
G01X187819Y1199319D01*
X187726Y1199290D01*
X187421Y1198985D01*
X187392Y1198892D01*
X187401Y1198843D01*
G02X187422Y1198621I-1181J-224D01*
G02X187401Y1198399I-1202J2D01*
G01X187392Y1198350D01*
X187421Y1198257D01*
X187726Y1197952D01*
X187819Y1197923D01*
X187868Y1197932D01*
G02X188090Y1197953I224J-1181D01*
G02X186888Y1196751I0J-1202D01*
G02X186909Y1196973I1202J-2D01*
G01X186918Y1197022D01*
X186889Y1197115D01*
X186584Y1197420D01*
X186491Y1197449D01*
X186442Y1197440D01*
G02X186220Y1197419I-224J1181D01*
G02X185998Y1197440I2J1202D01*
G01X185949Y1197449D01*
X185856Y1197420D01*
X185551Y1197115D01*
X185522Y1197022D01*
X185531Y1196973D01*
G02X185552Y1196751I-1181J-224D01*
G02X183148I-1202J0D01*
G02X183169Y1196973I1202J-2D01*
G01X183178Y1197022D01*
X183149Y1197115D01*
X182844Y1197420D01*
X182751Y1197449D01*
X182702Y1197440D01*
G02X182480Y1197419I-224J1181D01*
G02X183682Y1198621I0J1202D01*
G02X183661Y1198399I-1202J2D01*
G01X183652Y1198350D01*
X183681Y1198257D01*
X183986Y1197952D01*
X184079Y1197923D01*
X184128Y1197932D01*
G02X184350Y1197953I224J-1181D01*
G02X184572Y1197932I-2J-1202D01*
G01X184621Y1197923D01*
X184714Y1197952D01*
X185019Y1198257D01*
X185048Y1198350D01*
X185039Y1198399D01*
G02X185018Y1198621I1181J224D01*
G02X186220Y1199823I1202J0D01*
G02X186442Y1199802I-2J-1202D01*
G01X186491Y1199793D01*
X186584Y1199822D01*
X186889Y1200127D01*
X186918Y1200220D01*
X186909Y1200269D01*
G02X186888Y1200491I1181J224D01*
G37*
G36*
G01X186442Y1204921D02*
G02X186220Y1204900I-224J1181D01*
G02X187422Y1206102I0J1202D01*
G02X187401Y1205880I-1202J2D01*
G03X187868Y1205413I393J-74D01*
G02X188090Y1205434I224J-1181D01*
G02X186888Y1204232I0J-1202D01*
G02X186909Y1204454I1202J-2D01*
G03X186442Y1204921I-393J74D01*
G37*
G36*
G01X196238Y1209842D02*
G02X198642I1202J0D01*
G02X198621Y1209621I-1202J3D01*
G01Y1209619D01*
G03X198676Y1209442I197J-36D01*
G01X198946Y1209173D01*
X199039Y1209144D01*
X199088Y1209153D01*
G02X199311Y1209174I224J-1181D01*
G02X198109Y1207972I0J-1202D01*
G02X198130Y1208193I1202J-3D01*
G01Y1208195D01*
G03X198075Y1208372I-197J36D01*
G01X197805Y1208641D01*
X197712Y1208670D01*
X197663Y1208661D01*
G02X197440Y1208640I-224J1181D01*
G02X197218Y1208661I2J1202D01*
G01X197169Y1208670D01*
X197076Y1208641D01*
X196771Y1208336D01*
X196742Y1208243D01*
X196751Y1208194D01*
G02X196772Y1207972I-1181J-224D01*
G02X194368I-1202J0D01*
G02X194389Y1208194I1202J-2D01*
G01X194398Y1208243D01*
X194369Y1208336D01*
X194064Y1208641D01*
X193971Y1208670D01*
X193922Y1208661D01*
G02X193700Y1208640I-224J1181D01*
G02X193478Y1208661I2J1202D01*
G01X193429Y1208670D01*
X193336Y1208641D01*
X193031Y1208336D01*
X193002Y1208243D01*
X193011Y1208194D01*
G02X193032Y1207972I-1181J-224D01*
G02X190628I-1202J0D01*
G02X190649Y1208194I1202J-2D01*
G01X190658Y1208243D01*
X190629Y1208336D01*
X190324Y1208641D01*
X190231Y1208670D01*
X190182Y1208661D01*
G02X189960Y1208640I-224J1181D01*
G02X191162Y1209842I0J1202D01*
G02X191141Y1209620I-1202J2D01*
G01X191132Y1209571D01*
X191161Y1209478D01*
X191466Y1209173D01*
X191559Y1209144D01*
X191608Y1209153D01*
G02X191830Y1209174I224J-1181D01*
G02X192052Y1209153I-2J-1202D01*
G01X192101Y1209144D01*
X192194Y1209173D01*
X192499Y1209478D01*
X192528Y1209571D01*
X192519Y1209620D01*
G02X192498Y1209842I1181J224D01*
G02X194902I1202J0D01*
G02X194881Y1209620I-1202J2D01*
G01X194872Y1209571D01*
X194901Y1209478D01*
X195206Y1209173D01*
X195299Y1209144D01*
X195348Y1209153D01*
G02X195570Y1209174I224J-1181D01*
G02X195792Y1209153I-2J-1202D01*
G01X195841Y1209144D01*
X195934Y1209173D01*
X196239Y1209478D01*
X196268Y1209571D01*
X196259Y1209620D01*
G02X196238Y1209842I1181J224D01*
G37*
G36*
G01Y1217322D02*
G02X197440Y1216120I1202J0D01*
G02X197218Y1216141I2J1202D01*
G01X197169Y1216150D01*
X197076Y1216121D01*
X196771Y1215816D01*
X196742Y1215723D01*
X196751Y1215674D01*
G02X196772Y1215452I-1181J-224D01*
G02X195570Y1214250I-1202J0D01*
G02X195348Y1214271I2J1202D01*
G01X195299Y1214280D01*
X195206Y1214251D01*
X194901Y1213946D01*
X194872Y1213853D01*
X194881Y1213804D01*
G02X194902Y1213582I-1181J-224D01*
G02X193700Y1214784I-1202J0D01*
G02X193922Y1214763I-2J-1202D01*
G01X193971Y1214754D01*
X194064Y1214783D01*
X194369Y1215088D01*
X194398Y1215181D01*
X194389Y1215230D01*
G02X194368Y1215452I1181J224D01*
G02X195570Y1216654I1202J0D01*
G02X195792Y1216633I-2J-1202D01*
G01X195841Y1216624D01*
X195934Y1216653D01*
X196239Y1216958D01*
X196268Y1217051D01*
X196259Y1217100D01*
G02X196238Y1217322I1181J224D01*
G37*
G36*
G01X201181Y1216120D02*
G02X202383Y1217322I0J1202D01*
G02X202362Y1217100I-1202J2D01*
G01X202353Y1217051D01*
X202382Y1216958D01*
X202687Y1216653D01*
X202780Y1216624D01*
X202829Y1216633D01*
G02X203051Y1216654I224J-1181D01*
G02X204253Y1215452I0J-1202D01*
G02X204232Y1215230I-1202J2D01*
G01X204223Y1215181D01*
X204252Y1215088D01*
X204557Y1214783D01*
X204650Y1214754D01*
X204699Y1214763D01*
G02X204921Y1214784I224J-1181D01*
G02X203719Y1213582I0J-1202D01*
G02X203740Y1213804I1202J-2D01*
G01X203749Y1213853D01*
X203720Y1213946D01*
X203415Y1214251D01*
X203322Y1214280D01*
X203273Y1214271D01*
G02X203051Y1214250I-224J1181D01*
G02X202829Y1214271I2J1202D01*
G01X202780Y1214280D01*
X202687Y1214251D01*
X202382Y1213946D01*
X202353Y1213853D01*
X202362Y1213804D01*
G02X202383Y1213582I-1181J-224D01*
G02X201181Y1214784I-1202J0D01*
G02X201403Y1214763I-2J-1202D01*
G01X201452Y1214754D01*
X201545Y1214783D01*
X201850Y1215088D01*
X201879Y1215181D01*
X201870Y1215230D01*
G02X201849Y1215452I1181J224D01*
G02X201870Y1215674I1202J-2D01*
G01X201879Y1215723D01*
X201850Y1215816D01*
X201545Y1216121D01*
X201452Y1216150D01*
X201403Y1216141D01*
G02X201181Y1216120I-224J1181D01*
G37*
G36*
G01X208661D02*
G02X209863Y1217322I0J1202D01*
G02X209842Y1217100I-1202J2D01*
G01X209833Y1217051D01*
X209862Y1216958D01*
X210167Y1216653D01*
X210260Y1216624D01*
X210309Y1216633D01*
G02X210531Y1216654I224J-1181D01*
G02Y1214250I0J-1202D01*
G02X210309Y1214271I2J1202D01*
G01X210260Y1214280D01*
X210167Y1214251D01*
X209862Y1213946D01*
X209833Y1213853D01*
X209842Y1213804D01*
G02X209863Y1213582I-1181J-224D01*
G02X209842Y1213360I-1202J2D01*
G01X209833Y1213311D01*
X209862Y1213218D01*
X210167Y1212913D01*
X210260Y1212884D01*
X210309Y1212893D01*
G02X210531Y1212914I224J-1181D01*
G02X209329Y1211712I0J-1202D01*
G02X209350Y1211934I1202J-2D01*
G01X209359Y1211983D01*
X209330Y1212076D01*
X209025Y1212381D01*
X208932Y1212410D01*
X208883Y1212401D01*
G02X208661Y1212380I-224J1181D01*
G02Y1214784I0J1202D01*
G02X208883Y1214763I-2J-1202D01*
G01X208932Y1214754D01*
X209025Y1214783D01*
X209330Y1215088D01*
X209359Y1215181D01*
X209350Y1215230D01*
G02X209329Y1215452I1181J224D01*
G02X209350Y1215674I1202J-2D01*
G01X209359Y1215723D01*
X209330Y1215816D01*
X209025Y1216121D01*
X208932Y1216150D01*
X208883Y1216141D01*
G02X208661Y1216120I-224J1181D01*
G37*
G36*
G01X218679Y1217322D02*
G02X221083I1202J0D01*
G02X221062Y1217101I-1202J3D01*
G01Y1217099D01*
G03X221117Y1216922I197J-36D01*
G01X221387Y1216653D01*
X221480Y1216624D01*
X221529Y1216633D01*
G02X221752Y1216654I224J-1181D01*
G02X220550Y1215452I0J-1202D01*
G02X220571Y1215673I1202J-3D01*
G01Y1215675D01*
G03X220516Y1215852I-197J36D01*
G01X220246Y1216121D01*
X220153Y1216150D01*
X220104Y1216141D01*
G02X219881Y1216120I-224J1181D01*
G02X219659Y1216141I2J1202D01*
G01X219610Y1216150D01*
X219517Y1216121D01*
X219212Y1215816D01*
X219183Y1215723D01*
X219192Y1215674D01*
G02X219213Y1215452I-1181J-224D01*
G02X218011Y1216654I-1202J0D01*
G02X218233Y1216633I-2J-1202D01*
G01X218282Y1216624D01*
X218375Y1216653D01*
X218680Y1216958D01*
X218709Y1217051D01*
X218700Y1217100D01*
G02X218679Y1217322I1181J224D01*
G37*
G36*
G01X241120D02*
G02X243524I1202J0D01*
G02X243503Y1217100I-1202J2D01*
G01X243494Y1217051D01*
X243523Y1216958D01*
X243828Y1216653D01*
X243921Y1216624D01*
X243970Y1216633D01*
G02X244192Y1216654I224J-1181D01*
G02X242990Y1215452I0J-1202D01*
G02X243011Y1215674I1202J-2D01*
G01X243020Y1215723D01*
X242991Y1215816D01*
X242686Y1216121D01*
X242593Y1216150D01*
X242544Y1216141D01*
G02X242322Y1216120I-224J1181D01*
G02X242100Y1216141I2J1202D01*
G01X242051Y1216150D01*
X241958Y1216121D01*
X241653Y1215816D01*
X241624Y1215723D01*
X241633Y1215674D01*
G02X241654Y1215452I-1181J-224D01*
G02X239250I-1202J0D01*
G02X239271Y1215674I1202J-2D01*
G01X239280Y1215723D01*
X239251Y1215816D01*
X238946Y1216121D01*
X238853Y1216150D01*
X238804Y1216141D01*
G02X238582Y1216120I-224J1181D01*
G02X238360Y1216141I2J1202D01*
G01X238311Y1216150D01*
X238218Y1216121D01*
X237913Y1215816D01*
X237884Y1215723D01*
X237893Y1215674D01*
G02X237914Y1215452I-1181J-224D01*
G02X236712Y1216654I-1202J0D01*
G02X236934Y1216633I-2J-1202D01*
G01X236983Y1216624D01*
X237076Y1216653D01*
X237381Y1216958D01*
X237410Y1217051D01*
X237401Y1217100D01*
G02X237380Y1217322I1181J224D01*
G02X239784I1202J0D01*
G02X239763Y1217100I-1202J2D01*
G01X239754Y1217051D01*
X239783Y1216958D01*
X240088Y1216653D01*
X240181Y1216624D01*
X240230Y1216633D01*
G02X240452Y1216654I224J-1181D01*
G02X240674Y1216633I-2J-1202D01*
G01X240723Y1216624D01*
X240816Y1216653D01*
X241121Y1216958D01*
X241150Y1217051D01*
X241141Y1217100D01*
G02X241120Y1217322I1181J224D01*
G37*
G36*
G01X192498Y1221062D02*
G02X193700Y1219860I1202J0D01*
G02X193478Y1219881I2J1202D01*
G01X193429Y1219890D01*
X193336Y1219861D01*
X193031Y1219556D01*
X193002Y1219463D01*
X193011Y1219414D01*
G02X193032Y1219192I-1181J-224D01*
G02X191830Y1217990I-1202J0D01*
G02X191608Y1218011I2J1202D01*
G01X191559Y1218020D01*
X191466Y1217991D01*
X191161Y1217686D01*
X191132Y1217593D01*
X191141Y1217544D01*
G02X191162Y1217322I-1181J-224D01*
G02X189960Y1218524I-1202J0D01*
G02X190182Y1218503I-2J-1202D01*
G01X190231Y1218494D01*
X190324Y1218523D01*
X190629Y1218828D01*
X190658Y1218921D01*
X190649Y1218970D01*
G02X190628Y1219192I1181J224D01*
G02X190649Y1219414I1202J-2D01*
G01X190658Y1219463D01*
X190629Y1219556D01*
X190324Y1219861D01*
X190231Y1219890D01*
X190182Y1219881D01*
G02X189960Y1219860I-224J1181D01*
G02X191162Y1221062I0J1202D01*
G02X191141Y1220840I-1202J2D01*
G01X191132Y1220791D01*
X191161Y1220698D01*
X191466Y1220393D01*
X191559Y1220364D01*
X191608Y1220373D01*
G02X191830Y1220394I224J-1181D01*
G02X192052Y1220373I-2J-1202D01*
G01X192101Y1220364D01*
X192194Y1220393D01*
X192499Y1220698D01*
X192528Y1220791D01*
X192519Y1220840D01*
G02X192498Y1221062I1181J224D01*
G37*
G36*
G01X402489Y1419078D02*
X405889D01*
G02Y1415472I0J-1803D01*
G01X402489D01*
G02Y1419078I0J1803D01*
G37*
G36*
G01X452642Y1361602D02*
X456042D01*
G02Y1358596I0J-1503D01*
G01X452642D01*
G02Y1361602I0J1503D01*
G37*
G36*
G01Y1349690D02*
X456042D01*
G02Y1346684I0J-1503D01*
G01X452642D01*
G02Y1349690I0J1503D01*
G37*
G36*
G01X440402D02*
X443802D01*
G02Y1346684I0J-1503D01*
G01X440402D01*
G02Y1349690I0J1503D01*
G37*
G36*
G01Y1361602D02*
X443802D01*
G02Y1358596I0J-1503D01*
G01X440402D01*
G02Y1361602I0J1503D01*
G37*
G36*
G01Y1385800D02*
X443802D01*
G02Y1382794I0J-1503D01*
G01X440402D01*
G02Y1385800I0J1503D01*
G37*
G36*
G01Y1373888D02*
X443802D01*
G02Y1370882I0J-1503D01*
G01X440402D01*
G02Y1373888I0J1503D01*
G37*
G36*
G01X452642D02*
X456042D01*
G02Y1370882I0J-1503D01*
G01X452642D01*
G02Y1373888I0J1503D01*
G37*
G36*
G01Y1385800D02*
X456042D01*
G02Y1382794I0J-1503D01*
G01X452642D01*
G02Y1385800I0J1503D01*
G37*
G36*
G01Y1398086D02*
X456042D01*
G02Y1395080I0J-1503D01*
G01X452642D01*
G02Y1398086I0J1503D01*
G37*
G36*
G01Y1409998D02*
X456042D01*
G02Y1406992I0J-1503D01*
G01X452642D01*
G02Y1409998I0J1503D01*
G37*
G36*
G01X216125Y1441832D02*
X219525D01*
G02Y1438226I0J-1803D01*
G01X216125D01*
G02Y1441832I0J1803D01*
G37*
G36*
G01X413753Y1518690D02*
X417153D01*
G02Y1515084I0J-1803D01*
G01X413753D01*
G02Y1518690I0J1803D01*
G37*
G36*
G01X417334Y1475298D02*
X413934D01*
G02Y1478902I0J1802D01*
G01X417334D01*
G02Y1475298I0J-1802D01*
G37*
G36*
G01X416029Y1370070D02*
G02Y1373074I0J1502D01*
G02X417039Y1372683I-1J-1502D01*
G03X417041Y1372681I142J140D01*
G01X417068Y1372657D01*
X417138Y1372630D01*
X417448Y1372632D01*
G03X417583Y1372686I-2J200D01*
G02X418610Y1373092I1027J-1096D01*
G02Y1370088I0J-1502D01*
G02X417600Y1370479I1J1502D01*
G03X417598Y1370481I-142J-140D01*
G01X417571Y1370505D01*
X417501Y1370532D01*
X417191Y1370530D01*
G03X417056Y1370476I2J-200D01*
G02X416029Y1370070I-1027J1096D01*
G37*
G36*
G01X419698Y1417900D02*
G02X422702I1502J0D01*
G02X422370Y1416958I-1502J0D01*
G01X422347Y1416930D01*
X422324Y1416862D01*
X422336Y1416562D01*
G03X422391Y1416432I200J8D01*
G02X422802Y1415400I-1090J-1032D01*
G02X419798I-1502J0D01*
G02X420130Y1416342I1502J0D01*
G01X420153Y1416370D01*
X420176Y1416438D01*
X420164Y1416738D01*
G03X420109Y1416868I-200J-8D01*
G02X419698Y1417900I1090J1032D01*
G37*
G36*
G01X410154Y1461843D02*
Y1462157D01*
G03X410077Y1462315I-200J0D01*
G02X409498Y1463500I923J1185D01*
G02X412502I1502J0D01*
G02X411923Y1462315I-1502J0D01*
G03X411846Y1462157I123J-158D01*
G01Y1461843D01*
G03X411923Y1461685I200J0D01*
G02Y1459315I-923J-1185D01*
G03X411846Y1459157I123J-158D01*
G01Y1458843D01*
G03X411923Y1458685I200J0D01*
G02Y1456315I-923J-1185D01*
G03X411846Y1456157I123J-158D01*
G01Y1455843D01*
G03X411923Y1455685I200J0D01*
G02X412502Y1454500I-923J-1185D01*
G02X409498I-1502J0D01*
G02X410077Y1455685I1502J0D01*
G03X410154Y1455843I-123J158D01*
G01Y1456157D01*
G03X410077Y1456315I-200J0D01*
G02Y1458685I923J1185D01*
G03X410154Y1458843I-123J158D01*
G01Y1459157D01*
G03X410077Y1459315I-200J0D01*
G02Y1461685I923J1185D01*
G03X410154Y1461843I-123J158D01*
G37*
G36*
G01X186222Y1469155D02*
Y1470281D01*
G02X186425Y1470484I203J0D01*
G01X189245D01*
G02X189448Y1470281I0J-203D01*
G01Y1469155D01*
G03X189476Y1469052I200J-1D01*
G02Y1467090I-1642J-981D01*
G03X189448Y1466987I172J-102D01*
G01Y1464037D01*
G03X189476Y1463934I200J-1D01*
G02Y1461972I-1642J-981D01*
G03X189448Y1461869I172J-102D01*
G01Y1460743D01*
G02X189245Y1460540I-203J0D01*
G01X186425D01*
G02X186222Y1460743I0J203D01*
G01Y1461869D01*
G03X186194Y1461972I-200J1D01*
G02Y1463934I1642J981D01*
G03X186222Y1464037I-172J102D01*
G01Y1466987D01*
G03X186194Y1467090I-200J1D01*
G02Y1469052I1642J981D01*
G03X186222Y1469155I-172J102D01*
G37*
G36*
G01Y1484510D02*
Y1485636D01*
G02X186425Y1485838I203J-1D01*
G01X189245D01*
G02X189448Y1485636I1J-202D01*
G01Y1484510D01*
G03X189476Y1484407I200J-1D01*
G02Y1482445I-1642J-981D01*
G03X189448Y1482342I172J-102D01*
G01Y1479392D01*
G03X189476Y1479289I200J-1D01*
G02Y1477327I-1642J-981D01*
G03X189448Y1477224I172J-102D01*
G01Y1476098D01*
G02X189245Y1475896I-203J1D01*
G01X186425D01*
G02X186222Y1476098I-1J202D01*
G01Y1477224D01*
G03X186194Y1477327I-200J1D01*
G02Y1479289I1642J981D01*
G03X186222Y1479392I-172J102D01*
G01Y1482342D01*
G03X186194Y1482445I-200J1D01*
G02Y1484407I1642J981D01*
G03X186222Y1484510I-172J102D01*
G37*
G36*
G01Y1515218D02*
Y1516344D01*
G02X186425Y1516546I203J-1D01*
G01X189245D01*
G02X189448Y1516344I1J-202D01*
G01Y1515218D01*
G03X189476Y1515115I200J-1D01*
G02Y1513153I-1642J-981D01*
G03X189448Y1513050I172J-102D01*
G01Y1510100D01*
G03X189476Y1509997I200J-1D01*
G02Y1508035I-1642J-981D01*
G03X189448Y1507932I172J-102D01*
G01Y1506806D01*
G02X189245Y1506604I-203J1D01*
G01X186425D01*
G02X186222Y1506806I-1J202D01*
G01Y1507932D01*
G03X186194Y1508035I-200J1D01*
G02Y1509997I1642J981D01*
G03X186222Y1510100I-172J102D01*
G01Y1513050D01*
G03X186194Y1513153I-200J1D01*
G02Y1515115I1642J981D01*
G03X186222Y1515218I-172J102D01*
G37*
G36*
G01X392889Y1537786D02*
G02X395893I1502J0D01*
G02X395523Y1536799I-1501J0D01*
G01Y1536798D01*
X395522D01*
G03X395474Y1536668I152J-130D01*
G01Y1536404D01*
G03X395522Y1536274I200J0D01*
G01X395523Y1536273D01*
G02X395893Y1535286I-1131J-987D01*
G02X392889I-1502J0D01*
G02X393259Y1536273I1501J0D01*
G01Y1536274D01*
X393260D01*
G03X393308Y1536404I-152J130D01*
G01Y1536668D01*
G03X393260Y1536798I-200J0D01*
G01X393259Y1536799D01*
G02X392889Y1537786I1131J987D01*
G37*
G36*
G01X186222Y1571518D02*
Y1572644D01*
G02X186425Y1572846I203J-1D01*
G01X189245D01*
G02X189448Y1572644I1J-202D01*
G01Y1571518D01*
G03X189476Y1571415I200J-1D01*
G02Y1569453I-1642J-981D01*
G03X189448Y1569350I172J-102D01*
G01Y1566399D01*
G03X189476Y1566296I200J-1D01*
G02Y1564334I-1642J-981D01*
G03X189448Y1564231I172J-102D01*
G01Y1563106D01*
G02X189245Y1562904I-203J1D01*
G01X186425D01*
G02X186222Y1563106I-1J202D01*
G01Y1564231D01*
G03X186194Y1564334I-200J1D01*
G02Y1566296I1642J981D01*
G03X186222Y1566399I-172J102D01*
G01Y1569350D01*
G03X186194Y1569453I-200J1D01*
G02Y1571415I1642J981D01*
G03X186222Y1571518I-172J102D01*
G37*
G36*
G01X359450D02*
Y1572644D01*
G02X359653Y1572846I203J-1D01*
G01X362473D01*
G02X362676Y1572644I1J-202D01*
G01Y1571518D01*
G03X362704Y1571415I200J-1D01*
G02Y1569453I-1642J-981D01*
G03X362676Y1569350I172J-102D01*
G01Y1566399D01*
G03X362704Y1566296I200J-1D01*
G02Y1564334I-1642J-981D01*
G03X362676Y1564231I172J-102D01*
G01Y1563106D01*
G02X362473Y1562904I-203J1D01*
G01X359653D01*
G02X359450Y1563106I-1J202D01*
G01Y1564231D01*
G03X359422Y1564334I-200J1D01*
G02Y1566296I1642J981D01*
G03X359450Y1566399I-172J102D01*
G01Y1569350D01*
G03X359422Y1569453I-200J1D01*
G02Y1571415I1642J981D01*
G03X359450Y1571518I-172J102D01*
G37*
G36*
G01X454726Y1582541D02*
Y1583667D01*
G02X454929Y1583870I203J0D01*
G01X457749D01*
G02X457952Y1583667I0J-203D01*
G01Y1582541D01*
G03X457980Y1582438I200J-1D01*
G02Y1580476I-1642J-981D01*
G03X457952Y1580373I172J-102D01*
G01Y1577423D01*
G03X457980Y1577320I200J-1D01*
G02Y1575358I-1642J-981D01*
G03X457952Y1575255I172J-102D01*
G01Y1574129D01*
G02X457749Y1573926I-203J0D01*
G01X454929D01*
G02X454726Y1574129I0J203D01*
G01Y1575255D01*
G03X454698Y1575358I-200J1D01*
G02Y1577320I1642J981D01*
G03X454726Y1577423I-172J102D01*
G01Y1580373D01*
G03X454698Y1580476I-200J1D01*
G02Y1582438I1642J981D01*
G03X454726Y1582541I-172J102D01*
G37*
G36*
G01X463388Y1586872D02*
Y1587998D01*
G02X463590Y1588200I202J0D01*
G01X466410D01*
G02X466612Y1587998I0J-202D01*
G01Y1586872D01*
G03X466640Y1586769I200J-1D01*
G02X466912Y1585788I-1640J-983D01*
G02X466640Y1584807I-1912J2D01*
G03X466612Y1584704I172J-102D01*
G01Y1581754D01*
G03X466640Y1581651I200J-1D01*
G02X466912Y1580670I-1640J-983D01*
G02X466640Y1579689I-1912J2D01*
G03X466612Y1579586I172J-102D01*
G01Y1578460D01*
G02X466410Y1578258I-202J0D01*
G01X463590D01*
G02X463388Y1578460I0J202D01*
G01Y1579586D01*
G03X463360Y1579689I-200J1D01*
G02X463088Y1580670I1640J983D01*
G02X463360Y1581651I1912J-2D01*
G03X463388Y1581754I-172J102D01*
G01Y1584704D01*
G03X463360Y1584807I-200J1D01*
G02X463088Y1585788I1640J983D01*
G02X463360Y1586769I1912J-2D01*
G03X463388Y1586872I-172J102D01*
G37*
G36*
G01X480710D02*
Y1587998D01*
G02X480913Y1588200I203J-1D01*
G01X483733D01*
G02X483936Y1587998I1J-202D01*
G01Y1586872D01*
G03X483964Y1586769I200J-1D01*
G02Y1584807I-1642J-981D01*
G03X483936Y1584704I172J-102D01*
G01Y1581754D01*
G03X483964Y1581651I200J-1D01*
G02Y1579689I-1642J-981D01*
G03X483936Y1579586I172J-102D01*
G01Y1578460D01*
G02X483733Y1578258I-203J1D01*
G01X480913D01*
G02X480710Y1578460I-1J202D01*
G01Y1579586D01*
G03X480682Y1579689I-200J1D01*
G02Y1581651I1642J981D01*
G03X480710Y1581754I-172J102D01*
G01Y1584704D01*
G03X480682Y1584807I-200J1D01*
G02Y1586769I1642J981D01*
G03X480710Y1586872I-172J102D01*
G37*
G36*
G01X498034D02*
Y1587998D01*
G02X498236Y1588200I202J0D01*
G01X501056D01*
G02X501258Y1587998I0J-202D01*
G01Y1586872D01*
G03X501286Y1586769I200J-1D01*
G02X501558Y1585788I-1640J-983D01*
G02X501286Y1584807I-1912J2D01*
G03X501258Y1584704I172J-102D01*
G01Y1581754D01*
G03X501286Y1581651I200J-1D01*
G02X501558Y1580670I-1640J-983D01*
G02X501286Y1579689I-1912J2D01*
G03X501258Y1579586I172J-102D01*
G01Y1578460D01*
G02X501056Y1578258I-202J0D01*
G01X498236D01*
G02X498034Y1578460I0J202D01*
G01Y1579586D01*
G03X498006Y1579689I-200J1D01*
G02X497734Y1580670I1640J983D01*
G02X498006Y1581651I1912J-2D01*
G03X498034Y1581754I-172J102D01*
G01Y1584704D01*
G03X498006Y1584807I-200J1D01*
G02X497734Y1585788I1640J983D01*
G02X498006Y1586769I1912J-2D01*
G03X498034Y1586872I-172J102D01*
G37*
G36*
G01X515356D02*
Y1587998D01*
G02X515559Y1588200I203J-1D01*
G01X518379D01*
G02X518582Y1587998I1J-202D01*
G01Y1586872D01*
G03X518610Y1586769I200J-1D01*
G02Y1584807I-1642J-981D01*
G03X518582Y1584704I172J-102D01*
G01Y1581754D01*
G03X518610Y1581651I200J-1D01*
G02Y1579689I-1642J-981D01*
G03X518582Y1579586I172J-102D01*
G01Y1578460D01*
G02X518379Y1578258I-203J1D01*
G01X515559D01*
G02X515356Y1578460I-1J202D01*
G01Y1579586D01*
G03X515328Y1579689I-200J1D01*
G02Y1581651I1642J981D01*
G03X515356Y1581754I-172J102D01*
G01Y1584704D01*
G03X515328Y1584807I-200J1D01*
G02Y1586769I1642J981D01*
G03X515356Y1586872I-172J102D01*
G37*
G36*
G01X281498Y1597895D02*
Y1599021D01*
G02X281700Y1599224I202J1D01*
G01X284520D01*
G02X284722Y1599021I-1J-203D01*
G01Y1597895D01*
G03X284750Y1597792I200J-1D01*
G02X285022Y1596811I-1640J-983D01*
G02X284750Y1595830I-1912J2D01*
G03X284722Y1595727I172J-102D01*
G01Y1592777D01*
G03X284750Y1592674I200J-1D01*
G02X285022Y1591693I-1640J-983D01*
G02X284750Y1590712I-1912J2D01*
G03X284722Y1590609I172J-102D01*
G01Y1589483D01*
G02X284520Y1589280I-202J-1D01*
G01X281700D01*
G02X281498Y1589483I1J203D01*
G01Y1590609D01*
G03X281470Y1590712I-200J1D01*
G02X281198Y1591693I1640J983D01*
G02X281470Y1592674I1912J-2D01*
G03X281498Y1592777I-172J102D01*
G01Y1595727D01*
G03X281470Y1595830I-200J1D01*
G02X281198Y1596811I1640J983D01*
G02X281470Y1597792I1912J-2D01*
G03X281498Y1597895I-172J102D01*
G37*
G36*
G01X298820D02*
Y1599021D01*
G02X299023Y1599224I203J0D01*
G01X301843D01*
G02X302046Y1599021I0J-203D01*
G01Y1597895D01*
G03X302074Y1597792I200J-1D01*
G02Y1595830I-1642J-981D01*
G03X302046Y1595727I172J-102D01*
G01Y1592777D01*
G03X302074Y1592674I200J-1D01*
G02Y1590712I-1642J-981D01*
G03X302046Y1590609I172J-102D01*
G01Y1589483D01*
G02X301843Y1589280I-203J0D01*
G01X299023D01*
G02X298820Y1589483I0J203D01*
G01Y1590609D01*
G03X298792Y1590712I-200J1D01*
G02Y1592674I1642J981D01*
G03X298820Y1592777I-172J102D01*
G01Y1595727D01*
G03X298792Y1595830I-200J1D01*
G02Y1597792I1642J981D01*
G03X298820Y1597895I-172J102D01*
G37*
G36*
G01X316144D02*
Y1599021D01*
G02X316346Y1599224I202J1D01*
G01X319166D01*
G02X319368Y1599021I-1J-203D01*
G01Y1597895D01*
G03X319396Y1597792I200J-1D01*
G02X319668Y1596811I-1640J-983D01*
G02X319396Y1595830I-1912J2D01*
G03X319368Y1595727I172J-102D01*
G01Y1592777D01*
G03X319396Y1592674I200J-1D01*
G02X319668Y1591693I-1640J-983D01*
G02X319396Y1590712I-1912J2D01*
G03X319368Y1590609I172J-102D01*
G01Y1589483D01*
G02X319166Y1589280I-202J-1D01*
G01X316346D01*
G02X316144Y1589483I1J203D01*
G01Y1590609D01*
G03X316116Y1590712I-200J1D01*
G02X315844Y1591693I1640J983D01*
G02X316116Y1592674I1912J-2D01*
G03X316144Y1592777I-172J102D01*
G01Y1595727D01*
G03X316116Y1595830I-200J1D01*
G02X315844Y1596811I1640J983D01*
G02X316116Y1597792I1912J-2D01*
G03X316144Y1597895I-172J102D01*
G37*
G36*
G01X333466D02*
Y1599021D01*
G02X333668Y1599224I202J1D01*
G01X336488D01*
G02X336690Y1599021I-1J-203D01*
G01Y1597895D01*
G03X336718Y1597792I200J-1D01*
G02X336990Y1596811I-1640J-983D01*
G02X336718Y1595830I-1912J2D01*
G03X336690Y1595727I172J-102D01*
G01Y1592777D01*
G03X336718Y1592674I200J-1D01*
G02X336990Y1591693I-1640J-983D01*
G02X336718Y1590712I-1912J2D01*
G03X336690Y1590609I172J-102D01*
G01Y1589483D01*
G02X336488Y1589280I-202J-1D01*
G01X333668D01*
G02X333466Y1589483I1J203D01*
G01Y1590609D01*
G03X333438Y1590712I-200J1D01*
G02X333166Y1591693I1640J983D01*
G02X333438Y1592674I1912J-2D01*
G03X333466Y1592777I-172J102D01*
G01Y1595727D01*
G03X333438Y1595830I-200J1D01*
G02X333166Y1596811I1640J983D01*
G02X333438Y1597792I1912J-2D01*
G03X333466Y1597895I-172J102D01*
G37*
G36*
G01X454726D02*
Y1599021D01*
G02X454929Y1599224I203J0D01*
G01X457749D01*
G02X457952Y1599021I0J-203D01*
G01Y1597895D01*
G03X457980Y1597792I200J-1D01*
G02Y1595830I-1642J-981D01*
G03X457952Y1595727I172J-102D01*
G01Y1592777D01*
G03X457980Y1592674I200J-1D01*
G02Y1590712I-1642J-981D01*
G03X457952Y1590609I172J-102D01*
G01Y1589483D01*
G02X457749Y1589280I-203J0D01*
G01X454929D01*
G02X454726Y1589483I0J203D01*
G01Y1590609D01*
G03X454698Y1590712I-200J1D01*
G02Y1592674I1642J981D01*
G03X454726Y1592777I-172J102D01*
G01Y1595727D01*
G03X454698Y1595830I-200J1D01*
G02Y1597792I1642J981D01*
G03X454726Y1597895I-172J102D01*
G37*
G36*
G01X472050D02*
Y1599021D01*
G02X472252Y1599224I202J1D01*
G01X475072D01*
G02X475274Y1599021I-1J-203D01*
G01Y1597895D01*
G03X475302Y1597792I200J-1D01*
G02X475574Y1596811I-1640J-983D01*
G02X475302Y1595830I-1912J2D01*
G03X475274Y1595727I172J-102D01*
G01Y1592777D01*
G03X475302Y1592674I200J-1D01*
G02X475574Y1591693I-1640J-983D01*
G02X475302Y1590712I-1912J2D01*
G03X475274Y1590609I172J-102D01*
G01Y1589483D01*
G02X475072Y1589280I-202J-1D01*
G01X472252D01*
G02X472050Y1589483I1J203D01*
G01Y1590609D01*
G03X472022Y1590712I-200J1D01*
G02X471750Y1591693I1640J983D01*
G02X472022Y1592674I1912J-2D01*
G03X472050Y1592777I-172J102D01*
G01Y1595727D01*
G03X472022Y1595830I-200J1D01*
G02X471750Y1596811I1640J983D01*
G02X472022Y1597792I1912J-2D01*
G03X472050Y1597895I-172J102D01*
G37*
G36*
G01X489372D02*
Y1599021D01*
G02X489575Y1599224I203J0D01*
G01X492395D01*
G02X492598Y1599021I0J-203D01*
G01Y1597895D01*
G03X492626Y1597792I200J-1D01*
G02Y1595830I-1642J-981D01*
G03X492598Y1595727I172J-102D01*
G01Y1592777D01*
G03X492626Y1592674I200J-1D01*
G02Y1590712I-1642J-981D01*
G03X492598Y1590609I172J-102D01*
G01Y1589483D01*
G02X492395Y1589280I-203J0D01*
G01X489575D01*
G02X489372Y1589483I0J203D01*
G01Y1590609D01*
G03X489344Y1590712I-200J1D01*
G02Y1592674I1642J981D01*
G03X489372Y1592777I-172J102D01*
G01Y1595727D01*
G03X489344Y1595830I-200J1D01*
G02Y1597792I1642J981D01*
G03X489372Y1597895I-172J102D01*
G37*
G36*
G01X506694D02*
Y1599021D01*
G02X506897Y1599224I203J0D01*
G01X509717D01*
G02X509920Y1599021I0J-203D01*
G01Y1597895D01*
G03X509948Y1597792I200J-1D01*
G02Y1595830I-1642J-981D01*
G03X509920Y1595727I172J-102D01*
G01Y1592777D01*
G03X509948Y1592674I200J-1D01*
G02Y1590712I-1642J-981D01*
G03X509920Y1590609I172J-102D01*
G01Y1589483D01*
G02X509717Y1589280I-203J0D01*
G01X506897D01*
G02X506694Y1589483I0J203D01*
G01Y1590609D01*
G03X506666Y1590712I-200J1D01*
G02Y1592674I1642J981D01*
G03X506694Y1592777I-172J102D01*
G01Y1595727D01*
G03X506666Y1595830I-200J1D01*
G02Y1597792I1642J981D01*
G03X506694Y1597895I-172J102D01*
G37*
G36*
G01X186222Y1602226D02*
Y1603352D01*
G02X186425Y1603554I203J-1D01*
G01X189245D01*
G02X189448Y1603352I1J-202D01*
G01Y1602226D01*
G03X189476Y1602123I200J-1D01*
G02Y1600161I-1642J-981D01*
G03X189448Y1600058I172J-102D01*
G01Y1597108D01*
G03X189476Y1597005I200J-1D01*
G02Y1595043I-1642J-981D01*
G03X189448Y1594940I172J-102D01*
G01Y1593814D01*
G02X189245Y1593612I-203J1D01*
G01X186425D01*
G02X186222Y1593814I-1J202D01*
G01Y1594940D01*
G03X186194Y1595043I-200J1D01*
G02Y1597005I1642J981D01*
G03X186222Y1597108I-172J102D01*
G01Y1600058D01*
G03X186194Y1600161I-200J1D01*
G02Y1602123I1642J981D01*
G03X186222Y1602226I-172J102D01*
G37*
G36*
G01X290158D02*
Y1603352D01*
G02X290361Y1603554I203J-1D01*
G01X293181D01*
G02X293384Y1603352I1J-202D01*
G01Y1602226D01*
G03X293412Y1602123I200J-1D01*
G02Y1600161I-1642J-981D01*
G03X293384Y1600058I172J-102D01*
G01Y1597108D01*
G03X293412Y1597005I200J-1D01*
G02Y1595043I-1642J-981D01*
G03X293384Y1594940I172J-102D01*
G01Y1593814D01*
G02X293181Y1593612I-203J1D01*
G01X290361D01*
G02X290158Y1593814I-1J202D01*
G01Y1594940D01*
G03X290130Y1595043I-200J1D01*
G02Y1597005I1642J981D01*
G03X290158Y1597108I-172J102D01*
G01Y1600058D01*
G03X290130Y1600161I-200J1D01*
G02Y1602123I1642J981D01*
G03X290158Y1602226I-172J102D01*
G37*
G36*
G01X307482D02*
Y1603352D01*
G02X307684Y1603554I202J0D01*
G01X310504D01*
G02X310706Y1603352I0J-202D01*
G01Y1602226D01*
G03X310734Y1602123I200J-1D01*
G02X311006Y1601142I-1640J-983D01*
G02X310734Y1600161I-1912J2D01*
G03X310706Y1600058I172J-102D01*
G01Y1597108D01*
G03X310734Y1597005I200J-1D01*
G02X311006Y1596024I-1640J-983D01*
G02X310734Y1595043I-1912J2D01*
G03X310706Y1594940I172J-102D01*
G01Y1593814D01*
G02X310504Y1593612I-202J0D01*
G01X307684D01*
G02X307482Y1593814I0J202D01*
G01Y1594940D01*
G03X307454Y1595043I-200J1D01*
G02X307182Y1596024I1640J983D01*
G02X307454Y1597005I1912J-2D01*
G03X307482Y1597108I-172J102D01*
G01Y1600058D01*
G03X307454Y1600161I-200J1D01*
G02X307182Y1601142I1640J983D01*
G02X307454Y1602123I1912J-2D01*
G03X307482Y1602226I-172J102D01*
G37*
G36*
G01X324804D02*
Y1603352D01*
G02X325007Y1603554I203J-1D01*
G01X327827D01*
G02X328030Y1603352I1J-202D01*
G01Y1602226D01*
G03X328058Y1602123I200J-1D01*
G02Y1600161I-1642J-981D01*
G03X328030Y1600058I172J-102D01*
G01Y1597108D01*
G03X328058Y1597005I200J-1D01*
G02Y1595043I-1642J-981D01*
G03X328030Y1594940I172J-102D01*
G01Y1593814D01*
G02X327827Y1593612I-203J1D01*
G01X325007D01*
G02X324804Y1593814I-1J202D01*
G01Y1594940D01*
G03X324776Y1595043I-200J1D01*
G02Y1597005I1642J981D01*
G03X324804Y1597108I-172J102D01*
G01Y1600058D01*
G03X324776Y1600161I-200J1D01*
G02Y1602123I1642J981D01*
G03X324804Y1602226I-172J102D01*
G37*
G36*
G01X342128D02*
Y1603352D01*
G02X342330Y1603554I202J0D01*
G01X345150D01*
G02X345352Y1603352I0J-202D01*
G01Y1602226D01*
G03X345380Y1602123I200J-1D01*
G02X345652Y1601142I-1640J-983D01*
G02X345380Y1600161I-1912J2D01*
G03X345352Y1600058I172J-102D01*
G01Y1597108D01*
G03X345380Y1597005I200J-1D01*
G02X345652Y1596024I-1640J-983D01*
G02X345380Y1595043I-1912J2D01*
G03X345352Y1594940I172J-102D01*
G01Y1593814D01*
G02X345150Y1593612I-202J0D01*
G01X342330D01*
G02X342128Y1593814I0J202D01*
G01Y1594940D01*
G03X342100Y1595043I-200J1D01*
G02X341828Y1596024I1640J983D01*
G02X342100Y1597005I1912J-2D01*
G03X342128Y1597108I-172J102D01*
G01Y1600058D01*
G03X342100Y1600161I-200J1D01*
G02X341828Y1601142I1640J983D01*
G02X342100Y1602123I1912J-2D01*
G03X342128Y1602226I-172J102D01*
G37*
G36*
G01X359450D02*
Y1603352D01*
G02X359653Y1603554I203J-1D01*
G01X362473D01*
G02X362676Y1603352I1J-202D01*
G01Y1602226D01*
G03X362704Y1602123I200J-1D01*
G02Y1600161I-1642J-981D01*
G03X362676Y1600058I172J-102D01*
G01Y1597108D01*
G03X362704Y1597005I200J-1D01*
G02Y1595043I-1642J-981D01*
G03X362676Y1594940I172J-102D01*
G01Y1593814D01*
G02X362473Y1593612I-203J1D01*
G01X359653D01*
G02X359450Y1593814I-1J202D01*
G01Y1594940D01*
G03X359422Y1595043I-200J1D01*
G02Y1597005I1642J981D01*
G03X359450Y1597108I-172J102D01*
G01Y1600058D01*
G03X359422Y1600161I-200J1D01*
G02Y1602123I1642J981D01*
G03X359450Y1602226I-172J102D01*
G37*
G36*
G01X463388D02*
Y1603352D01*
G02X463590Y1603554I202J0D01*
G01X466410D01*
G02X466612Y1603352I0J-202D01*
G01Y1602226D01*
G03X466640Y1602123I200J-1D01*
G02X466912Y1601142I-1640J-983D01*
G02X466640Y1600161I-1912J2D01*
G03X466612Y1600058I172J-102D01*
G01Y1597108D01*
G03X466640Y1597005I200J-1D01*
G02X466912Y1596024I-1640J-983D01*
G02X466640Y1595043I-1912J2D01*
G03X466612Y1594940I172J-102D01*
G01Y1593814D01*
G02X466410Y1593612I-202J0D01*
G01X463590D01*
G02X463388Y1593814I0J202D01*
G01Y1594940D01*
G03X463360Y1595043I-200J1D01*
G02X463088Y1596024I1640J983D01*
G02X463360Y1597005I1912J-2D01*
G03X463388Y1597108I-172J102D01*
G01Y1600058D01*
G03X463360Y1600161I-200J1D01*
G02X463088Y1601142I1640J983D01*
G02X463360Y1602123I1912J-2D01*
G03X463388Y1602226I-172J102D01*
G37*
G36*
G01X480710D02*
Y1603352D01*
G02X480913Y1603554I203J-1D01*
G01X483733D01*
G02X483936Y1603352I1J-202D01*
G01Y1602226D01*
G03X483964Y1602123I200J-1D01*
G02Y1600161I-1642J-981D01*
G03X483936Y1600058I172J-102D01*
G01Y1597108D01*
G03X483964Y1597005I200J-1D01*
G02Y1595043I-1642J-981D01*
G03X483936Y1594940I172J-102D01*
G01Y1593814D01*
G02X483733Y1593612I-203J1D01*
G01X480913D01*
G02X480710Y1593814I-1J202D01*
G01Y1594940D01*
G03X480682Y1595043I-200J1D01*
G02Y1597005I1642J981D01*
G03X480710Y1597108I-172J102D01*
G01Y1600058D01*
G03X480682Y1600161I-200J1D01*
G02Y1602123I1642J981D01*
G03X480710Y1602226I-172J102D01*
G37*
G36*
G01X498034D02*
Y1603352D01*
G02X498236Y1603554I202J0D01*
G01X501056D01*
G02X501258Y1603352I0J-202D01*
G01Y1602226D01*
G03X501286Y1602123I200J-1D01*
G02X501558Y1601142I-1640J-983D01*
G02X501286Y1600161I-1912J2D01*
G03X501258Y1600058I172J-102D01*
G01Y1597108D01*
G03X501286Y1597005I200J-1D01*
G02X501558Y1596024I-1640J-983D01*
G02X501286Y1595043I-1912J2D01*
G03X501258Y1594940I172J-102D01*
G01Y1593814D01*
G02X501056Y1593612I-202J0D01*
G01X498236D01*
G02X498034Y1593814I0J202D01*
G01Y1594940D01*
G03X498006Y1595043I-200J1D01*
G02X497734Y1596024I1640J983D01*
G02X498006Y1597005I1912J-2D01*
G03X498034Y1597108I-172J102D01*
G01Y1600058D01*
G03X498006Y1600161I-200J1D01*
G02X497734Y1601142I1640J983D01*
G02X498006Y1602123I1912J-2D01*
G03X498034Y1602226I-172J102D01*
G37*
G36*
G01X515356D02*
Y1603352D01*
G02X515559Y1603554I203J-1D01*
G01X518379D01*
G02X518582Y1603352I1J-202D01*
G01Y1602226D01*
G03X518610Y1602123I200J-1D01*
G02Y1600161I-1642J-981D01*
G03X518582Y1600058I172J-102D01*
G01Y1597108D01*
G03X518610Y1597005I200J-1D01*
G02Y1595043I-1642J-981D01*
G03X518582Y1594940I172J-102D01*
G01Y1593814D01*
G02X518379Y1593612I-203J1D01*
G01X515559D01*
G02X515356Y1593814I-1J202D01*
G01Y1594940D01*
G03X515328Y1595043I-200J1D01*
G02Y1597005I1642J981D01*
G03X515356Y1597108I-172J102D01*
G01Y1600058D01*
G03X515328Y1600161I-200J1D01*
G02Y1602123I1642J981D01*
G03X515356Y1602226I-172J102D01*
G37*
G36*
G01X281498Y1613250D02*
Y1614376D01*
G02X281700Y1614578I202J0D01*
G01X284520D01*
G02X284722Y1614376I0J-202D01*
G01Y1613250D01*
G03X284750Y1613147I200J-1D01*
G02X285022Y1612166I-1640J-983D01*
G02X284750Y1611185I-1912J2D01*
G03X284722Y1611082I172J-102D01*
G01Y1608132D01*
G03X284750Y1608029I200J-1D01*
G02X285022Y1607048I-1640J-983D01*
G02X284750Y1606067I-1912J2D01*
G03X284722Y1605964I172J-102D01*
G01Y1604838D01*
G02X284520Y1604636I-202J0D01*
G01X281700D01*
G02X281498Y1604838I0J202D01*
G01Y1605964D01*
G03X281470Y1606067I-200J1D01*
G02X281198Y1607048I1640J983D01*
G02X281470Y1608029I1912J-2D01*
G03X281498Y1608132I-172J102D01*
G01Y1611082D01*
G03X281470Y1611185I-200J1D01*
G02X281198Y1612166I1640J983D01*
G02X281470Y1613147I1912J-2D01*
G03X281498Y1613250I-172J102D01*
G37*
G36*
G01X298820D02*
Y1614376D01*
G02X299023Y1614578I203J-1D01*
G01X301843D01*
G02X302046Y1614376I1J-202D01*
G01Y1613250D01*
G03X302074Y1613147I200J-1D01*
G02Y1611185I-1642J-981D01*
G03X302046Y1611082I172J-102D01*
G01Y1608132D01*
G03X302074Y1608029I200J-1D01*
G02Y1606067I-1642J-981D01*
G03X302046Y1605964I172J-102D01*
G01Y1604838D01*
G02X301843Y1604636I-203J1D01*
G01X299023D01*
G02X298820Y1604838I-1J202D01*
G01Y1605964D01*
G03X298792Y1606067I-200J1D01*
G02Y1608029I1642J981D01*
G03X298820Y1608132I-172J102D01*
G01Y1611082D01*
G03X298792Y1611185I-200J1D01*
G02Y1613147I1642J981D01*
G03X298820Y1613250I-172J102D01*
G37*
G36*
G01X316144D02*
Y1614376D01*
G02X316346Y1614578I202J0D01*
G01X319166D01*
G02X319368Y1614376I0J-202D01*
G01Y1613250D01*
G03X319396Y1613147I200J-1D01*
G02X319668Y1612166I-1640J-983D01*
G02X319396Y1611185I-1912J2D01*
G03X319368Y1611082I172J-102D01*
G01Y1608132D01*
G03X319396Y1608029I200J-1D01*
G02X319668Y1607048I-1640J-983D01*
G02X319396Y1606067I-1912J2D01*
G03X319368Y1605964I172J-102D01*
G01Y1604838D01*
G02X319166Y1604636I-202J0D01*
G01X316346D01*
G02X316144Y1604838I0J202D01*
G01Y1605964D01*
G03X316116Y1606067I-200J1D01*
G02X315844Y1607048I1640J983D01*
G02X316116Y1608029I1912J-2D01*
G03X316144Y1608132I-172J102D01*
G01Y1611082D01*
G03X316116Y1611185I-200J1D01*
G02X315844Y1612166I1640J983D01*
G02X316116Y1613147I1912J-2D01*
G03X316144Y1613250I-172J102D01*
G37*
G36*
G01X333466D02*
Y1614376D01*
G02X333668Y1614578I202J0D01*
G01X336488D01*
G02X336690Y1614376I0J-202D01*
G01Y1613250D01*
G03X336718Y1613147I200J-1D01*
G02X336990Y1612166I-1640J-983D01*
G02X336718Y1611185I-1912J2D01*
G03X336690Y1611082I172J-102D01*
G01Y1608132D01*
G03X336718Y1608029I200J-1D01*
G02X336990Y1607048I-1640J-983D01*
G02X336718Y1606067I-1912J2D01*
G03X336690Y1605964I172J-102D01*
G01Y1604838D01*
G02X336488Y1604636I-202J0D01*
G01X333668D01*
G02X333466Y1604838I0J202D01*
G01Y1605964D01*
G03X333438Y1606067I-200J1D01*
G02X333166Y1607048I1640J983D01*
G02X333438Y1608029I1912J-2D01*
G03X333466Y1608132I-172J102D01*
G01Y1611082D01*
G03X333438Y1611185I-200J1D01*
G02X333166Y1612166I1640J983D01*
G02X333438Y1613147I1912J-2D01*
G03X333466Y1613250I-172J102D01*
G37*
G36*
G01X454726D02*
Y1614376D01*
G02X454929Y1614578I203J-1D01*
G01X457749D01*
G02X457952Y1614376I1J-202D01*
G01Y1613250D01*
G03X457980Y1613147I200J-1D01*
G02Y1611185I-1642J-981D01*
G03X457952Y1611082I172J-102D01*
G01Y1608132D01*
G03X457980Y1608029I200J-1D01*
G02Y1606067I-1642J-981D01*
G03X457952Y1605964I172J-102D01*
G01Y1604838D01*
G02X457749Y1604636I-203J1D01*
G01X454929D01*
G02X454726Y1604838I-1J202D01*
G01Y1605964D01*
G03X454698Y1606067I-200J1D01*
G02Y1608029I1642J981D01*
G03X454726Y1608132I-172J102D01*
G01Y1611082D01*
G03X454698Y1611185I-200J1D01*
G02Y1613147I1642J981D01*
G03X454726Y1613250I-172J102D01*
G37*
G36*
G01X472050D02*
Y1614376D01*
G02X472252Y1614578I202J0D01*
G01X475072D01*
G02X475274Y1614376I0J-202D01*
G01Y1613250D01*
G03X475302Y1613147I200J-1D01*
G02X475574Y1612166I-1640J-983D01*
G02X475302Y1611185I-1912J2D01*
G03X475274Y1611082I172J-102D01*
G01Y1608132D01*
G03X475302Y1608029I200J-1D01*
G02X475574Y1607048I-1640J-983D01*
G02X475302Y1606067I-1912J2D01*
G03X475274Y1605964I172J-102D01*
G01Y1604838D01*
G02X475072Y1604636I-202J0D01*
G01X472252D01*
G02X472050Y1604838I0J202D01*
G01Y1605964D01*
G03X472022Y1606067I-200J1D01*
G02X471750Y1607048I1640J983D01*
G02X472022Y1608029I1912J-2D01*
G03X472050Y1608132I-172J102D01*
G01Y1611082D01*
G03X472022Y1611185I-200J1D01*
G02X471750Y1612166I1640J983D01*
G02X472022Y1613147I1912J-2D01*
G03X472050Y1613250I-172J102D01*
G37*
G36*
G01X489372D02*
Y1614376D01*
G02X489575Y1614578I203J-1D01*
G01X492395D01*
G02X492598Y1614376I1J-202D01*
G01Y1613250D01*
G03X492626Y1613147I200J-1D01*
G02Y1611185I-1642J-981D01*
G03X492598Y1611082I172J-102D01*
G01Y1608132D01*
G03X492626Y1608029I200J-1D01*
G02Y1606067I-1642J-981D01*
G03X492598Y1605964I172J-102D01*
G01Y1604838D01*
G02X492395Y1604636I-203J1D01*
G01X489575D01*
G02X489372Y1604838I-1J202D01*
G01Y1605964D01*
G03X489344Y1606067I-200J1D01*
G02Y1608029I1642J981D01*
G03X489372Y1608132I-172J102D01*
G01Y1611082D01*
G03X489344Y1611185I-200J1D01*
G02Y1613147I1642J981D01*
G03X489372Y1613250I-172J102D01*
G37*
G36*
G01X506694D02*
Y1614376D01*
G02X506897Y1614578I203J-1D01*
G01X509717D01*
G02X509920Y1614376I1J-202D01*
G01Y1613250D01*
G03X509948Y1613147I200J-1D01*
G02Y1611185I-1642J-981D01*
G03X509920Y1611082I172J-102D01*
G01Y1608132D01*
G03X509948Y1608029I200J-1D01*
G02Y1606067I-1642J-981D01*
G03X509920Y1605964I172J-102D01*
G01Y1604838D01*
G02X509717Y1604636I-203J1D01*
G01X506897D01*
G02X506694Y1604838I-1J202D01*
G01Y1605964D01*
G03X506666Y1606067I-200J1D01*
G02Y1608029I1642J981D01*
G03X506694Y1608132I-172J102D01*
G01Y1611082D01*
G03X506666Y1611185I-200J1D01*
G02Y1613147I1642J981D01*
G03X506694Y1613250I-172J102D01*
G37*
G36*
G01X186222Y1617580D02*
Y1618706D01*
G02X186425Y1618908I203J-1D01*
G01X189245D01*
G02X189448Y1618706I1J-202D01*
G01Y1617580D01*
G03X189476Y1617477I200J-1D01*
G02Y1615515I-1642J-981D01*
G03X189448Y1615412I172J-102D01*
G01Y1612462D01*
G03X189476Y1612359I200J-1D01*
G02Y1610397I-1642J-981D01*
G03X189448Y1610294I172J-102D01*
G01Y1609168D01*
G02X189245Y1608966I-203J1D01*
G01X186425D01*
G02X186222Y1609168I-1J202D01*
G01Y1610294D01*
G03X186194Y1610397I-200J1D01*
G02Y1612359I1642J981D01*
G03X186222Y1612462I-172J102D01*
G01Y1615412D01*
G03X186194Y1615515I-200J1D01*
G02Y1617477I1642J981D01*
G03X186222Y1617580I-172J102D01*
G37*
G36*
G01X290158D02*
Y1618706D01*
G02X290361Y1618908I203J-1D01*
G01X293181D01*
G02X293384Y1618706I1J-202D01*
G01Y1617580D01*
G03X293412Y1617477I200J-1D01*
G02Y1615515I-1642J-981D01*
G03X293384Y1615412I172J-102D01*
G01Y1612462D01*
G03X293412Y1612359I200J-1D01*
G02Y1610397I-1642J-981D01*
G03X293384Y1610294I172J-102D01*
G01Y1609168D01*
G02X293181Y1608966I-203J1D01*
G01X290361D01*
G02X290158Y1609168I-1J202D01*
G01Y1610294D01*
G03X290130Y1610397I-200J1D01*
G02Y1612359I1642J981D01*
G03X290158Y1612462I-172J102D01*
G01Y1615412D01*
G03X290130Y1615515I-200J1D01*
G02Y1617477I1642J981D01*
G03X290158Y1617580I-172J102D01*
G37*
G36*
G01X307482D02*
Y1618706D01*
G02X307684Y1618908I202J0D01*
G01X310504D01*
G02X310706Y1618706I0J-202D01*
G01Y1617580D01*
G03X310734Y1617477I200J-1D01*
G02X311006Y1616496I-1640J-983D01*
G02X310734Y1615515I-1912J2D01*
G03X310706Y1615412I172J-102D01*
G01Y1612462D01*
G03X310734Y1612359I200J-1D01*
G02X311006Y1611378I-1640J-983D01*
G02X310734Y1610397I-1912J2D01*
G03X310706Y1610294I172J-102D01*
G01Y1609168D01*
G02X310504Y1608966I-202J0D01*
G01X307684D01*
G02X307482Y1609168I0J202D01*
G01Y1610294D01*
G03X307454Y1610397I-200J1D01*
G02X307182Y1611378I1640J983D01*
G02X307454Y1612359I1912J-2D01*
G03X307482Y1612462I-172J102D01*
G01Y1615412D01*
G03X307454Y1615515I-200J1D01*
G02X307182Y1616496I1640J983D01*
G02X307454Y1617477I1912J-2D01*
G03X307482Y1617580I-172J102D01*
G37*
G36*
G01X324804D02*
Y1618706D01*
G02X325007Y1618908I203J-1D01*
G01X327827D01*
G02X328030Y1618706I1J-202D01*
G01Y1617580D01*
G03X328058Y1617477I200J-1D01*
G02Y1615515I-1642J-981D01*
G03X328030Y1615412I172J-102D01*
G01Y1612462D01*
G03X328058Y1612359I200J-1D01*
G02Y1610397I-1642J-981D01*
G03X328030Y1610294I172J-102D01*
G01Y1609168D01*
G02X327827Y1608966I-203J1D01*
G01X325007D01*
G02X324804Y1609168I-1J202D01*
G01Y1610294D01*
G03X324776Y1610397I-200J1D01*
G02Y1612359I1642J981D01*
G03X324804Y1612462I-172J102D01*
G01Y1615412D01*
G03X324776Y1615515I-200J1D01*
G02Y1617477I1642J981D01*
G03X324804Y1617580I-172J102D01*
G37*
G36*
G01X342128D02*
Y1618706D01*
G02X342330Y1618908I202J0D01*
G01X345150D01*
G02X345352Y1618706I0J-202D01*
G01Y1617580D01*
G03X345380Y1617477I200J-1D01*
G02X345652Y1616496I-1640J-983D01*
G02X345380Y1615515I-1912J2D01*
G03X345352Y1615412I172J-102D01*
G01Y1612462D01*
G03X345380Y1612359I200J-1D01*
G02X345652Y1611378I-1640J-983D01*
G02X345380Y1610397I-1912J2D01*
G03X345352Y1610294I172J-102D01*
G01Y1609168D01*
G02X345150Y1608966I-202J0D01*
G01X342330D01*
G02X342128Y1609168I0J202D01*
G01Y1610294D01*
G03X342100Y1610397I-200J1D01*
G02X341828Y1611378I1640J983D01*
G02X342100Y1612359I1912J-2D01*
G03X342128Y1612462I-172J102D01*
G01Y1615412D01*
G03X342100Y1615515I-200J1D01*
G02X341828Y1616496I1640J983D01*
G02X342100Y1617477I1912J-2D01*
G03X342128Y1617580I-172J102D01*
G37*
G36*
G01X359450D02*
Y1618706D01*
G02X359653Y1618908I203J-1D01*
G01X362473D01*
G02X362676Y1618706I1J-202D01*
G01Y1617580D01*
G03X362704Y1617477I200J-1D01*
G02Y1615515I-1642J-981D01*
G03X362676Y1615412I172J-102D01*
G01Y1612462D01*
G03X362704Y1612359I200J-1D01*
G02Y1610397I-1642J-981D01*
G03X362676Y1610294I172J-102D01*
G01Y1609168D01*
G02X362473Y1608966I-203J1D01*
G01X359653D01*
G02X359450Y1609168I-1J202D01*
G01Y1610294D01*
G03X359422Y1610397I-200J1D01*
G02Y1612359I1642J981D01*
G03X359450Y1612462I-172J102D01*
G01Y1615412D01*
G03X359422Y1615515I-200J1D01*
G02Y1617477I1642J981D01*
G03X359450Y1617580I-172J102D01*
G37*
G36*
G01X463388D02*
Y1618706D01*
G02X463590Y1618908I202J0D01*
G01X466410D01*
G02X466612Y1618706I0J-202D01*
G01Y1617580D01*
G03X466640Y1617477I200J-1D01*
G02X466912Y1616496I-1640J-983D01*
G02X466640Y1615515I-1912J2D01*
G03X466612Y1615412I172J-102D01*
G01Y1612462D01*
G03X466640Y1612359I200J-1D01*
G02X466912Y1611378I-1640J-983D01*
G02X466640Y1610397I-1912J2D01*
G03X466612Y1610294I172J-102D01*
G01Y1609168D01*
G02X466410Y1608966I-202J0D01*
G01X463590D01*
G02X463388Y1609168I0J202D01*
G01Y1610294D01*
G03X463360Y1610397I-200J1D01*
G02X463088Y1611378I1640J983D01*
G02X463360Y1612359I1912J-2D01*
G03X463388Y1612462I-172J102D01*
G01Y1615412D01*
G03X463360Y1615515I-200J1D01*
G02X463088Y1616496I1640J983D01*
G02X463360Y1617477I1912J-2D01*
G03X463388Y1617580I-172J102D01*
G37*
G36*
G01X480710D02*
Y1618706D01*
G02X480913Y1618908I203J-1D01*
G01X483733D01*
G02X483936Y1618706I1J-202D01*
G01Y1617580D01*
G03X483964Y1617477I200J-1D01*
G02Y1615515I-1642J-981D01*
G03X483936Y1615412I172J-102D01*
G01Y1612462D01*
G03X483964Y1612359I200J-1D01*
G02Y1610397I-1642J-981D01*
G03X483936Y1610294I172J-102D01*
G01Y1609168D01*
G02X483733Y1608966I-203J1D01*
G01X480913D01*
G02X480710Y1609168I-1J202D01*
G01Y1610294D01*
G03X480682Y1610397I-200J1D01*
G02Y1612359I1642J981D01*
G03X480710Y1612462I-172J102D01*
G01Y1615412D01*
G03X480682Y1615515I-200J1D01*
G02Y1617477I1642J981D01*
G03X480710Y1617580I-172J102D01*
G37*
G36*
G01X498034D02*
Y1618706D01*
G02X498236Y1618908I202J0D01*
G01X501056D01*
G02X501258Y1618706I0J-202D01*
G01Y1617580D01*
G03X501286Y1617477I200J-1D01*
G02X501558Y1616496I-1640J-983D01*
G02X501286Y1615515I-1912J2D01*
G03X501258Y1615412I172J-102D01*
G01Y1612462D01*
G03X501286Y1612359I200J-1D01*
G02X501558Y1611378I-1640J-983D01*
G02X501286Y1610397I-1912J2D01*
G03X501258Y1610294I172J-102D01*
G01Y1609168D01*
G02X501056Y1608966I-202J0D01*
G01X498236D01*
G02X498034Y1609168I0J202D01*
G01Y1610294D01*
G03X498006Y1610397I-200J1D01*
G02X497734Y1611378I1640J983D01*
G02X498006Y1612359I1912J-2D01*
G03X498034Y1612462I-172J102D01*
G01Y1615412D01*
G03X498006Y1615515I-200J1D01*
G02X497734Y1616496I1640J983D01*
G02X498006Y1617477I1912J-2D01*
G03X498034Y1617580I-172J102D01*
G37*
G36*
G01X515356D02*
Y1618706D01*
G02X515559Y1618908I203J-1D01*
G01X518379D01*
G02X518582Y1618706I1J-202D01*
G01Y1617580D01*
G03X518610Y1617477I200J-1D01*
G02Y1615515I-1642J-981D01*
G03X518582Y1615412I172J-102D01*
G01Y1612462D01*
G03X518610Y1612359I200J-1D01*
G02Y1610397I-1642J-981D01*
G03X518582Y1610294I172J-102D01*
G01Y1609168D01*
G02X518379Y1608966I-203J1D01*
G01X515559D01*
G02X515356Y1609168I-1J202D01*
G01Y1610294D01*
G03X515328Y1610397I-200J1D01*
G02Y1612359I1642J981D01*
G03X515356Y1612462I-172J102D01*
G01Y1615412D01*
G03X515328Y1615515I-200J1D01*
G02Y1617477I1642J981D01*
G03X515356Y1617580I-172J102D01*
G37*
G36*
G01X425169Y1359159D02*
G02X424353Y1360495I686J1336D01*
G02X427357I1502J0D01*
G02X426586Y1359183I-1502J0D01*
G03X426598Y1358477I194J-350D01*
G02X427414Y1357141I-686J-1336D01*
G02X424410I-1502J0D01*
G02X425181Y1358453I1502J0D01*
G03X425169Y1359159I-194J350D01*
G37*
G36*
G01X421227Y1400490D02*
G02X424231I1502J0D01*
G02X423814Y1399451I-1503J0D01*
G03X423760Y1399281I144J-139D01*
G01X423810Y1398967D01*
G03X423913Y1398822I197J31D01*
G02X424702Y1397500I-713J-1322D01*
G02X424197Y1396377I-1501J0D01*
G01X424162Y1396346D01*
X424127Y1396261D01*
X424152Y1395898D01*
G03X424239Y1395746I199J13D01*
G02X424902Y1394500I-839J-1246D01*
G02X421898I-1502J0D01*
G02X422403Y1395623I1501J0D01*
G01X422438Y1395654D01*
X422473Y1395739D01*
X422448Y1396102D01*
G03X422361Y1396254I-199J-13D01*
G02X421698Y1397500I839J1246D01*
G02X422115Y1398539I1503J0D01*
G03X422169Y1398709I-144J139D01*
G01X422119Y1399023D01*
G03X422016Y1399168I-197J-31D01*
G02X421227Y1400490I713J1322D01*
G37*
G36*
G01X418350Y1400899D02*
G02X417598Y1402200I749J1301D01*
G02X420602I1502J0D01*
G02X419807Y1400875I-1502J0D01*
G03X419795Y1400175I188J-353D01*
G02X420547Y1398874I-749J-1301D01*
G02X417543I-1502J0D01*
G02X418338Y1400199I1502J0D01*
G03X418350Y1400899I-188J353D01*
G37*
G36*
G01X394483Y1449492D02*
G02X394386Y1450022I1405J531D01*
G02X395888Y1448520I1502J0D01*
G02X395764Y1448525I-2J1502D01*
G03X395356Y1447985I-34J-399D01*
G02X395453Y1447455I-1405J-531D01*
G02X393951Y1448957I-1502J0D01*
G02X394075Y1448952I2J-1502D01*
G03X394483Y1449492I34J399D01*
G37*
G36*
G01X409513Y1451212D02*
G02X411000Y1452502I1487J-212D01*
G02Y1449498I0J-1502D01*
G02X410094Y1449802I0J1502D01*
G03X409457Y1449539I-241J-319D01*
G02X407970Y1448249I-1487J212D01*
G02Y1451253I0J1502D01*
G02X408876Y1450949I0J-1502D01*
G03X409513Y1451212I241J319D01*
G37*
G36*
G01X396691Y1500306D02*
G02X395370Y1499520I-1321J717D01*
G02Y1502524I0J1502D01*
G02X396716Y1501688I0J-1502D01*
G03X397426Y1501675I358J177D01*
G02X398747Y1502461I1321J-717D01*
G02Y1499457I0J-1502D01*
G02X397401Y1500293I0J1502D01*
G03X396691Y1500306I-358J-177D01*
G37*
G36*
G01X360830Y1230265D02*
G02X362332Y1228763I1502J0D01*
G02X362204Y1228768I-5J1502D01*
G01X362160Y1228772D01*
X362078Y1228742D01*
X361798Y1228466D01*
X361768Y1228384D01*
X361771Y1228340D01*
G02X361775Y1228226I-1498J-110D01*
G02X360273Y1226724I-1502J0D01*
G01X360272D01*
G02X360005Y1226748I0J1502D01*
G01X359956Y1226757D01*
X359863Y1226728D01*
X359560Y1226425D01*
X359531Y1226332D01*
X359540Y1226283D01*
G02X359564Y1226016I-1478J-267D01*
G02X358062Y1227518I-1502J0D01*
G01X358063D01*
G02X358330Y1227494I0J-1502D01*
G01X358379Y1227485D01*
X358472Y1227514D01*
X358775Y1227817D01*
X358804Y1227910D01*
X358795Y1227959D01*
G02X358771Y1228226I1478J267D01*
G02X360273Y1229728I1502J0D01*
G02X360401Y1229723I5J-1502D01*
G01X360445Y1229719D01*
X360527Y1229749D01*
X360807Y1230025D01*
X360837Y1230107D01*
X360834Y1230151D01*
G02X360830Y1230265I1498J110D01*
G37*
G36*
G01X282935Y454744D02*
G02X285939I1502J0D01*
G02X285461Y453645I-1502J0D01*
G01X285431Y453618D01*
X285398Y453544D01*
X285391Y453175D01*
X285420Y453101D01*
X285449Y453072D01*
G02X285881Y452018I-1070J-1054D01*
G02X282877I-1502J0D01*
G02X283355Y453117I1502J0D01*
G01X283385Y453144D01*
X283418Y453218D01*
X283425Y453587D01*
X283396Y453661D01*
X283367Y453690D01*
G02X282935Y454744I1070J1054D01*
G37*
G36*
G01X434924Y372112D02*
G02Y368506I0J-1803D01*
G01X431524D01*
G02Y372112I0J1803D01*
G01X434924D01*
G37*
G36*
G01X361144Y384277D02*
X360828D01*
G03X360671Y384200I1J-200D01*
G02X359486Y383621I-1185J923D01*
G02Y386625I0J1502D01*
G02X360671Y386046I0J-1502D01*
G03X360828Y385969I158J123D01*
G01X361144D01*
G03X361301Y386046I-1J200D01*
G02X362486Y386625I1185J-923D01*
G02Y383621I0J-1502D01*
G02X361301Y384200I0J1502D01*
G03X361144Y384277I-158J-123D01*
G37*
G36*
G01X405338Y385733D02*
Y386069D01*
X405313Y386136D01*
X405289Y386164D01*
G02X404919Y387151I1131J987D01*
G02X407923I1502J0D01*
G02X407553Y386164I-1501J0D01*
G01X407529Y386136D01*
X407504Y386069D01*
Y385733D01*
X407529Y385666D01*
X407553Y385638D01*
G02Y383664I-1131J-987D01*
G01X407529Y383636D01*
X407504Y383569D01*
Y383233D01*
X407529Y383166D01*
X407553Y383138D01*
G02X407923Y382151I-1131J-987D01*
G02X404919I-1502J0D01*
G02X405289Y383138I1501J0D01*
G01X405313Y383166D01*
X405338Y383233D01*
Y383569D01*
X405313Y383636D01*
X405289Y383664D01*
G02Y385638I1131J987D01*
G01X405313Y385666D01*
X405338Y385733D01*
G37*
G36*
G01X417914Y385792D02*
Y386128D01*
X417889Y386195D01*
X417865Y386223D01*
G02X417495Y387210I1131J987D01*
G02X420499I1502J0D01*
G02X420129Y386223I-1501J0D01*
G01X420105Y386195D01*
X420080Y386128D01*
Y385792D01*
X420105Y385725D01*
X420129Y385697D01*
G02Y383723I-1131J-987D01*
G01X420105Y383695D01*
X420080Y383628D01*
Y383292D01*
X420105Y383225D01*
X420129Y383197D01*
G02X420499Y382210I-1131J-987D01*
G02X417495I-1502J0D01*
G02X417865Y383197I1501J0D01*
G01X417889Y383225D01*
X417914Y383292D01*
Y383628D01*
X417889Y383695D01*
X417865Y383723D01*
G02Y385697I1131J987D01*
G01X417889Y385725D01*
X417914Y385792D01*
G37*
G36*
G01X400000Y386750D02*
X399706D01*
G03X399559Y386685I1J-200D01*
G02X398453Y386200I-1105J1017D01*
G02Y389204I0J1502D01*
G02X399559Y388719I1J-1502D01*
G03X399706Y388654I148J135D01*
G01X400000D01*
G03X400147Y388719I-1J200D01*
G02X401253Y389204I1105J-1017D01*
G02Y386200I0J-1502D01*
G02X400147Y386685I-1J1502D01*
G03X400000Y386750I-148J-135D01*
G37*
G36*
G01X390857Y387399D02*
Y387735D01*
X390832Y387802D01*
X390808Y387830D01*
G02X390438Y388817I1131J987D01*
G02X391940Y390319I1502J0D01*
G02X392795Y390052I0J-1502D01*
G01X392829Y390028D01*
X392910Y390012D01*
X393277Y390091D01*
X393344Y390139D01*
X393365Y390175D01*
G02X394653Y390904I1288J-773D01*
G02Y387900I0J-1502D01*
G02X393798Y388167I0J1502D01*
G01X393764Y388191D01*
X393683Y388207D01*
X393316Y388128D01*
X393249Y388080D01*
X393228Y388044D01*
G02X393072Y387830I-1287J774D01*
G01X393048Y387802D01*
X393023Y387735D01*
Y387399D01*
X393048Y387332D01*
X393072Y387304D01*
G02Y385330I-1131J-987D01*
G01X393048Y385302D01*
X393023Y385235D01*
Y384899D01*
X393048Y384832D01*
X393072Y384804D01*
G02X393442Y383817I-1131J-987D01*
G02X390438I-1502J0D01*
G02X390808Y384804I1501J0D01*
G01X390832Y384832D01*
X390857Y384899D01*
Y385235D01*
X390832Y385302D01*
X390808Y385330D01*
G02Y387304I1131J987D01*
G01X390832Y387332D01*
X390857Y387399D01*
G37*
G36*
G01X384782Y397195D02*
X384446D01*
X384379Y397170D01*
X384351Y397146D01*
G02X383364Y396776I-987J1131D01*
G02Y399780I0J1502D01*
G02X384351Y399410I0J-1501D01*
G01X384379Y399386D01*
X384446Y399361D01*
X384782D01*
X384849Y399386D01*
X384877Y399410D01*
G02X385864Y399780I987J-1131D01*
G02Y396776I0J-1502D01*
G02X384877Y397146I0J1501D01*
G01X384849Y397170D01*
X384782Y397195D01*
G37*
G36*
G01X383009Y400898D02*
X382673D01*
X382606Y400873D01*
X382578Y400849D01*
G02X381591Y400479I-987J1131D01*
G02Y403483I0J1502D01*
G02X382578Y403113I0J-1501D01*
G01X382606Y403089D01*
X382673Y403064D01*
X383009D01*
X383076Y403089D01*
X383104Y403113D01*
G02X384091Y403483I987J-1131D01*
G02Y400479I0J-1502D01*
G02X383104Y400849I0J1501D01*
G01X383076Y400873D01*
X383009Y400898D01*
G37*
G36*
G01X429890Y409056D02*
X430184D01*
G03X430331Y409121I-1J200D01*
G02X431437Y409606I1105J-1017D01*
G02X432543Y409121I1J-1502D01*
G03X432690Y409056I148J135D01*
G01X432984D01*
G03X433131Y409121I-1J200D01*
G02X434237Y409606I1105J-1017D01*
G02Y406602I0J-1502D01*
G02X433131Y407087I-1J1502D01*
G03X432984Y407152I-148J-135D01*
G01X432690D01*
G03X432543Y407087I1J-200D01*
G02X431437Y406602I-1105J1017D01*
G02X430331Y407087I-1J1502D01*
G03X430184Y407152I-148J-135D01*
G01X429890D01*
G03X429743Y407087I1J-200D01*
G02X428637Y406602I-1105J1017D01*
G02Y409606I0J1502D01*
G02X429743Y409121I1J-1502D01*
G03X429890Y409056I148J135D01*
G37*
G36*
G01X382027Y414694D02*
X382363D01*
X382430Y414719D01*
X382458Y414743D01*
G02X384432I987J-1131D01*
G01X384460Y414719D01*
X384527Y414694D01*
X384863D01*
X384930Y414719D01*
X384958Y414743D01*
G02X385945Y415113I987J-1131D01*
G02Y412109I0J-1502D01*
G02X384958Y412479I0J1501D01*
G01X384930Y412503D01*
X384863Y412528D01*
X384527D01*
X384460Y412503D01*
X384432Y412479D01*
G02X382458I-987J1131D01*
G01X382430Y412503D01*
X382363Y412528D01*
X382027D01*
X381960Y412503D01*
X381932Y412479D01*
G02X379958I-987J1131D01*
G01X379930Y412503D01*
X379863Y412528D01*
X379527D01*
X379460Y412503D01*
X379432Y412479D01*
G02X378445Y412109I-987J1131D01*
G02Y415113I0J1502D01*
G02X379432Y414743I0J-1501D01*
G01X379460Y414719D01*
X379527Y414694D01*
X379863D01*
X379930Y414719D01*
X379958Y414743D01*
G02X381932I987J-1131D01*
G01X381960Y414719D01*
X382027Y414694D01*
G37*
G36*
G01X429607Y421327D02*
X429901D01*
G03X430048Y421392I-1J200D01*
G02X431154Y421877I1105J-1017D01*
G02X432260Y421392I1J-1502D01*
G03X432407Y421327I148J135D01*
G01X432701D01*
G03X432848Y421392I-1J200D01*
G02X433954Y421877I1105J-1017D01*
G02Y418873I0J-1502D01*
G02X432848Y419358I-1J1502D01*
G03X432701Y419423I-148J-135D01*
G01X432407D01*
G03X432260Y419358I1J-200D01*
G02X431154Y418873I-1105J1017D01*
G02X430048Y419358I-1J1502D01*
G03X429901Y419423I-148J-135D01*
G01X429607D01*
G03X429460Y419358I1J-200D01*
G02X428354Y418873I-1105J1017D01*
G02Y421877I0J1502D01*
G02X429460Y421392I1J-1502D01*
G03X429607Y421327I148J135D01*
G37*
G36*
G01X353113Y420013D02*
Y420365D01*
X353085Y420434D01*
X353059Y420462D01*
G02X352653Y421489I1096J1027D01*
G02X355657I1502J0D01*
G02X355251Y420462I-1502J0D01*
G01X355225Y420434D01*
X355197Y420365D01*
Y420013D01*
X355225Y419944D01*
X355251Y419916D01*
G02Y417862I-1096J-1027D01*
G01X355225Y417834D01*
X355197Y417765D01*
Y417413D01*
X355225Y417344D01*
X355251Y417316D01*
G02X355657Y416289I-1096J-1027D01*
G02X352653I-1502J0D01*
G02X353059Y417316I1502J0D01*
G01X353085Y417344D01*
X353113Y417413D01*
Y417765D01*
X353085Y417834D01*
X353059Y417862D01*
G02Y419916I1096J1027D01*
G01X353085Y419944D01*
X353113Y420013D01*
G37*
G36*
G01X338030Y420612D02*
Y420964D01*
X338002Y421033D01*
X337976Y421061D01*
G02X337570Y422088I1096J1027D01*
G02X340574I1502J0D01*
G02X340168Y421061I-1502J0D01*
G01X340142Y421033D01*
X340114Y420964D01*
Y420612D01*
X340142Y420543D01*
X340168Y420515D01*
G02Y418461I-1096J-1027D01*
G01X340142Y418433D01*
X340114Y418364D01*
Y418012D01*
X340142Y417943D01*
X340168Y417915D01*
G02X340574Y416888I-1096J-1027D01*
G02X337570I-1502J0D01*
G02X337976Y417915I1502J0D01*
G01X338002Y417943D01*
X338030Y418012D01*
Y418364D01*
X338002Y418433D01*
X337976Y418461D01*
G02Y420515I1096J1027D01*
G01X338002Y420543D01*
X338030Y420612D01*
G37*
G36*
G01X381792Y425150D02*
X382128D01*
X382195Y425175D01*
X382223Y425199D01*
G02X384197I987J-1131D01*
G01X384225Y425175D01*
X384292Y425150D01*
X384628D01*
X384695Y425175D01*
X384723Y425199D01*
G02X385710Y425569I987J-1131D01*
G02Y422565I0J-1502D01*
G02X384723Y422935I0J1501D01*
G01X384695Y422959D01*
X384628Y422984D01*
X384292D01*
X384225Y422959D01*
X384197Y422935D01*
G02X382223I-987J1131D01*
G01X382195Y422959D01*
X382128Y422984D01*
X381792D01*
X381725Y422959D01*
X381697Y422935D01*
G02X379723I-987J1131D01*
G01X379695Y422959D01*
X379628Y422984D01*
X379292D01*
X379225Y422959D01*
X379197Y422935D01*
G02X378210Y422565I-987J1131D01*
G02Y425569I0J1502D01*
G02X379197Y425199I0J-1501D01*
G01X379225Y425175D01*
X379292Y425150D01*
X379628D01*
X379695Y425175D01*
X379723Y425199D01*
G02X381697I987J-1131D01*
G01X381725Y425175D01*
X381792Y425150D01*
G37*
G36*
G01X356613Y425213D02*
Y425565D01*
X356585Y425634D01*
X356559Y425662D01*
G02X356153Y426689I1096J1027D01*
G02X359157I1502J0D01*
G02X358751Y425662I-1502J0D01*
G01X358725Y425634D01*
X358697Y425565D01*
Y425213D01*
X358725Y425144D01*
X358751Y425116D01*
G02Y423062I-1096J-1027D01*
G01X358725Y423034D01*
X358697Y422965D01*
Y422613D01*
X358725Y422544D01*
X358751Y422516D01*
G02Y420462I-1096J-1027D01*
G01X358725Y420434D01*
X358697Y420365D01*
Y420013D01*
X358725Y419944D01*
X358751Y419916D01*
G02Y417862I-1096J-1027D01*
G01X358725Y417834D01*
X358697Y417765D01*
Y417413D01*
X358725Y417344D01*
X358751Y417316D01*
G02Y415262I-1096J-1027D01*
G01X358725Y415234D01*
X358697Y415165D01*
Y414813D01*
X358725Y414744D01*
X358751Y414716D01*
G02Y412662I-1096J-1027D01*
G01X358725Y412634D01*
X358697Y412565D01*
Y412213D01*
X358725Y412144D01*
X358751Y412116D01*
G02Y410062I-1096J-1027D01*
G01X358725Y410034D01*
X358697Y409965D01*
Y409613D01*
X358725Y409544D01*
X358751Y409516D01*
G02Y407462I-1096J-1027D01*
G01X358725Y407434D01*
X358697Y407365D01*
Y407013D01*
X358725Y406944D01*
X358751Y406916D01*
G02X359157Y405889I-1096J-1027D01*
G02X358937Y405107I-1502J1D01*
G01X358917Y405073D01*
X358904Y404996D01*
X358984Y404647D01*
X359029Y404584D01*
X359062Y404562D01*
G02X359750Y403300I-813J-1262D01*
G02X356746I-1502J0D01*
G02X356966Y404082I1502J-1D01*
G01X356986Y404116D01*
X356999Y404193D01*
X356919Y404542D01*
X356874Y404605D01*
X356841Y404627D01*
G02X356153Y405889I813J1262D01*
G02X356559Y406916I1502J0D01*
G01X356585Y406944D01*
X356613Y407013D01*
Y407365D01*
X356585Y407434D01*
X356559Y407462D01*
G02Y409516I1096J1027D01*
G01X356585Y409544D01*
X356613Y409613D01*
Y409965D01*
X356585Y410034D01*
X356559Y410062D01*
G02Y412116I1096J1027D01*
G01X356585Y412144D01*
X356613Y412213D01*
Y412565D01*
X356585Y412634D01*
X356559Y412662D01*
G02Y414716I1096J1027D01*
G01X356585Y414744D01*
X356613Y414813D01*
Y415165D01*
X356585Y415234D01*
X356559Y415262D01*
G02Y417316I1096J1027D01*
G01X356585Y417344D01*
X356613Y417413D01*
Y417765D01*
X356585Y417834D01*
X356559Y417862D01*
G02Y419916I1096J1027D01*
G01X356585Y419944D01*
X356613Y420013D01*
Y420365D01*
X356585Y420434D01*
X356559Y420462D01*
G02Y422516I1096J1027D01*
G01X356585Y422544D01*
X356613Y422613D01*
Y422965D01*
X356585Y423034D01*
X356559Y423062D01*
G02Y425116I1096J1027D01*
G01X356585Y425144D01*
X356613Y425213D01*
G37*
G36*
G01X421132Y426021D02*
Y426357D01*
X421107Y426424D01*
X421083Y426452D01*
G02X420713Y427439I1131J987D01*
G02X423717I1502J0D01*
G02X423347Y426452I-1501J0D01*
G01X423323Y426424D01*
X423298Y426357D01*
Y426021D01*
X423323Y425954D01*
X423347Y425926D01*
G02X423717Y424939I-1131J-987D01*
G02X420713I-1502J0D01*
G02X421083Y425926I1501J0D01*
G01X421107Y425954D01*
X421132Y426021D01*
G37*
G36*
G01X357090Y433971D02*
Y434265D01*
G03X357025Y434412I-200J-1D01*
G02X356540Y435518I1017J1105D01*
G02X359544I1502J0D01*
G02X359059Y434412I-1502J-1D01*
G03X358994Y434265I135J-148D01*
G01Y433971D01*
G03X359059Y433824I200J1D01*
G02X359544Y432718I-1017J-1105D01*
G02X356540I-1502J0D01*
G02X357025Y433824I1502J1D01*
G03X357090Y433971I-135J148D01*
G37*
G36*
G01X366967Y440571D02*
Y440865D01*
G03X366902Y441012I-200J-1D01*
G02X366417Y442118I1017J1105D01*
G02X369421I1502J0D01*
G02X368936Y441012I-1502J-1D01*
G03X368871Y440865I135J-148D01*
G01Y440571D01*
G03X368936Y440424I200J1D01*
G02X369421Y439318I-1017J-1105D01*
G02X366417I-1502J0D01*
G02X366902Y440424I1502J1D01*
G03X366967Y440571I-135J148D01*
G37*
G36*
G01X374967D02*
Y440865D01*
G03X374902Y441012I-200J-1D01*
G02X374417Y442118I1017J1105D01*
G02X377421I1502J0D01*
G02X376936Y441012I-1502J-1D01*
G03X376871Y440865I135J-148D01*
G01Y440571D01*
G03X376936Y440424I200J1D01*
G02X377421Y439318I-1017J-1105D01*
G02X374417I-1502J0D01*
G02X374902Y440424I1502J1D01*
G03X374967Y440571I-135J148D01*
G37*
G36*
G01X411172Y442174D02*
Y442468D01*
G03X411107Y442615I-200J-1D01*
G02X410622Y443721I1017J1105D01*
G02X412124Y445223I1502J0D01*
G02X413230Y444738I1J-1502D01*
G03X413377Y444673I148J135D01*
G01X413671D01*
G03X413818Y444738I-1J200D01*
G02X414924Y445223I1105J-1017D01*
G02X416426Y443721I0J-1502D01*
G02X415941Y442615I-1502J-1D01*
G03X415876Y442468I135J-148D01*
G01Y442174D01*
G03X415941Y442027I200J1D01*
G02X416426Y440921I-1017J-1105D01*
G02X415941Y439815I-1502J-1D01*
G03X415876Y439668I135J-148D01*
G01Y439374D01*
G03X415941Y439227I200J1D01*
G02X416426Y438121I-1017J-1105D01*
G02X415941Y437015I-1502J-1D01*
G03X415876Y436868I135J-148D01*
G01Y436574D01*
G03X415941Y436427I200J1D01*
G02X416426Y435321I-1017J-1105D01*
G02X414924Y433819I-1502J0D01*
G02X413818Y434304I-1J1502D01*
G03X413671Y434369I-148J-135D01*
G01X413377D01*
G03X413230Y434304I1J-200D01*
G02X412124Y433819I-1105J1017D01*
G02X410622Y435321I0J1502D01*
G02X411107Y436427I1502J1D01*
G03X411172Y436574I-135J148D01*
G01Y436868D01*
G03X411107Y437015I-200J-1D01*
G02X410622Y438121I1017J1105D01*
G02X411107Y439227I1502J1D01*
G03X411172Y439374I-135J148D01*
G01Y439668D01*
G03X411107Y439815I-200J-1D01*
G02X410622Y440921I1017J1105D01*
G02X411107Y442027I1502J1D01*
G03X411172Y442174I-135J148D01*
G37*
G36*
G01X384632Y442346D02*
Y442640D01*
G03X384567Y442787I-200J-1D01*
G02X384082Y443893I1017J1105D01*
G02X387086I1502J0D01*
G02X386601Y442787I-1502J-1D01*
G03X386536Y442640I135J-148D01*
G01Y442346D01*
G03X386601Y442199I200J1D01*
G02X387086Y441093I-1017J-1105D01*
G02X386601Y439987I-1502J-1D01*
G03X386536Y439840I135J-148D01*
G01Y439546D01*
G03X386601Y439399I200J1D01*
G02X387086Y438293I-1017J-1105D01*
G02X384082I-1502J0D01*
G02X384567Y439399I1502J1D01*
G03X384632Y439546I-135J148D01*
G01Y439840D01*
G03X384567Y439987I-200J-1D01*
G02X384082Y441093I1017J1105D01*
G02X384567Y442199I1502J1D01*
G03X384632Y442346I-135J148D01*
G37*
G36*
G01X394625D02*
Y442640D01*
G03X394560Y442787I-200J-1D01*
G02X394075Y443893I1017J1105D01*
G02X397079I1502J0D01*
G02X396594Y442787I-1502J-1D01*
G03X396529Y442640I135J-148D01*
G01Y442346D01*
G03X396594Y442199I200J1D01*
G02X397079Y441093I-1017J-1105D01*
G02X396594Y439987I-1502J-1D01*
G03X396529Y439840I135J-148D01*
G01Y439546D01*
G03X396594Y439399I200J1D01*
G02X397079Y438293I-1017J-1105D01*
G02X394075I-1502J0D01*
G02X394560Y439399I1502J1D01*
G03X394625Y439546I-135J148D01*
G01Y439840D01*
G03X394560Y439987I-200J-1D01*
G02X394075Y441093I1017J1105D01*
G02X394560Y442199I1502J1D01*
G03X394625Y442346I-135J148D01*
G37*
G36*
G01X463784Y459589D02*
X463468D01*
G03X463311Y459512I1J-200D01*
G02X462126Y458933I-1185J923D01*
G02Y461937I0J1502D01*
G02X463311Y461358I0J-1502D01*
G03X463468Y461281I158J123D01*
G01X463784D01*
G03X463941Y461358I-1J200D01*
G02X465126Y461937I1185J-923D01*
G02Y458933I0J-1502D01*
G02X463941Y459512I0J1502D01*
G03X463784Y459589I-158J-123D01*
G37*
G36*
G01X360412Y461214D02*
X360096D01*
G03X359939Y461137I1J-200D01*
G02X358754Y460558I-1185J923D01*
G02Y463562I0J1502D01*
G02X359939Y462983I0J-1502D01*
G03X360096Y462906I158J123D01*
G01X360412D01*
G03X360569Y462983I-1J200D01*
G02X361754Y463562I1185J-923D01*
G02Y460558I0J-1502D01*
G02X360569Y461137I0J1502D01*
G03X360412Y461214I-158J-123D01*
G37*
G36*
G01X374964Y468918D02*
X374628D01*
X374561Y468893D01*
X374533Y468869D01*
G02X373546Y468499I-987J1131D01*
G02Y471503I0J1502D01*
G02X374533Y471133I0J-1501D01*
G01X374561Y471109D01*
X374628Y471084D01*
X374964D01*
X375031Y471109D01*
X375059Y471133D01*
G02X376046Y471503I987J-1131D01*
G02Y468499I0J-1502D01*
G02X375059Y468869I0J1501D01*
G01X375031Y468893D01*
X374964Y468918D01*
G37*
G36*
G01X413192Y498551D02*
Y498887D01*
X413167Y498954D01*
X413143Y498982D01*
G02X412773Y499969I1131J987D01*
G02X415777I1502J0D01*
G02X415407Y498982I-1501J0D01*
G01X415383Y498954D01*
X415358Y498887D01*
Y498551D01*
X415383Y498484D01*
X415407Y498456D01*
G02Y496482I-1131J-987D01*
G01X415383Y496454D01*
X415358Y496387D01*
Y496051D01*
X415383Y495984D01*
X415407Y495956D01*
G02Y493982I-1131J-987D01*
G01X415383Y493954D01*
X415358Y493887D01*
Y493551D01*
X415383Y493484D01*
X415407Y493456D01*
G02X415777Y492469I-1131J-987D01*
G02X412773I-1502J0D01*
G02X413143Y493456I1501J0D01*
G01X413167Y493484D01*
X413192Y493551D01*
Y493887D01*
X413167Y493954D01*
X413143Y493982D01*
G02Y495956I1131J987D01*
G01X413167Y495984D01*
X413192Y496051D01*
Y496387D01*
X413167Y496454D01*
X413143Y496482D01*
G02Y498456I1131J987D01*
G01X413167Y498484D01*
X413192Y498551D01*
G37*
G36*
G01X447024Y507532D02*
X447360D01*
X447427Y507557D01*
X447455Y507581D01*
G02X449429I987J-1131D01*
G01X449457Y507557D01*
X449524Y507532D01*
X449860D01*
X449927Y507557D01*
X449955Y507581D01*
G02X450942Y507951I987J-1131D01*
G02Y504947I0J-1502D01*
G02X449955Y505317I0J1501D01*
G01X449927Y505341D01*
X449860Y505366D01*
X449524D01*
X449457Y505341D01*
X449429Y505317D01*
G02X447455I-987J1131D01*
G01X447427Y505341D01*
X447360Y505366D01*
X447024D01*
X446957Y505341D01*
X446929Y505317D01*
G02X445942Y504947I-987J1131D01*
G02Y507951I0J1502D01*
G02X446929Y507581I0J-1501D01*
G01X446957Y507557D01*
X447024Y507532D01*
G37*
G36*
G01X447443Y510429D02*
X447107D01*
X447040Y510404D01*
X447012Y510380D01*
G02X446025Y510010I-987J1131D01*
G02Y513014I0J1502D01*
G02X447012Y512644I0J-1501D01*
G01X447040Y512620D01*
X447107Y512595D01*
X447443D01*
X447510Y512620D01*
X447538Y512644D01*
G02X448525Y513014I987J-1131D01*
G02Y510010I0J-1502D01*
G02X447538Y510380I0J1501D01*
G01X447510Y510404D01*
X447443Y510429D01*
G37*
G36*
G01Y518616D02*
X447107D01*
X447040Y518591D01*
X447012Y518567D01*
G02X446025Y518197I-987J1131D01*
G02Y521201I0J1502D01*
G02X447012Y520831I0J-1501D01*
G01X447040Y520807D01*
X447107Y520782D01*
X447443D01*
X447510Y520807D01*
X447538Y520831D01*
G02X448525Y521201I987J-1131D01*
G02Y518197I0J-1502D01*
G02X447538Y518567I0J1501D01*
G01X447510Y518591D01*
X447443Y518616D01*
G37*
G36*
G01X380269Y410385D02*
X380585D01*
G03X380742Y410462I-1J200D01*
G02X381927Y411041I1185J-923D01*
G02X383429Y409539I0J-1502D01*
G02X383059Y408552I-1501J0D01*
G01X383035Y408524D01*
X383010Y408457D01*
Y408121D01*
X383035Y408054D01*
X383059Y408026D01*
G02X383429Y407039I-1131J-987D01*
G02X381927Y405537I-1502J0D01*
G02X380834Y406009I0J1502D01*
G01X380801Y406044D01*
X380715Y406076D01*
X380305Y406035D01*
X380228Y405986D01*
X380203Y405946D01*
G02X378927Y405237I-1276J794D01*
G02X377425Y406739I0J1502D01*
G02X377910Y407845I1502J1D01*
G03X377975Y407992I-135J148D01*
G01Y408286D01*
G03X377910Y408433I-200J-1D01*
G02X377425Y409539I1017J1105D01*
G02X378927Y411041I1502J0D01*
G02X380112Y410462I0J-1502D01*
G03X380269Y410385I158J123D01*
G37*
G36*
G01X423294Y433259D02*
G02X422223Y432697I-1071J739D01*
G02Y435301I0J1302D01*
G02X423294Y434739I0J-1301D01*
G03X423952I329J228D01*
G02X425023Y435301I1071J-739D01*
G02Y432697I0J-1302D01*
G02X423952Y433259I0J1301D01*
G03X423294I-329J-228D01*
G37*
G36*
G01Y436803D02*
G02X422223Y436241I-1071J739D01*
G02Y438845I0J1302D01*
G02X423294Y438283I0J-1301D01*
G03X423952I329J228D01*
G02X425023Y438845I1071J-739D01*
G02Y436241I0J-1302D01*
G02X423952Y436803I0J1301D01*
G03X423294I-329J-228D01*
G37*
G36*
G01Y440346D02*
G02X422223Y439784I-1071J739D01*
G02Y442388I0J1302D01*
G02X423294Y441826I0J-1301D01*
G03X423952I329J228D01*
G02X425023Y442388I1071J-739D01*
G02Y439784I0J-1302D01*
G02X423952Y440346I0J1301D01*
G03X423294I-329J-228D01*
G37*
G36*
G01Y443889D02*
G02X422223Y443327I-1071J739D01*
G02Y445931I0J1302D01*
G02X423294Y445369I0J-1301D01*
G03X423952I329J228D01*
G02X425023Y445931I1071J-739D01*
G02Y443327I0J-1302D01*
G02X423952Y443889I0J1301D01*
G03X423294I-329J-228D01*
G37*
G36*
G01X360096Y450937D02*
X360412D01*
G03X360569Y451014I-1J200D01*
G02X361754Y451593I1185J-923D01*
G02Y448589I0J-1502D01*
G02X360569Y449168I0J1502D01*
G03X360412Y449245I-158J-123D01*
G01X360096D01*
G03X359939Y449168I1J-200D01*
G02X359790Y449004I-1183J925D01*
G01X359754Y448970D01*
X359723Y448877D01*
X359790Y448454D01*
X359848Y448376D01*
X359893Y448354D01*
G02X360743Y447001I-652J-1353D01*
G02X359241Y445499I-1502J0D01*
G02X358056Y446078I0J1502D01*
G03X357899Y446155I-158J-123D01*
G01X357583D01*
G03X357426Y446078I1J-200D01*
G02X356241Y445499I-1185J923D01*
G02X354739Y447001I0J1502D01*
G02X354755Y447217I1502J-3D01*
G01X354762Y447271D01*
X354723Y447369D01*
X354367Y447651D01*
X354263Y447667D01*
X354213Y447647D01*
G02X353663Y447543I-549J1398D01*
G02X355165Y449045I0J1502D01*
G02X355149Y448829I-1502J3D01*
G01X355142Y448775D01*
X355181Y448677D01*
X355537Y448395D01*
X355641Y448379D01*
X355691Y448399D01*
G02X356241Y448503I549J-1398D01*
G02X357426Y447924I0J-1502D01*
G03X357583Y447847I158J123D01*
G01X357899D01*
G03X358056Y447924I-1J200D01*
G02X358205Y448088I1183J-925D01*
G01X358241Y448122D01*
X358272Y448215D01*
X358205Y448638D01*
X358147Y448716D01*
X358102Y448738D01*
G02X357252Y450091I652J1353D01*
G02X358754Y451593I1502J0D01*
G02X359939Y451014I0J-1502D01*
G03X360096Y450937I158J123D01*
G37*
G36*
G01X434737Y500452D02*
X434710Y500480D01*
G02X434287Y501525I1079J1045D01*
G02X435789Y503027I1502J0D01*
G02X437230Y501948I0J-1502D01*
G01X437244Y501901D01*
X437307Y501833D01*
X437698Y501688D01*
X437790Y501698D01*
X437831Y501724D01*
G02X438644Y501963I813J-1263D01*
G02Y498959I0J-1502D01*
G02X437921Y499144I-1J1502D01*
G01X437876Y499169D01*
X437774D01*
X437388Y498958D01*
X437333Y498872D01*
X437330Y498821D01*
G02X435831Y497421I-1499J103D01*
G02X434329Y498923I0J1502D01*
G02X434719Y499933I1503J0D01*
G01X434745Y499962D01*
X434772Y500031D01*
X434766Y500383D01*
X434737Y500452D01*
G37*
G36*
G01X426075Y501832D02*
X426070Y501888D01*
G02X426066Y502003I1498J110D01*
G02X429070I1502J0D01*
G02X428508Y500831I-1503J0D01*
G01X428470Y500801D01*
X428431Y500715D01*
X428448Y500297D01*
X428494Y500215D01*
X428534Y500188D01*
G02X429195Y498943I-842J-1245D01*
G02X427693Y497441I-1502J0D01*
G02X426834Y497711I0J1501D01*
G01X426792Y497740D01*
X426691Y497751D01*
X426283Y497581D01*
X426220Y497501D01*
X426211Y497450D01*
G02X425863Y496717I-1480J254D01*
G01X425839Y496689D01*
X425814Y496622D01*
Y496286D01*
X425839Y496219D01*
X425863Y496191D01*
G02Y494217I-1131J-987D01*
G01X425839Y494189D01*
X425814Y494122D01*
Y493786D01*
X425839Y493719D01*
X425863Y493691D01*
G02X426233Y492704I-1131J-987D01*
G02X423229I-1502J0D01*
G02X423599Y493691I1501J0D01*
G01X423623Y493719D01*
X423648Y493786D01*
Y494122D01*
X423623Y494189D01*
X423599Y494217D01*
G02Y496191I1131J987D01*
G01X423623Y496219D01*
X423648Y496286D01*
Y496622D01*
X423623Y496689D01*
X423599Y496717D01*
G02Y498691I1131J987D01*
G01X423623Y498719D01*
X423648Y498786D01*
Y499122D01*
X423623Y499189D01*
X423599Y499217D01*
G02X423229Y500204I1131J987D01*
G02X424731Y501706I1502J0D01*
G02X425474Y501509I-1J-1502D01*
G01X425523Y501482D01*
X425632Y501484D01*
X426026Y501734D01*
X426075Y501832D01*
G37*
G36*
G01X359160Y475970D02*
X358824D01*
X358757Y475945D01*
X358729Y475921D01*
G02X357742Y475551I-987J1131D01*
G02Y478555I0J1502D01*
G02X358729Y478185I0J-1501D01*
G01X358757Y478161D01*
X358824Y478136D01*
X359160D01*
X359227Y478161D01*
X359255Y478185D01*
G02X360242Y478555I987J-1131D01*
G02Y475551I0J-1502D01*
G02X359255Y475921I0J1501D01*
G01X359227Y475945D01*
X359160Y475970D01*
G37*
G36*
G01X372914Y486663D02*
X373250D01*
X373317Y486688D01*
X373345Y486712D01*
G02X375319I987J-1131D01*
G01X375347Y486688D01*
X375414Y486663D01*
X375750D01*
X375817Y486688D01*
X375845Y486712D01*
G02X376832Y487082I987J-1131D01*
G02Y484078I0J-1502D01*
G02X375845Y484448I0J1501D01*
G01X375817Y484472D01*
X375750Y484497D01*
X375414D01*
X375347Y484472D01*
X375319Y484448D01*
G02X373345I-987J1131D01*
G01X373317Y484472D01*
X373250Y484497D01*
X372914D01*
X372847Y484472D01*
X372819Y484448D01*
G02X371832Y484078I-987J1131D01*
G02Y487082I0J1502D01*
G02X372819Y486712I0J-1501D01*
G01X372847Y486688D01*
X372914Y486663D01*
G37*
G36*
G01X385769Y1302523D02*
G03X386282Y1302724I151J370D01*
G02X387644Y1303592I1362J-635D01*
G02X389147Y1302089I0J-1503D01*
G02X389096Y1301700I-1503J-1D01*
G03X389089Y1301645I193J-52D01*
G02Y1301632I-1502J-7D01*
G01Y1301630D01*
G02X387587Y1300129I-1502J1D01*
G02X387355Y1300147I0J1502D01*
G01X387312Y1300154D01*
X387228Y1300130D01*
X386930Y1299876D01*
X386894Y1299797D01*
Y1299752D01*
Y1298554D01*
Y1298509D01*
X386930Y1298430D01*
X387228Y1298176D01*
X387312Y1298152D01*
X387355Y1298159D01*
G02X387587Y1298177I232J-1484D01*
G02Y1295173I0J-1502D01*
G01X387586D01*
G02X386364Y1295802I0J1502D01*
G01X386342Y1295832D01*
X386282Y1295873D01*
X386126Y1295908D01*
G03X385983Y1295887I-44J-195D01*
G02X385091Y1295650I-893J1566D01*
G02X383288Y1297453I0J1803D01*
G01Y1300853D01*
G02X385091Y1302656I1803J0D01*
G02X385769Y1302523I-2J-1803D01*
G37*
G36*
G01X451362Y553514D02*
Y553866D01*
X451334Y553935D01*
X451308Y553963D01*
G02X450902Y554990I1096J1027D01*
G02X452404Y556492I1502J0D01*
G02X453465Y556053I0J-1502D01*
G01X453492Y556026D01*
X453562Y555996D01*
X453913Y555985D01*
X453985Y556011D01*
X454013Y556036D01*
G02X455009Y556414I996J-1123D01*
G02X456511Y554912I0J-1502D01*
G02X456105Y553885I-1502J0D01*
G01X456079Y553857D01*
X456051Y553788D01*
Y553436D01*
X456079Y553367D01*
X456105Y553339D01*
G02Y551285I-1096J-1027D01*
G01X456079Y551257D01*
X456051Y551188D01*
Y550836D01*
X456079Y550767D01*
X456105Y550739D01*
G02X456511Y549712I-1096J-1027D01*
G02X456026Y548606I-1502J-1D01*
G03X455961Y548459I135J-148D01*
G01Y548165D01*
G03X456026Y548018I200J1D01*
G02X456511Y546912I-1017J-1105D01*
G02X456105Y545885I-1502J0D01*
G01X456079Y545857D01*
X456051Y545788D01*
Y545436D01*
X456079Y545367D01*
X456105Y545339D01*
G02X456511Y544312I-1096J-1027D01*
G02X455009Y542810I-1502J0D01*
G02X453948Y543249I0J1502D01*
G01X453921Y543276D01*
X453851Y543306D01*
X453500Y543317D01*
X453428Y543291D01*
X453400Y543266D01*
G02X452404Y542888I-996J1123D01*
G02X450902Y544390I0J1502D01*
G02X451308Y545417I1502J0D01*
G01X451334Y545445D01*
X451362Y545514D01*
Y545866D01*
X451334Y545935D01*
X451308Y545963D01*
G02X450902Y546990I1096J1027D01*
G02X451387Y548096I1502J1D01*
G03X451452Y548243I-135J148D01*
G01Y548537D01*
G03X451387Y548684I-200J-1D01*
G02X450902Y549790I1017J1105D01*
G02X451308Y550817I1502J0D01*
G01X451334Y550845D01*
X451362Y550914D01*
Y551266D01*
X451334Y551335D01*
X451308Y551363D01*
G02Y553417I1096J1027D01*
G01X451334Y553445D01*
X451362Y553514D01*
G37*
G36*
G01X441962Y553614D02*
Y553966D01*
X441934Y554035D01*
X441908Y554063D01*
G02X441502Y555090I1096J1027D01*
G02X444506I1502J0D01*
G02X444100Y554063I-1502J0D01*
G01X444074Y554035D01*
X444046Y553966D01*
Y553614D01*
X444074Y553545D01*
X444100Y553517D01*
G02Y551463I-1096J-1027D01*
G01X444074Y551435D01*
X444046Y551366D01*
Y551014D01*
X444074Y550945D01*
X444100Y550917D01*
G02X444506Y549890I-1096J-1027D01*
G02X443892Y548678I-1503J0D01*
G01X443855Y548652D01*
X443813Y548575D01*
X443786Y548181D01*
X443817Y548100D01*
X443849Y548068D01*
G02X444306Y546990I-1045J-1079D01*
G02X443900Y545963I-1502J0D01*
G01X443874Y545935D01*
X443846Y545866D01*
Y545514D01*
X443874Y545445D01*
X443900Y545417D01*
G02X444306Y544390I-1096J-1027D01*
G02X441302I-1502J0D01*
G02X441708Y545417I1502J0D01*
G01X441734Y545445D01*
X441762Y545514D01*
Y545866D01*
X441734Y545935D01*
X441708Y545963D01*
G02X441302Y546990I1096J1027D01*
G02X441916Y548202I1503J0D01*
G01X441953Y548228D01*
X441995Y548305D01*
X442022Y548699D01*
X441991Y548780D01*
X441959Y548812D01*
G02X441502Y549890I1045J1079D01*
G02X441908Y550917I1502J0D01*
G01X441934Y550945D01*
X441962Y551014D01*
Y551366D01*
X441934Y551435D01*
X441908Y551463D01*
G02Y553517I1096J1027D01*
G01X441934Y553545D01*
X441962Y553614D01*
G37*
G36*
G01X418298Y553714D02*
Y554066D01*
X418270Y554135D01*
X418244Y554163D01*
G02X417838Y555190I1096J1027D01*
G02X420842I1502J0D01*
G02X420436Y554163I-1502J0D01*
G01X420410Y554135D01*
X420382Y554066D01*
Y553714D01*
X420410Y553645D01*
X420436Y553617D01*
G02Y551563I-1096J-1027D01*
G01X420410Y551535D01*
X420382Y551466D01*
Y551114D01*
X420410Y551045D01*
X420436Y551017D01*
G02X420842Y549990I-1096J-1027D01*
G02X420351Y548880I-1502J1D01*
G01X420323Y548854D01*
X420290Y548785D01*
X420263Y548435D01*
X420285Y548363D01*
X420309Y548333D01*
G02X420642Y547390I-1169J-943D01*
G02X420236Y546363I-1502J0D01*
G01X420210Y546335D01*
X420182Y546266D01*
Y545914D01*
X420210Y545845D01*
X420236Y545817D01*
G02X420642Y544790I-1096J-1027D01*
G02X417638I-1502J0D01*
G02X418044Y545817I1502J0D01*
G01X418070Y545845D01*
X418098Y545914D01*
Y546266D01*
X418070Y546335D01*
X418044Y546363D01*
G02X417638Y547390I1096J1027D01*
G02X418129Y548500I1502J-1D01*
G01X418157Y548526D01*
X418190Y548595D01*
X418217Y548945D01*
X418195Y549017D01*
X418171Y549047D01*
G02X417838Y549990I1169J943D01*
G02X418244Y551017I1502J0D01*
G01X418270Y551045D01*
X418298Y551114D01*
Y551466D01*
X418270Y551535D01*
X418244Y551563D01*
G02Y553617I1096J1027D01*
G01X418270Y553645D01*
X418298Y553714D01*
G37*
G36*
G01X427698D02*
Y554066D01*
X427670Y554135D01*
X427644Y554163D01*
G02X427238Y555190I1096J1027D01*
G02X428740Y556692I1502J0D01*
G02X429784Y556270I0J-1502D01*
G01X429813Y556242D01*
X429883Y556214D01*
X430241D01*
X430311Y556242D01*
X430340Y556270D01*
G02X431384Y556692I1044J-1080D01*
G02X432886Y555190I0J-1502D01*
G02X432480Y554163I-1502J0D01*
G01X432454Y554135D01*
X432426Y554066D01*
Y553714D01*
X432454Y553645D01*
X432480Y553617D01*
G02Y551563I-1096J-1027D01*
G01X432454Y551535D01*
X432426Y551466D01*
Y551114D01*
X432454Y551045D01*
X432480Y551017D01*
G02X432886Y549990I-1096J-1027D01*
G02X432307Y548805I-1502J0D01*
G03X432230Y548648I123J-158D01*
G01Y548332D01*
G03X432307Y548175I200J1D01*
G02X432886Y546990I-923J-1185D01*
G02X432480Y545963I-1502J0D01*
G01X432454Y545935D01*
X432426Y545866D01*
Y545514D01*
X432454Y545445D01*
X432480Y545417D01*
G02X432886Y544390I-1096J-1027D01*
G02X431384Y542888I-1502J0D01*
G02X430340Y543310I0J1502D01*
G01X430311Y543338D01*
X430241Y543366D01*
X429883D01*
X429813Y543338D01*
X429784Y543310D01*
G02X428740Y542888I-1044J1080D01*
G02X427238Y544390I0J1502D01*
G02X427644Y545417I1502J0D01*
G01X427670Y545445D01*
X427698Y545514D01*
Y545866D01*
X427670Y545935D01*
X427644Y545963D01*
G02X427238Y546990I1096J1027D01*
G02X427817Y548175I1502J0D01*
G03X427894Y548332I-123J158D01*
G01Y548648D01*
G03X427817Y548805I-200J-1D01*
G02X427238Y549990I923J1185D01*
G02X427644Y551017I1502J0D01*
G01X427670Y551045D01*
X427698Y551114D01*
Y551466D01*
X427670Y551535D01*
X427644Y551563D01*
G02Y553617I1096J1027D01*
G01X427670Y553645D01*
X427698Y553714D01*
G37*
G36*
G01X435372Y713482D02*
X435708D01*
X435775Y713507D01*
X435803Y713531D01*
G02X437777I987J-1131D01*
G01X437805Y713507D01*
X437872Y713482D01*
X438208D01*
X438275Y713507D01*
X438303Y713531D01*
G02X439290Y713901I987J-1131D01*
G02X440792Y712399I0J-1502D01*
G02X440386Y711372I-1502J0D01*
G01X440360Y711344D01*
X440332Y711275D01*
Y710923D01*
X440360Y710854D01*
X440386Y710826D01*
G02X440792Y709799I-1096J-1027D01*
G02X439290Y708297I-1502J0D01*
G02X438303Y708667I0J1501D01*
G01X438275Y708691D01*
X438208Y708716D01*
X437872D01*
X437805Y708691D01*
X437777Y708667D01*
G02X435803I-987J1131D01*
G01X435775Y708691D01*
X435708Y708716D01*
X435372D01*
X435305Y708691D01*
X435277Y708667D01*
G02X433303I-987J1131D01*
G01X433275Y708691D01*
X433208Y708716D01*
X432872D01*
X432805Y708691D01*
X432777Y708667D01*
G02X430803I-987J1131D01*
G01X430775Y708691D01*
X430708Y708716D01*
X430372D01*
X430305Y708691D01*
X430277Y708667D01*
G02X429290Y708297I-987J1131D01*
G02X428246Y708719I0J1502D01*
G01X428217Y708747D01*
X428145Y708776D01*
X427782Y708771D01*
X427710Y708740D01*
X427682Y708711D01*
G02X426607Y708258I-1075J1049D01*
G02X425105Y709760I0J1502D01*
G02X425511Y710787I1502J0D01*
G01X425537Y710815D01*
X425565Y710884D01*
Y711236D01*
X425537Y711305D01*
X425511Y711333D01*
G02X425105Y712360I1096J1027D01*
G02X426607Y713862I1502J0D01*
G02X427651Y713440I0J-1502D01*
G01X427680Y713412D01*
X427752Y713383D01*
X428115Y713388D01*
X428187Y713419D01*
X428215Y713448D01*
G02X429290Y713901I1075J-1049D01*
G02X430277Y713531I0J-1501D01*
G01X430305Y713507D01*
X430372Y713482D01*
X430708D01*
X430775Y713507D01*
X430803Y713531D01*
G02X432777I987J-1131D01*
G01X432805Y713507D01*
X432872Y713482D01*
X433208D01*
X433275Y713507D01*
X433303Y713531D01*
G02X435277I987J-1131D01*
G01X435305Y713507D01*
X435372Y713482D01*
G37*
G36*
G01X412349Y832776D02*
X412685D01*
X412752Y832801D01*
X412780Y832825D01*
G02X414754I987J-1131D01*
G01X414782Y832801D01*
X414849Y832776D01*
X415185D01*
X415252Y832801D01*
X415280Y832825D01*
G02X416267Y833195I987J-1131D01*
G02X417769Y831693I0J-1502D01*
G02X417399Y830706I-1501J0D01*
G01X417375Y830678D01*
X417350Y830611D01*
Y830275D01*
X417375Y830208D01*
X417399Y830180D01*
G02X417769Y829193I-1131J-987D01*
G02X416267Y827691I-1502J0D01*
G02X415280Y828061I0J1501D01*
G01X415252Y828085D01*
X415185Y828110D01*
X414849D01*
X414782Y828085D01*
X414754Y828061D01*
G02X412780I-987J1131D01*
G01X412752Y828085D01*
X412685Y828110D01*
X412349D01*
X412282Y828085D01*
X412254Y828061D01*
G02X411267Y827691I-987J1131D01*
G02X409765Y829193I0J1502D01*
G02X410135Y830180I1501J0D01*
G01X410159Y830208D01*
X410184Y830275D01*
Y830611D01*
X410159Y830678D01*
X410135Y830706D01*
G02X409765Y831693I1131J987D01*
G02X411267Y833195I1502J0D01*
G02X412254Y832825I0J-1501D01*
G01X412282Y832801D01*
X412349Y832776D01*
G37*
G36*
G01X409828Y868942D02*
X423102Y882216D01*
G03X423160Y882357I-142J141D01*
G01Y883981D01*
G02X426964I1902J0D01*
G01Y881487D01*
G02X426407Y880142I-1902J0D01*
G01X411902Y865637D01*
G02X410557Y865080I-1345J1345D01*
G01X406350D01*
G03X406199Y865011I0J-200D01*
G01X405972Y864749D01*
X405948Y864667D01*
X405954Y864623D01*
G02X405970Y864407I-1486J-219D01*
G02X402966I-1502J0D01*
G02X402982Y864623I1502J-3D01*
G01X402988Y864667D01*
X402964Y864749D01*
X402737Y865011D01*
G03X402586Y865080I-151J-131D01*
G01X399749D01*
G03X399608Y865022I0J-200D01*
G01X397651Y863064D01*
G02X396306Y862508I-1344J1346D01*
G02X394404Y864409I-1J1901D01*
G02X394961Y865754I1902J0D01*
G01X397534Y868327D01*
G02X398879Y868884I1345J-1345D01*
G01X404931D01*
G03X405089Y868961I0J200D01*
G01X405311Y869250D01*
X405329Y869339D01*
X405317Y869385D01*
G02X405268Y869767I1453J381D01*
G02X408272I1502J0D01*
G02X408223Y869385I-1502J-1D01*
G01X408211Y869339D01*
X408229Y869250D01*
X408451Y868961D01*
G03X408609Y868884I158J123D01*
G01X409687D01*
G03X409828Y868942I0J200D01*
G37*
G36*
G01X400038Y930768D02*
Y931104D01*
X400013Y931171D01*
X399989Y931199D01*
G02X399619Y932186I1131J987D01*
G02X402623I1502J0D01*
G02X402253Y931199I-1501J0D01*
G01X402229Y931171D01*
X402204Y931104D01*
Y930768D01*
X402229Y930701D01*
X402253Y930673D01*
G02X402623Y929686I-1131J-987D01*
G02X399619I-1502J0D01*
G02X399989Y930673I1501J0D01*
G01X400013Y930701D01*
X400038Y930768D01*
G37*
G36*
G01X408038D02*
Y931104D01*
X408013Y931171D01*
X407989Y931199D01*
G02X407619Y932186I1131J987D01*
G02X410623I1502J0D01*
G02X410253Y931199I-1501J0D01*
G01X410229Y931171D01*
X410204Y931104D01*
Y930768D01*
X410229Y930701D01*
X410253Y930673D01*
G02X410623Y929686I-1131J-987D01*
G02X407619I-1502J0D01*
G02X407989Y930673I1501J0D01*
G01X408013Y930701D01*
X408038Y930768D01*
G37*
G36*
G01X416038D02*
Y931104D01*
X416013Y931171D01*
X415989Y931199D01*
G02X415619Y932186I1131J987D01*
G02X418623I1502J0D01*
G02X418253Y931199I-1501J0D01*
G01X418229Y931171D01*
X418204Y931104D01*
Y930768D01*
X418229Y930701D01*
X418253Y930673D01*
G02X418623Y929686I-1131J-987D01*
G02X415619I-1502J0D01*
G02X415989Y930673I1501J0D01*
G01X416013Y930701D01*
X416038Y930768D01*
G37*
G36*
G01X424038D02*
Y931104D01*
X424013Y931171D01*
X423989Y931199D01*
G02X423619Y932186I1131J987D01*
G02X426623I1502J0D01*
G02X426253Y931199I-1501J0D01*
G01X426229Y931171D01*
X426204Y931104D01*
Y930768D01*
X426229Y930701D01*
X426253Y930673D01*
G02X426623Y929686I-1131J-987D01*
G02X423619I-1502J0D01*
G02X423989Y930673I1501J0D01*
G01X424013Y930701D01*
X424038Y930768D01*
G37*
G36*
G01X413084Y963303D02*
X413436D01*
X413505Y963331D01*
X413533Y963357D01*
G02X415587I1027J-1096D01*
G01X415615Y963331D01*
X415684Y963303D01*
X416036D01*
X416105Y963331D01*
X416133Y963357D01*
G02X417160Y963763I1027J-1096D01*
G02Y960759I0J-1502D01*
G02X416133Y961165I0J1502D01*
G01X416105Y961191D01*
X416036Y961219D01*
X415684D01*
X415615Y961191D01*
X415587Y961165D01*
G02X413533I-1027J1096D01*
G01X413505Y961191D01*
X413436Y961219D01*
X413084D01*
X413015Y961191D01*
X412987Y961165D01*
G02X411960Y960759I-1027J1096D01*
G02Y963763I0J1502D01*
G02X412987Y963357I0J-1502D01*
G01X413015Y963331D01*
X413084Y963303D01*
G37*
G36*
G01X403134Y976208D02*
Y976560D01*
X403106Y976629D01*
X403080Y976657D01*
G02X402674Y977684I1096J1027D01*
G02X405678I1502J0D01*
G02X405272Y976657I-1502J0D01*
G01X405246Y976629D01*
X405218Y976560D01*
Y976208D01*
X405246Y976139D01*
X405272Y976111D01*
G02Y974057I-1096J-1027D01*
G01X405246Y974029D01*
X405218Y973960D01*
Y973608D01*
X405246Y973539D01*
X405272Y973511D01*
G02X405678Y972484I-1096J-1027D01*
G02X405308Y971497I-1501J0D01*
G01X405284Y971469D01*
X405259Y971402D01*
Y971066D01*
X405284Y970999D01*
X405308Y970971D01*
G02X405678Y969984I-1131J-987D01*
G02X402674I-1502J0D01*
G02X403044Y970971I1501J0D01*
G01X403068Y970999D01*
X403093Y971066D01*
Y971402D01*
X403068Y971469D01*
X403044Y971497D01*
G02X402674Y972484I1131J987D01*
G02X403080Y973511I1502J0D01*
G01X403106Y973539D01*
X403134Y973608D01*
Y973960D01*
X403106Y974029D01*
X403080Y974057D01*
G02Y976111I1096J1027D01*
G01X403106Y976139D01*
X403134Y976208D01*
G37*
G36*
G01X412400Y979151D02*
X412752D01*
X412821Y979179D01*
X412849Y979205D01*
G02X414903I1027J-1096D01*
G01X414931Y979179D01*
X415000Y979151D01*
X415352D01*
X415421Y979179D01*
X415449Y979205D01*
G02X416476Y979611I1027J-1096D01*
G02Y976607I0J-1502D01*
G02X415449Y977013I0J1502D01*
G01X415421Y977039D01*
X415352Y977067D01*
X415000D01*
X414931Y977039D01*
X414903Y977013D01*
G02X412849I-1027J1096D01*
G01X412821Y977039D01*
X412752Y977067D01*
X412400D01*
X412331Y977039D01*
X412303Y977013D01*
G02X411276Y976607I-1027J1096D01*
G02Y979611I0J1502D01*
G02X412303Y979205I0J-1502D01*
G01X412331Y979179D01*
X412400Y979151D01*
G37*
G36*
G01X405478Y984012D02*
X405830D01*
X405899Y984040D01*
X405927Y984066D01*
G02X407981I1027J-1096D01*
G01X408009Y984040D01*
X408078Y984012D01*
X408430D01*
X408499Y984040D01*
X408527Y984066D01*
G02X409554Y984472I1027J-1096D01*
G02Y981468I0J-1502D01*
G02X408527Y981874I0J1502D01*
G01X408499Y981900D01*
X408430Y981928D01*
X408078D01*
X408009Y981900D01*
X407981Y981874D01*
G02X405927I-1027J1096D01*
G01X405899Y981900D01*
X405830Y981928D01*
X405478D01*
X405409Y981900D01*
X405381Y981874D01*
G02X404354Y981468I-1027J1096D01*
G02Y984472I0J1502D01*
G02X405381Y984066I0J-1502D01*
G01X405409Y984040D01*
X405478Y984012D01*
G37*
G36*
G01X505635Y984219D02*
X505341D01*
G03X505194Y984154I1J-200D01*
G02X504088Y983669I-1105J1017D01*
G02Y986673I0J1502D01*
G02X505194Y986188I1J-1502D01*
G03X505341Y986123I148J135D01*
G01X505635D01*
G03X505782Y986188I-1J200D01*
G02X506888Y986673I1105J-1017D01*
G02Y983669I0J-1502D01*
G02X505782Y984154I-1J1502D01*
G03X505635Y984219I-148J-135D01*
G37*
G36*
G01X471844Y1030987D02*
X472125Y1031185D01*
X472165Y1031246D01*
X472174Y1031283D01*
G02X473639Y1032454I1465J-331D01*
G02Y1029450I0J-1502D01*
G02X473461Y1029461I3J1502D01*
G01X473423Y1029465D01*
X473353Y1029447D01*
X473072Y1029249D01*
X473032Y1029188D01*
X473023Y1029151D01*
G02X471558Y1027980I-1465J331D01*
G02Y1030984I0J1502D01*
G02X471736Y1030973I-3J-1502D01*
G01X471774Y1030969D01*
X471844Y1030987D01*
G37*
G36*
G01X411129Y1061780D02*
X411465D01*
X411532Y1061805D01*
X411560Y1061829D01*
G02X413534I987J-1131D01*
G01X413562Y1061805D01*
X413629Y1061780D01*
X413965D01*
X414032Y1061805D01*
X414060Y1061829D01*
G02X415047Y1062199I987J-1131D01*
G02X416549Y1060697I0J-1502D01*
G02X416143Y1059670I-1502J0D01*
G01X416117Y1059642D01*
X416089Y1059573D01*
Y1059221D01*
X416117Y1059152D01*
X416143Y1059124D01*
G02X416549Y1058097I-1096J-1027D01*
G02X415047Y1056595I-1502J0D01*
G02X414060Y1056965I0J1501D01*
G01X414032Y1056989D01*
X413965Y1057014D01*
X413629D01*
X413562Y1056989D01*
X413534Y1056965D01*
G02X411560I-987J1131D01*
G01X411532Y1056989D01*
X411465Y1057014D01*
X411129D01*
X411062Y1056989D01*
X411034Y1056965D01*
G02X409060I-987J1131D01*
G01X409032Y1056989D01*
X408965Y1057014D01*
X408629D01*
X408562Y1056989D01*
X408534Y1056965D01*
G02X406560I-987J1131D01*
G01X406532Y1056989D01*
X406465Y1057014D01*
X406129D01*
X406062Y1056989D01*
X406034Y1056965D01*
G02X405047Y1056595I-987J1131D01*
G02X403545Y1058097I0J1502D01*
G02X403951Y1059124I1502J0D01*
G01X403977Y1059152D01*
X404005Y1059221D01*
Y1059573D01*
X403977Y1059642D01*
X403951Y1059670D01*
G02X403545Y1060697I1096J1027D01*
G02X405047Y1062199I1502J0D01*
G02X406034Y1061829I0J-1501D01*
G01X406062Y1061805D01*
X406129Y1061780D01*
X406465D01*
X406532Y1061805D01*
X406560Y1061829D01*
G02X408534I987J-1131D01*
G01X408562Y1061805D01*
X408629Y1061780D01*
X408965D01*
X409032Y1061805D01*
X409060Y1061829D01*
G02X411034I987J-1131D01*
G01X411062Y1061805D01*
X411129Y1061780D01*
G37*
G36*
G01X499259D02*
X499595D01*
X499662Y1061805D01*
X499690Y1061829D01*
G02X501664I987J-1131D01*
G01X501692Y1061805D01*
X501759Y1061780D01*
X502095D01*
X502162Y1061805D01*
X502190Y1061829D01*
G02X503177Y1062199I987J-1131D01*
G02X504679Y1060697I0J-1502D01*
G02X504273Y1059670I-1502J0D01*
G01X504247Y1059642D01*
X504219Y1059573D01*
Y1059221D01*
X504247Y1059152D01*
X504273Y1059124D01*
G02X504679Y1058097I-1096J-1027D01*
G02X503177Y1056595I-1502J0D01*
G02X502190Y1056965I0J1501D01*
G01X502162Y1056989D01*
X502095Y1057014D01*
X501759D01*
X501692Y1056989D01*
X501664Y1056965D01*
G02X499690I-987J1131D01*
G01X499662Y1056989D01*
X499595Y1057014D01*
X499259D01*
X499192Y1056989D01*
X499164Y1056965D01*
G02X497190I-987J1131D01*
G01X497162Y1056989D01*
X497095Y1057014D01*
X496759D01*
X496692Y1056989D01*
X496664Y1056965D01*
G02X494690I-987J1131D01*
G01X494662Y1056989D01*
X494595Y1057014D01*
X494259D01*
X494192Y1056989D01*
X494164Y1056965D01*
G02X493177Y1056595I-987J1131D01*
G02X491675Y1058097I0J1502D01*
G02X492081Y1059124I1502J0D01*
G01X492107Y1059152D01*
X492135Y1059221D01*
Y1059573D01*
X492107Y1059642D01*
X492081Y1059670D01*
G02X491675Y1060697I1096J1027D01*
G02X493177Y1062199I1502J0D01*
G02X494164Y1061829I0J-1501D01*
G01X494192Y1061805D01*
X494259Y1061780D01*
X494595D01*
X494662Y1061805D01*
X494690Y1061829D01*
G02X496664I987J-1131D01*
G01X496692Y1061805D01*
X496759Y1061780D01*
X497095D01*
X497162Y1061805D01*
X497190Y1061829D01*
G02X499164I987J-1131D01*
G01X499192Y1061805D01*
X499259Y1061780D01*
G37*
G36*
G01X497585Y1087879D02*
X497921D01*
X497988Y1087904D01*
X498016Y1087928D01*
G02X499990I987J-1131D01*
G01X500018Y1087904D01*
X500085Y1087879D01*
X500421D01*
X500488Y1087904D01*
X500516Y1087928D01*
G02X501503Y1088298I987J-1131D01*
G02X503005Y1086796I0J-1502D01*
G02X502635Y1085809I-1501J0D01*
G01X502611Y1085781D01*
X502586Y1085714D01*
Y1085378D01*
X502611Y1085311D01*
X502635Y1085283D01*
G02X503005Y1084296I-1131J-987D01*
G02X501503Y1082794I-1502J0D01*
G02X500516Y1083164I0J1501D01*
G01X500488Y1083188D01*
X500421Y1083213D01*
X500085D01*
X500018Y1083188D01*
X499990Y1083164D01*
G02X498016I-987J1131D01*
G01X497988Y1083188D01*
X497921Y1083213D01*
X497585D01*
X497518Y1083188D01*
X497490Y1083164D01*
G02X495516I-987J1131D01*
G01X495488Y1083188D01*
X495421Y1083213D01*
X495085D01*
X495018Y1083188D01*
X494990Y1083164D01*
G02X493016I-987J1131D01*
G01X492988Y1083188D01*
X492921Y1083213D01*
X492585D01*
X492518Y1083188D01*
X492490Y1083164D01*
G02X491503Y1082794I-987J1131D01*
G02X490001Y1084296I0J1502D01*
G02X490371Y1085283I1501J0D01*
G01X490395Y1085311D01*
X490420Y1085378D01*
Y1085714D01*
X490395Y1085781D01*
X490371Y1085809D01*
G02X490001Y1086796I1131J987D01*
G02X491503Y1088298I1502J0D01*
G02X492490Y1087928I0J-1501D01*
G01X492518Y1087904D01*
X492585Y1087879D01*
X492921D01*
X492988Y1087904D01*
X493016Y1087928D01*
G02X494990I987J-1131D01*
G01X495018Y1087904D01*
X495085Y1087879D01*
X495421D01*
X495488Y1087904D01*
X495516Y1087928D01*
G02X497490I987J-1131D01*
G01X497518Y1087904D01*
X497585Y1087879D01*
G37*
G36*
G01X500879Y1091541D02*
Y1091835D01*
G03X500814Y1091982I-200J-1D01*
G02X500329Y1093088I1017J1105D01*
G02X503333I1502J0D01*
G02X502848Y1091982I-1502J-1D01*
G03X502783Y1091835I135J-148D01*
G01Y1091541D01*
G03X502848Y1091394I200J1D01*
G02X503333Y1090288I-1017J-1105D01*
G02X500329I-1502J0D01*
G02X500814Y1091394I1502J1D01*
G03X500879Y1091541I-135J148D01*
G37*
G36*
G01X479085Y1112565D02*
X478749D01*
X478682Y1112540D01*
X478654Y1112516D01*
G02X477667Y1112146I-987J1131D01*
G02Y1115150I0J1502D01*
G02X478654Y1114780I0J-1501D01*
G01X478682Y1114756D01*
X478749Y1114731D01*
X479085D01*
X479152Y1114756D01*
X479180Y1114780D01*
G02X480167Y1115150I987J-1131D01*
G02Y1112146I0J-1502D01*
G02X479180Y1112516I0J1501D01*
G01X479152Y1112540D01*
X479085Y1112565D01*
G37*
G36*
G01X511213D02*
X510877D01*
X510810Y1112540D01*
X510782Y1112516D01*
G02X509795Y1112146I-987J1131D01*
G02Y1115150I0J1502D01*
G02X510782Y1114780I0J-1501D01*
G01X510810Y1114756D01*
X510877Y1114731D01*
X511213D01*
X511280Y1114756D01*
X511308Y1114780D01*
G02X512295Y1115150I987J-1131D01*
G02Y1112146I0J-1502D01*
G02X511308Y1112516I0J1501D01*
G01X511280Y1112540D01*
X511213Y1112565D01*
G37*
G36*
G01X407878Y1173466D02*
Y1173802D01*
X407853Y1173869D01*
X407829Y1173897D01*
G02X407459Y1174884I1131J987D01*
G02X408961Y1176386I1502J0D01*
G02X409948Y1176016I0J-1501D01*
G01X409976Y1175992D01*
X410043Y1175967D01*
X410379D01*
X410446Y1175992D01*
X410474Y1176016D01*
G02X411461Y1176386I987J-1131D01*
G02X412963Y1174884I0J-1502D01*
G02X412593Y1173897I-1501J0D01*
G01X412569Y1173869D01*
X412544Y1173802D01*
Y1173466D01*
X412569Y1173399D01*
X412593Y1173371D01*
G02Y1171397I-1131J-987D01*
G01X412569Y1171369D01*
X412544Y1171302D01*
Y1170966D01*
X412569Y1170899D01*
X412593Y1170871D01*
G02Y1168897I-1131J-987D01*
G01X412569Y1168869D01*
X412544Y1168802D01*
Y1168466D01*
X412569Y1168399D01*
X412593Y1168371D01*
G02Y1166397I-1131J-987D01*
G01X412569Y1166369D01*
X412544Y1166302D01*
Y1165966D01*
X412569Y1165899D01*
X412593Y1165871D01*
G02Y1163897I-1131J-987D01*
G01X412569Y1163869D01*
X412544Y1163802D01*
Y1163466D01*
X412569Y1163399D01*
X412593Y1163371D01*
G02X412963Y1162384I-1131J-987D01*
G02X411461Y1160882I-1502J0D01*
G02X410474Y1161252I0J1501D01*
G01X410446Y1161276D01*
X410379Y1161301D01*
X410043D01*
X409976Y1161276D01*
X409948Y1161252D01*
G02X408961Y1160882I-987J1131D01*
G02X407459Y1162384I0J1502D01*
G02X407829Y1163371I1501J0D01*
G01X407853Y1163399D01*
X407878Y1163466D01*
Y1163802D01*
X407853Y1163869D01*
X407829Y1163897D01*
G02Y1165871I1131J987D01*
G01X407853Y1165899D01*
X407878Y1165966D01*
Y1166302D01*
X407853Y1166369D01*
X407829Y1166397D01*
G02Y1168371I1131J987D01*
G01X407853Y1168399D01*
X407878Y1168466D01*
Y1168802D01*
X407853Y1168869D01*
X407829Y1168897D01*
G02Y1170871I1131J987D01*
G01X407853Y1170899D01*
X407878Y1170966D01*
Y1171302D01*
X407853Y1171369D01*
X407829Y1171397D01*
G02Y1173371I1131J987D01*
G01X407853Y1173399D01*
X407878Y1173466D01*
G37*
G36*
G01X435706D02*
Y1173802D01*
X435681Y1173869D01*
X435657Y1173897D01*
G02X435287Y1174884I1131J987D01*
G02X436789Y1176386I1502J0D01*
G02X437776Y1176016I0J-1501D01*
G01X437804Y1175992D01*
X437871Y1175967D01*
X438207D01*
X438274Y1175992D01*
X438302Y1176016D01*
G02X439289Y1176386I987J-1131D01*
G02X440791Y1174884I0J-1502D01*
G02X440421Y1173897I-1501J0D01*
G01X440397Y1173869D01*
X440372Y1173802D01*
Y1173466D01*
X440397Y1173399D01*
X440421Y1173371D01*
G02Y1171397I-1131J-987D01*
G01X440397Y1171369D01*
X440372Y1171302D01*
Y1170966D01*
X440397Y1170899D01*
X440421Y1170871D01*
G02Y1168897I-1131J-987D01*
G01X440397Y1168869D01*
X440372Y1168802D01*
Y1168466D01*
X440397Y1168399D01*
X440421Y1168371D01*
G02Y1166397I-1131J-987D01*
G01X440397Y1166369D01*
X440372Y1166302D01*
Y1165966D01*
X440397Y1165899D01*
X440421Y1165871D01*
G02Y1163897I-1131J-987D01*
G01X440397Y1163869D01*
X440372Y1163802D01*
Y1163466D01*
X440397Y1163399D01*
X440421Y1163371D01*
G02X440791Y1162384I-1131J-987D01*
G02X439289Y1160882I-1502J0D01*
G02X438302Y1161252I0J1501D01*
G01X438274Y1161276D01*
X438207Y1161301D01*
X437871D01*
X437804Y1161276D01*
X437776Y1161252D01*
G02X436789Y1160882I-987J1131D01*
G02X435287Y1162384I0J1502D01*
G02X435657Y1163371I1501J0D01*
G01X435681Y1163399D01*
X435706Y1163466D01*
Y1163802D01*
X435681Y1163869D01*
X435657Y1163897D01*
G02Y1165871I1131J987D01*
G01X435681Y1165899D01*
X435706Y1165966D01*
Y1166302D01*
X435681Y1166369D01*
X435657Y1166397D01*
G02Y1168371I1131J987D01*
G01X435681Y1168399D01*
X435706Y1168466D01*
Y1168802D01*
X435681Y1168869D01*
X435657Y1168897D01*
G02Y1170871I1131J987D01*
G01X435681Y1170899D01*
X435706Y1170966D01*
Y1171302D01*
X435681Y1171369D01*
X435657Y1171397D01*
G02Y1173371I1131J987D01*
G01X435681Y1173399D01*
X435706Y1173466D01*
G37*
G36*
G01X473465D02*
Y1173802D01*
X473440Y1173869D01*
X473416Y1173897D01*
G02X473046Y1174884I1131J987D01*
G02X474548Y1176386I1502J0D01*
G02X475535Y1176016I0J-1501D01*
G01X475563Y1175992D01*
X475630Y1175967D01*
X475966D01*
X476033Y1175992D01*
X476061Y1176016D01*
G02X477048Y1176386I987J-1131D01*
G02X478550Y1174884I0J-1502D01*
G02X478180Y1173897I-1501J0D01*
G01X478156Y1173869D01*
X478131Y1173802D01*
Y1173466D01*
X478156Y1173399D01*
X478180Y1173371D01*
G02Y1171397I-1131J-987D01*
G01X478156Y1171369D01*
X478131Y1171302D01*
Y1170966D01*
X478156Y1170899D01*
X478180Y1170871D01*
G02Y1168897I-1131J-987D01*
G01X478156Y1168869D01*
X478131Y1168802D01*
Y1168466D01*
X478156Y1168399D01*
X478180Y1168371D01*
G02Y1166397I-1131J-987D01*
G01X478156Y1166369D01*
X478131Y1166302D01*
Y1165966D01*
X478156Y1165899D01*
X478180Y1165871D01*
G02Y1163897I-1131J-987D01*
G01X478156Y1163869D01*
X478131Y1163802D01*
Y1163466D01*
X478156Y1163399D01*
X478180Y1163371D01*
G02X478550Y1162384I-1131J-987D01*
G02X477048Y1160882I-1502J0D01*
G02X476061Y1161252I0J1501D01*
G01X476033Y1161276D01*
X475966Y1161301D01*
X475630D01*
X475563Y1161276D01*
X475535Y1161252D01*
G02X474548Y1160882I-987J1131D01*
G02X473046Y1162384I0J1502D01*
G02X473416Y1163371I1501J0D01*
G01X473440Y1163399D01*
X473465Y1163466D01*
Y1163802D01*
X473440Y1163869D01*
X473416Y1163897D01*
G02Y1165871I1131J987D01*
G01X473440Y1165899D01*
X473465Y1165966D01*
Y1166302D01*
X473440Y1166369D01*
X473416Y1166397D01*
G02Y1168371I1131J987D01*
G01X473440Y1168399D01*
X473465Y1168466D01*
Y1168802D01*
X473440Y1168869D01*
X473416Y1168897D01*
G02Y1170871I1131J987D01*
G01X473440Y1170899D01*
X473465Y1170966D01*
Y1171302D01*
X473440Y1171369D01*
X473416Y1171397D01*
G02Y1173371I1131J987D01*
G01X473440Y1173399D01*
X473465Y1173466D01*
G37*
G36*
G01X501293D02*
Y1173802D01*
X501268Y1173869D01*
X501244Y1173897D01*
G02X500874Y1174884I1131J987D01*
G02X502376Y1176386I1502J0D01*
G02X503363Y1176016I0J-1501D01*
G01X503391Y1175992D01*
X503458Y1175967D01*
X503794D01*
X503861Y1175992D01*
X503889Y1176016D01*
G02X504876Y1176386I987J-1131D01*
G02X506378Y1174884I0J-1502D01*
G02X506008Y1173897I-1501J0D01*
G01X505984Y1173869D01*
X505959Y1173802D01*
Y1173466D01*
X505984Y1173399D01*
X506008Y1173371D01*
G02Y1171397I-1131J-987D01*
G01X505984Y1171369D01*
X505959Y1171302D01*
Y1170966D01*
X505984Y1170899D01*
X506008Y1170871D01*
G02Y1168897I-1131J-987D01*
G01X505984Y1168869D01*
X505959Y1168802D01*
Y1168466D01*
X505984Y1168399D01*
X506008Y1168371D01*
G02Y1166397I-1131J-987D01*
G01X505984Y1166369D01*
X505959Y1166302D01*
Y1165966D01*
X505984Y1165899D01*
X506008Y1165871D01*
G02Y1163897I-1131J-987D01*
G01X505984Y1163869D01*
X505959Y1163802D01*
Y1163466D01*
X505984Y1163399D01*
X506008Y1163371D01*
G02X506378Y1162384I-1131J-987D01*
G02X504876Y1160882I-1502J0D01*
G02X503889Y1161252I0J1501D01*
G01X503861Y1161276D01*
X503794Y1161301D01*
X503458D01*
X503391Y1161276D01*
X503363Y1161252D01*
G02X502376Y1160882I-987J1131D01*
G02X500874Y1162384I0J1502D01*
G02X501244Y1163371I1501J0D01*
G01X501268Y1163399D01*
X501293Y1163466D01*
Y1163802D01*
X501268Y1163869D01*
X501244Y1163897D01*
G02Y1165871I1131J987D01*
G01X501268Y1165899D01*
X501293Y1165966D01*
Y1166302D01*
X501268Y1166369D01*
X501244Y1166397D01*
G02Y1168371I1131J987D01*
G01X501268Y1168399D01*
X501293Y1168466D01*
Y1168802D01*
X501268Y1168869D01*
X501244Y1168897D01*
G02Y1170871I1131J987D01*
G01X501268Y1170899D01*
X501293Y1170966D01*
Y1171302D01*
X501268Y1171369D01*
X501244Y1171397D01*
G02Y1173371I1131J987D01*
G01X501268Y1173399D01*
X501293Y1173466D01*
G37*
G36*
G01X405236Y1185291D02*
Y1185627D01*
X405211Y1185694D01*
X405187Y1185722D01*
G02X404817Y1186709I1131J987D01*
G02X407821I1502J0D01*
G02X407451Y1185722I-1501J0D01*
G01X407427Y1185694D01*
X407402Y1185627D01*
Y1185291D01*
X407427Y1185224D01*
X407451Y1185196D01*
G02Y1183222I-1131J-987D01*
G01X407427Y1183194D01*
X407402Y1183127D01*
Y1182791D01*
X407427Y1182724D01*
X407451Y1182696D01*
G02Y1180722I-1131J-987D01*
G01X407427Y1180694D01*
X407402Y1180627D01*
Y1180291D01*
X407427Y1180224D01*
X407451Y1180196D01*
G02X407821Y1179209I-1131J-987D01*
G02X404817I-1502J0D01*
G02X405187Y1180196I1501J0D01*
G01X405211Y1180224D01*
X405236Y1180291D01*
Y1180627D01*
X405211Y1180694D01*
X405187Y1180722D01*
G02Y1182696I1131J987D01*
G01X405211Y1182724D01*
X405236Y1182791D01*
Y1183127D01*
X405211Y1183194D01*
X405187Y1183222D01*
G02Y1185196I1131J987D01*
G01X405211Y1185224D01*
X405236Y1185291D01*
G37*
G36*
G01X432166D02*
Y1185627D01*
X432141Y1185694D01*
X432117Y1185722D01*
G02X431747Y1186709I1131J987D01*
G02X434751I1502J0D01*
G02X434381Y1185722I-1501J0D01*
G01X434357Y1185694D01*
X434332Y1185627D01*
Y1185291D01*
X434357Y1185224D01*
X434381Y1185196D01*
G02Y1183222I-1131J-987D01*
G01X434357Y1183194D01*
X434332Y1183127D01*
Y1182791D01*
X434357Y1182724D01*
X434381Y1182696D01*
G02Y1180722I-1131J-987D01*
G01X434357Y1180694D01*
X434332Y1180627D01*
Y1180291D01*
X434357Y1180224D01*
X434381Y1180196D01*
G02X434751Y1179209I-1131J-987D01*
G02X431747I-1502J0D01*
G02X432117Y1180196I1501J0D01*
G01X432141Y1180224D01*
X432166Y1180291D01*
Y1180627D01*
X432141Y1180694D01*
X432117Y1180722D01*
G02Y1182696I1131J987D01*
G01X432141Y1182724D01*
X432166Y1182791D01*
Y1183127D01*
X432141Y1183194D01*
X432117Y1183222D01*
G02Y1185196I1131J987D01*
G01X432141Y1185224D01*
X432166Y1185291D01*
G37*
G36*
G01X478438D02*
Y1185627D01*
X478413Y1185694D01*
X478389Y1185722D01*
G02X478019Y1186709I1131J987D01*
G02X481023I1502J0D01*
G02X480653Y1185722I-1501J0D01*
G01X480629Y1185694D01*
X480604Y1185627D01*
Y1185291D01*
X480629Y1185224D01*
X480653Y1185196D01*
G02Y1183222I-1131J-987D01*
G01X480629Y1183194D01*
X480604Y1183127D01*
Y1182791D01*
X480629Y1182724D01*
X480653Y1182696D01*
G02Y1180722I-1131J-987D01*
G01X480629Y1180694D01*
X480604Y1180627D01*
Y1180291D01*
X480629Y1180224D01*
X480653Y1180196D01*
G02X481023Y1179209I-1131J-987D01*
G02X478019I-1502J0D01*
G02X478389Y1180196I1501J0D01*
G01X478413Y1180224D01*
X478438Y1180291D01*
Y1180627D01*
X478413Y1180694D01*
X478389Y1180722D01*
G02Y1182696I1131J987D01*
G01X478413Y1182724D01*
X478438Y1182791D01*
Y1183127D01*
X478413Y1183194D01*
X478389Y1183222D01*
G02Y1185196I1131J987D01*
G01X478413Y1185224D01*
X478438Y1185291D01*
G37*
G36*
G01X505368D02*
Y1185627D01*
X505343Y1185694D01*
X505319Y1185722D01*
G02X504949Y1186709I1131J987D01*
G02X507953I1502J0D01*
G02X507583Y1185722I-1501J0D01*
G01X507559Y1185694D01*
X507534Y1185627D01*
Y1185291D01*
X507559Y1185224D01*
X507583Y1185196D01*
G02Y1183222I-1131J-987D01*
G01X507559Y1183194D01*
X507534Y1183127D01*
Y1182791D01*
X507559Y1182724D01*
X507583Y1182696D01*
G02Y1180722I-1131J-987D01*
G01X507559Y1180694D01*
X507534Y1180627D01*
Y1180291D01*
X507559Y1180224D01*
X507583Y1180196D01*
G02X507953Y1179209I-1131J-987D01*
G02X504949I-1502J0D01*
G02X505319Y1180196I1501J0D01*
G01X505343Y1180224D01*
X505368Y1180291D01*
Y1180627D01*
X505343Y1180694D01*
X505319Y1180722D01*
G02Y1182696I1131J987D01*
G01X505343Y1182724D01*
X505368Y1182791D01*
Y1183127D01*
X505343Y1183194D01*
X505319Y1183222D01*
G02Y1185196I1131J987D01*
G01X505343Y1185224D01*
X505368Y1185291D01*
G37*
G36*
G01X419536Y1185503D02*
Y1185839D01*
X419511Y1185906D01*
X419487Y1185934D01*
G02X419117Y1186921I1131J987D01*
G02X422121I1502J0D01*
G02X421751Y1185934I-1501J0D01*
G01X421727Y1185906D01*
X421702Y1185839D01*
Y1185503D01*
X421727Y1185436D01*
X421751Y1185408D01*
G02Y1183434I-1131J-987D01*
G01X421727Y1183406D01*
X421702Y1183339D01*
Y1183003D01*
X421727Y1182936D01*
X421751Y1182908D01*
G02Y1180934I-1131J-987D01*
G01X421727Y1180906D01*
X421702Y1180839D01*
Y1180503D01*
X421727Y1180436D01*
X421751Y1180408D01*
G02X422121Y1179421I-1131J-987D01*
G02X419117I-1502J0D01*
G02X419487Y1180408I1501J0D01*
G01X419511Y1180436D01*
X419536Y1180503D01*
Y1180839D01*
X419511Y1180906D01*
X419487Y1180934D01*
G02Y1182908I1131J987D01*
G01X419511Y1182936D01*
X419536Y1183003D01*
Y1183339D01*
X419511Y1183406D01*
X419487Y1183434D01*
G02Y1185408I1131J987D01*
G01X419511Y1185436D01*
X419536Y1185503D01*
G37*
G36*
G01X446466D02*
Y1185839D01*
X446441Y1185906D01*
X446417Y1185934D01*
G02X446047Y1186921I1131J987D01*
G02X449051I1502J0D01*
G02X448681Y1185934I-1501J0D01*
G01X448657Y1185906D01*
X448632Y1185839D01*
Y1185503D01*
X448657Y1185436D01*
X448681Y1185408D01*
G02Y1183434I-1131J-987D01*
G01X448657Y1183406D01*
X448632Y1183339D01*
Y1183003D01*
X448657Y1182936D01*
X448681Y1182908D01*
G02Y1180934I-1131J-987D01*
G01X448657Y1180906D01*
X448632Y1180839D01*
Y1180503D01*
X448657Y1180436D01*
X448681Y1180408D01*
G02X449051Y1179421I-1131J-987D01*
G02X446047I-1502J0D01*
G02X446417Y1180408I1501J0D01*
G01X446441Y1180436D01*
X446466Y1180503D01*
Y1180839D01*
X446441Y1180906D01*
X446417Y1180934D01*
G02Y1182908I1131J987D01*
G01X446441Y1182936D01*
X446466Y1183003D01*
Y1183339D01*
X446441Y1183406D01*
X446417Y1183434D01*
G02Y1185408I1131J987D01*
G01X446441Y1185436D01*
X446466Y1185503D01*
G37*
G36*
G01X492738D02*
Y1185839D01*
X492713Y1185906D01*
X492689Y1185934D01*
G02X492319Y1186921I1131J987D01*
G02X495323I1502J0D01*
G02X494953Y1185934I-1501J0D01*
G01X494929Y1185906D01*
X494904Y1185839D01*
Y1185503D01*
X494929Y1185436D01*
X494953Y1185408D01*
G02Y1183434I-1131J-987D01*
G01X494929Y1183406D01*
X494904Y1183339D01*
Y1183003D01*
X494929Y1182936D01*
X494953Y1182908D01*
G02Y1180934I-1131J-987D01*
G01X494929Y1180906D01*
X494904Y1180839D01*
Y1180503D01*
X494929Y1180436D01*
X494953Y1180408D01*
G02X495323Y1179421I-1131J-987D01*
G02X492319I-1502J0D01*
G02X492689Y1180408I1501J0D01*
G01X492713Y1180436D01*
X492738Y1180503D01*
Y1180839D01*
X492713Y1180906D01*
X492689Y1180934D01*
G02Y1182908I1131J987D01*
G01X492713Y1182936D01*
X492738Y1183003D01*
Y1183339D01*
X492713Y1183406D01*
X492689Y1183434D01*
G02Y1185408I1131J987D01*
G01X492713Y1185436D01*
X492738Y1185503D01*
G37*
G36*
G01X519668D02*
Y1185839D01*
X519643Y1185906D01*
X519619Y1185934D01*
G02X519249Y1186921I1131J987D01*
G02X522253I1502J0D01*
G02X521883Y1185934I-1501J0D01*
G01X521859Y1185906D01*
X521834Y1185839D01*
Y1185503D01*
X521859Y1185436D01*
X521883Y1185408D01*
G02Y1183434I-1131J-987D01*
G01X521859Y1183406D01*
X521834Y1183339D01*
Y1183003D01*
X521859Y1182936D01*
X521883Y1182908D01*
G02Y1180934I-1131J-987D01*
G01X521859Y1180906D01*
X521834Y1180839D01*
Y1180503D01*
X521859Y1180436D01*
X521883Y1180408D01*
G02X522253Y1179421I-1131J-987D01*
G02X519249I-1502J0D01*
G02X519619Y1180408I1501J0D01*
G01X519643Y1180436D01*
X519668Y1180503D01*
Y1180839D01*
X519643Y1180906D01*
X519619Y1180934D01*
G02Y1182908I1131J987D01*
G01X519643Y1182936D01*
X519668Y1183003D01*
Y1183339D01*
X519643Y1183406D01*
X519619Y1183434D01*
G02Y1185408I1131J987D01*
G01X519643Y1185436D01*
X519668Y1185503D01*
G37*
G36*
G01X402921Y1191203D02*
Y1191539D01*
X402896Y1191606D01*
X402872Y1191634D01*
G02X402502Y1192621I1131J987D01*
G02X405506I1502J0D01*
G02X405136Y1191634I-1501J0D01*
G01X405112Y1191606D01*
X405087Y1191539D01*
Y1191203D01*
X405112Y1191136D01*
X405136Y1191108D01*
G02X405506Y1190121I-1131J-987D01*
G02X402502I-1502J0D01*
G02X402872Y1191108I1501J0D01*
G01X402896Y1191136D01*
X402921Y1191203D01*
G37*
G36*
G01X416386D02*
Y1191539D01*
X416361Y1191606D01*
X416337Y1191634D01*
G02X415967Y1192621I1131J987D01*
G02X418971I1502J0D01*
G02X418601Y1191634I-1501J0D01*
G01X418577Y1191606D01*
X418552Y1191539D01*
Y1191203D01*
X418577Y1191136D01*
X418601Y1191108D01*
G02X418971Y1190121I-1131J-987D01*
G02X415967I-1502J0D01*
G02X416337Y1191108I1501J0D01*
G01X416361Y1191136D01*
X416386Y1191203D01*
G37*
G36*
G01X421851D02*
Y1191539D01*
X421826Y1191606D01*
X421802Y1191634D01*
G02X421432Y1192621I1131J987D01*
G02X424436I1502J0D01*
G02X424066Y1191634I-1501J0D01*
G01X424042Y1191606D01*
X424017Y1191539D01*
Y1191203D01*
X424042Y1191136D01*
X424066Y1191108D01*
G02X424436Y1190121I-1131J-987D01*
G02X421432I-1502J0D01*
G02X421802Y1191108I1501J0D01*
G01X421826Y1191136D01*
X421851Y1191203D01*
G37*
G36*
G01X429851D02*
Y1191539D01*
X429826Y1191606D01*
X429802Y1191634D01*
G02X429432Y1192621I1131J987D01*
G02X432436I1502J0D01*
G02X432066Y1191634I-1501J0D01*
G01X432042Y1191606D01*
X432017Y1191539D01*
Y1191203D01*
X432042Y1191136D01*
X432066Y1191108D01*
G02X432436Y1190121I-1131J-987D01*
G02X429432I-1502J0D01*
G02X429802Y1191108I1501J0D01*
G01X429826Y1191136D01*
X429851Y1191203D01*
G37*
G36*
G01X448781D02*
Y1191539D01*
X448756Y1191606D01*
X448732Y1191634D01*
G02X448362Y1192621I1131J987D01*
G02X451366I1502J0D01*
G02X450996Y1191634I-1501J0D01*
G01X450972Y1191606D01*
X450947Y1191539D01*
Y1191203D01*
X450972Y1191136D01*
X450996Y1191108D01*
G02X451366Y1190121I-1131J-987D01*
G02X448362I-1502J0D01*
G02X448732Y1191108I1501J0D01*
G01X448756Y1191136D01*
X448781Y1191203D01*
G37*
G36*
G01X476123D02*
Y1191539D01*
X476098Y1191606D01*
X476074Y1191634D01*
G02X475704Y1192621I1131J987D01*
G02X478708I1502J0D01*
G02X478338Y1191634I-1501J0D01*
G01X478314Y1191606D01*
X478289Y1191539D01*
Y1191203D01*
X478314Y1191136D01*
X478338Y1191108D01*
G02X478708Y1190121I-1131J-987D01*
G02X475704I-1502J0D01*
G02X476074Y1191108I1501J0D01*
G01X476098Y1191136D01*
X476123Y1191203D01*
G37*
G36*
G01X489588D02*
Y1191539D01*
X489563Y1191606D01*
X489539Y1191634D01*
G02X489169Y1192621I1131J987D01*
G02X492173I1502J0D01*
G02X491803Y1191634I-1501J0D01*
G01X491779Y1191606D01*
X491754Y1191539D01*
Y1191203D01*
X491779Y1191136D01*
X491803Y1191108D01*
G02X492173Y1190121I-1131J-987D01*
G02X489169I-1502J0D01*
G02X489539Y1191108I1501J0D01*
G01X489563Y1191136D01*
X489588Y1191203D01*
G37*
G36*
G01X495053D02*
Y1191539D01*
X495028Y1191606D01*
X495004Y1191634D01*
G02X494634Y1192621I1131J987D01*
G02X497638I1502J0D01*
G02X497268Y1191634I-1501J0D01*
G01X497244Y1191606D01*
X497219Y1191539D01*
Y1191203D01*
X497244Y1191136D01*
X497268Y1191108D01*
G02X497638Y1190121I-1131J-987D01*
G02X494634I-1502J0D01*
G02X495004Y1191108I1501J0D01*
G01X495028Y1191136D01*
X495053Y1191203D01*
G37*
G36*
G01X503053D02*
Y1191539D01*
X503028Y1191606D01*
X503004Y1191634D01*
G02X502634Y1192621I1131J987D01*
G02X505638I1502J0D01*
G02X505268Y1191634I-1501J0D01*
G01X505244Y1191606D01*
X505219Y1191539D01*
Y1191203D01*
X505244Y1191136D01*
X505268Y1191108D01*
G02X505638Y1190121I-1131J-987D01*
G02X502634I-1502J0D01*
G02X503004Y1191108I1501J0D01*
G01X503028Y1191136D01*
X503053Y1191203D01*
G37*
G36*
G01X521983D02*
Y1191539D01*
X521958Y1191606D01*
X521934Y1191634D01*
G02X521564Y1192621I1131J987D01*
G02X524568I1502J0D01*
G02X524198Y1191634I-1501J0D01*
G01X524174Y1191606D01*
X524149Y1191539D01*
Y1191203D01*
X524174Y1191136D01*
X524198Y1191108D01*
G02X524568Y1190121I-1131J-987D01*
G02X521564I-1502J0D01*
G02X521934Y1191108I1501J0D01*
G01X521958Y1191136D01*
X521983Y1191203D01*
G37*
G36*
G01X445044Y1261006D02*
X445360D01*
G03X445517Y1261083I-1J200D01*
G02X447887I1185J-923D01*
G03X448044Y1261006I158J123D01*
G01X448360D01*
G03X448517Y1261083I-1J200D01*
G02X449702Y1261662I1185J-923D01*
G02X451204Y1260160I0J-1502D01*
G02X450625Y1258975I-1502J0D01*
G03X450548Y1258818I123J-158D01*
G01Y1258502D01*
G03X450625Y1258345I200J1D01*
G02X451204Y1257160I-923J-1185D01*
G02X449702Y1255658I-1502J0D01*
G02X448517Y1256237I0J1502D01*
G03X448360Y1256314I-158J-123D01*
G01X448044D01*
G03X447887Y1256237I1J-200D01*
G02X445517I-1185J923D01*
G03X445360Y1256314I-158J-123D01*
G01X445044D01*
G03X444887Y1256237I1J-200D01*
G02X442517I-1185J923D01*
G03X442360Y1256314I-158J-123D01*
G01X442044D01*
G03X441887Y1256237I1J-200D01*
G02X439517I-1185J923D01*
G03X439360Y1256314I-158J-123D01*
G01X439044D01*
G03X438887Y1256237I1J-200D01*
G02X436517I-1185J923D01*
G03X436360Y1256314I-158J-123D01*
G01X436044D01*
G03X435887Y1256237I1J-200D01*
G02X433517I-1185J923D01*
G03X433360Y1256314I-158J-123D01*
G01X433044D01*
G03X432887Y1256237I1J-200D01*
G02X430517I-1185J923D01*
G03X430360Y1256314I-158J-123D01*
G01X430044D01*
G03X429887Y1256237I1J-200D01*
G02X427517I-1185J923D01*
G03X427360Y1256314I-158J-123D01*
G01X427044D01*
G03X426887Y1256237I1J-200D01*
G02X424517I-1185J923D01*
G03X424360Y1256314I-158J-123D01*
G01X424044D01*
G03X423887Y1256237I1J-200D01*
G02X421517I-1185J923D01*
G03X421360Y1256314I-158J-123D01*
G01X421044D01*
G03X420887Y1256237I1J-200D01*
G02X419702Y1255658I-1185J923D01*
G02X418200Y1257160I0J1502D01*
G02X418779Y1258345I1502J0D01*
G03X418856Y1258502I-123J158D01*
G01Y1258818D01*
G03X418779Y1258975I-200J-1D01*
G02X418200Y1260160I923J1185D01*
G02X419702Y1261662I1502J0D01*
G02X420887Y1261083I0J-1502D01*
G03X421044Y1261006I158J123D01*
G01X421360D01*
G03X421517Y1261083I-1J200D01*
G02X423887I1185J-923D01*
G03X424044Y1261006I158J123D01*
G01X424360D01*
G03X424517Y1261083I-1J200D01*
G02X426887I1185J-923D01*
G03X427044Y1261006I158J123D01*
G01X427360D01*
G03X427517Y1261083I-1J200D01*
G02X429887I1185J-923D01*
G03X430044Y1261006I158J123D01*
G01X430360D01*
G03X430517Y1261083I-1J200D01*
G02X432887I1185J-923D01*
G03X433044Y1261006I158J123D01*
G01X433360D01*
G03X433517Y1261083I-1J200D01*
G02X435887I1185J-923D01*
G03X436044Y1261006I158J123D01*
G01X436360D01*
G03X436517Y1261083I-1J200D01*
G02X438887I1185J-923D01*
G03X439044Y1261006I158J123D01*
G01X439360D01*
G03X439517Y1261083I-1J200D01*
G02X441887I1185J-923D01*
G03X442044Y1261006I158J123D01*
G01X442360D01*
G03X442517Y1261083I-1J200D01*
G02X444887I1185J-923D01*
G03X445044Y1261006I158J123D01*
G37*
G36*
G01X404059Y1274030D02*
X403262Y1274827D01*
G02X402822Y1275889I1062J1062D01*
G02X404324Y1277390I1502J-1D01*
G02X405386Y1276951I1J-1501D01*
G01X406165Y1276171D01*
G03X406307Y1276112I142J141D01*
G01X455272D01*
G02X456334Y1275673I1J-1501D01*
G01X462021Y1269986D01*
G02X462460Y1268924I-1062J-1061D01*
G01Y1208294D01*
G02X462021Y1207232I-1501J-1D01*
G01X459180Y1204392D01*
G03X459122Y1204250I142J-141D01*
G01Y1197926D01*
G03X459180Y1197784I200J-1D01*
G01X459183Y1197781D01*
G03X459325Y1197722I142J141D01*
G01X459330D01*
G03X459472Y1197781I0J200D01*
G01X460223Y1198533D01*
G02X461285Y1198972I1061J-1062D01*
G02X462786Y1197471I0J-1501D01*
G02X462347Y1196409I-1501J-1D01*
G01X461550Y1195612D01*
G03Y1195330I141J-141D01*
G01X462347Y1194533D01*
G02X462786Y1193471I-1062J-1061D01*
G02X461285Y1191970I-1501J0D01*
G02X460223Y1192409I-1J1501D01*
G01X459472Y1193161D01*
G03X459330Y1193220I-142J-141D01*
G01X457998D01*
G02X456936Y1193659I-1J1501D01*
G01X455058Y1195537D01*
G02X454618Y1196599I1062J1062D01*
G01Y1205577D01*
G02X455058Y1206639I1502J0D01*
G01X457899Y1209479D01*
G03X457958Y1209621I-141J142D01*
G01Y1267597D01*
G03X457899Y1267739I-200J0D01*
G01X454087Y1271551D01*
G03X453945Y1271610I-142J-141D01*
G01X406251D01*
G03X406109Y1271551I0J-200D01*
G01X405386Y1270827D01*
G02X404324Y1270388I-1061J1062D01*
G02X402822Y1271889I-1J1501D01*
G02X403262Y1272951I1502J0D01*
G01X404059Y1273748D01*
G03Y1274030I-141J141D01*
G37*
G36*
G01X460352Y1298097D02*
X461149Y1297300D01*
G03X461431I141J141D01*
G01X462228Y1298097D01*
G02X463290Y1298536I1061J-1062D01*
G02X464792Y1297035I1J-1501D01*
G02X464352Y1295973I-1502J0D01*
G01X463536Y1295158D01*
G03X463478Y1295016I142J-141D01*
G01Y1293930D01*
G03X463536Y1293788I200J-1D01*
G01X467908Y1289417D01*
G02X468348Y1288355I-1062J-1062D01*
G01Y1209394D01*
G03X468406Y1209252I200J-1D01*
G01X471712Y1205947D01*
G02X472152Y1204885I-1062J-1062D01*
G01Y1196299D01*
G02X471712Y1195237I-1502J0D01*
G01X470134Y1193659D01*
G02X469072Y1193220I-1061J1062D01*
G01X467740D01*
G03X467598Y1193161I0J-200D01*
G01X466847Y1192409D01*
G02X465785Y1191970I-1061J1062D01*
G02X464284Y1193471I0J1501D01*
G02X464723Y1194533I1501J1D01*
G01X465520Y1195330D01*
G03Y1195612I-141J141D01*
G01X464723Y1196409D01*
G02X464284Y1197471I1062J1061D01*
G02X465785Y1198972I1501J0D01*
G02X466847Y1198533I1J-1501D01*
G01X467298Y1198081D01*
G03X467440Y1198022I142J141D01*
G01X467448D01*
G03X467648Y1198222I0J200D01*
G01Y1203558D01*
G03X467590Y1203700I-200J1D01*
G01X464284Y1207005D01*
G02X463844Y1208067I1062J1062D01*
G01Y1287028D01*
G03X463786Y1287170I-200J1D01*
G01X459414Y1291541D01*
G02X458974Y1292603I1062J1062D01*
G01Y1295144D01*
G03X458916Y1295286I-200J1D01*
G01X458228Y1295973D01*
G02X457788Y1297035I1062J1062D01*
G02X459290Y1298536I1502J-1D01*
G02X460352Y1298097I1J-1501D01*
G37*
G36*
G01X400181Y958354D02*
X400149Y958326D01*
G02X399173Y957966I-976J1143D01*
G02Y960970I0J1502D01*
G02X400404Y960328I0J-1501D01*
G01X400429Y960293D01*
X400501Y960249D01*
X400879Y960201D01*
X400960Y960225D01*
X400992Y960253D01*
G02X401968Y960613I976J-1143D01*
G02X403251Y959892I0J-1502D01*
G01X403278Y959848D01*
X403366Y959797D01*
X403808Y959789D01*
X403898Y959836D01*
X403926Y959879D01*
G02X405179Y960553I1253J-828D01*
G02X406681Y959051I0J-1502D01*
G02X406110Y957872I-1503J0D01*
G01X406076Y957845D01*
X406037Y957773D01*
X406009Y957393D01*
X406036Y957316D01*
X406066Y957284D01*
G02X406473Y956256I-1095J-1028D01*
G02X404971Y954754I-1502J0D01*
G02X403851Y955255I0J1502D01*
G01X403825Y955284D01*
X403757Y955318D01*
X403404Y955346D01*
X403331Y955324D01*
X403301Y955299D01*
G02X402354Y954963I-947J1167D01*
G02X400852Y956465I0J1502D01*
G02X401145Y957356I1501J0D01*
G01X401168Y957388D01*
X401187Y957463D01*
X401135Y957821D01*
X401095Y957888D01*
X401063Y957912D01*
G02X400737Y958251I906J1198D01*
G01X400712Y958286D01*
X400640Y958330D01*
X400262Y958378D01*
X400181Y958354D01*
G37*
G36*
G01X459007Y1017640D02*
X458970Y1017669D01*
G02X458383Y1018860I915J1191D01*
G02X461387I1502J0D01*
G02X461380Y1018720I-1502J5D01*
G01X461376Y1018672D01*
X461411Y1018584D01*
X461725Y1018306D01*
X461817Y1018282D01*
X461864Y1018292D01*
G02X462185Y1018327I322J-1467D01*
G02Y1015323I0J-1502D01*
G02X461710Y1015400I0J1502D01*
G01X461675Y1015412D01*
X461602Y1015409D01*
X461289Y1015274D01*
X461237Y1015223D01*
X461221Y1015190D01*
G02X459860Y1014323I-1361J635D01*
G02X458358Y1015825I0J1502D01*
G02X458964Y1017031I1503J0D01*
G01X459003Y1017059D01*
X459045Y1017142D01*
X459048Y1017556D01*
X459007Y1017640D01*
G37*
G36*
G01X431105Y1020336D02*
X431399D01*
G03X431546Y1020401I-1J200D01*
G02X432652Y1020886I1105J-1017D01*
G02X434154Y1019384I0J-1502D01*
G02X433475Y1018128I-1501J0D01*
G01X433433Y1018100D01*
X433385Y1018010D01*
X433388Y1017572D01*
X433438Y1017483D01*
X433481Y1017455D01*
G02X434180Y1016186I-802J-1269D01*
G02X432678Y1014684I-1502J0D01*
G02X431572Y1015169I-1J1502D01*
G03X431425Y1015234I-148J-135D01*
G01X431131D01*
G03X430984Y1015169I1J-200D01*
G02X429878Y1014684I-1105J1017D01*
G02X428772Y1015169I-1J1502D01*
G03X428625Y1015234I-148J-135D01*
G01X428331D01*
G03X428184Y1015169I1J-200D01*
G02X427078Y1014684I-1105J1017D01*
G02X425576Y1016186I0J1502D01*
G02X426255Y1017442I1501J0D01*
G01X426297Y1017470D01*
X426345Y1017560D01*
X426342Y1017998D01*
X426292Y1018087D01*
X426249Y1018115D01*
G02X425550Y1019384I802J1269D01*
G02X427052Y1020886I1502J0D01*
G02X428158Y1020401I1J-1502D01*
G03X428305Y1020336I148J135D01*
G01X428599D01*
G03X428746Y1020401I-1J200D01*
G02X429852Y1020886I1105J-1017D01*
G02X430958Y1020401I1J-1502D01*
G03X431105Y1020336I148J135D01*
G37*
G36*
G01X438176Y1035611D02*
G02X439521Y1036168I1345J-1345D01*
G01X443091D01*
G02Y1032364I0J-1902D01*
G01X440391D01*
G03X440250Y1032306I0J-200D01*
G01X439681Y1031737D01*
G03X439622Y1031596I141J-142D01*
G01Y1019235D01*
G03X439681Y1019094I200J1D01*
G01X440250Y1018525D01*
G03X440391Y1018466I142J141D01*
G01X441915D01*
G03X442087Y1018564I0J200D01*
G01X442290Y1018904D01*
X442293Y1019009D01*
X442268Y1019056D01*
G02X442089Y1019766I1323J711D01*
G02X445093I1502J0D01*
G02X443766Y1018274I-1502J0D01*
G03X443650Y1017932I23J-199D01*
G02X443673Y1017910I-1303J-1385D01*
G01X454615Y1006968D01*
G02X455172Y1005623I-1345J-1345D01*
G01Y1003763D01*
G02X453270Y1001862I-1902J1D01*
G02X451494Y1003082I-1J1902D01*
G01X451481Y1003118D01*
X451431Y1003173D01*
X451120Y1003327D01*
X451046Y1003334D01*
X451010Y1003323D01*
G02X450591Y1003264I-417J1443D01*
G02X449089Y1004766I0J1502D01*
G02X449646Y1005933I1501J0D01*
G01X449679Y1005960D01*
X449717Y1006035D01*
X449735Y1006375D01*
G03X449677Y1006527I-200J11D01*
G01X441599Y1014605D01*
G03X441458Y1014664I-142J-141D01*
G01X439521D01*
G02X438176Y1015220I-1J1902D01*
G01X436376Y1017020D01*
G02X435820Y1018365I1346J1344D01*
G01Y1032466D01*
G02X436376Y1033811I1902J1D01*
G01X438176Y1035611D01*
G37*
G36*
G01X473357Y1091860D02*
X473323Y1091888D01*
G02X472775Y1093048I954J1160D01*
G02X475779I1502J0D01*
G02X475287Y1091936I-1503J0D01*
G01X475254Y1091906D01*
X475220Y1091828D01*
X475230Y1091436D01*
X475268Y1091359D01*
X475302Y1091331D01*
G02X475689Y1090848I-954J-1161D01*
G01X475713Y1090800D01*
X475800Y1090742D01*
X476249Y1090711D01*
X476343Y1090756D01*
X476374Y1090800D01*
G02X477607Y1091444I1233J-858D01*
G02X479109Y1089942I0J-1502D01*
G02X478655Y1088866I-1502J0D01*
G01X478616Y1088828D01*
X478587Y1088721D01*
X478713Y1088277D01*
X478793Y1088201D01*
X478846Y1088189D01*
G02X480019Y1086724I-328J-1465D01*
G02X479649Y1085737I-1501J0D01*
G01X479625Y1085709D01*
X479600Y1085642D01*
Y1085306D01*
X479625Y1085239D01*
X479649Y1085211D01*
G02Y1083237I-1131J-987D01*
G01X479625Y1083209D01*
X479600Y1083142D01*
Y1082806D01*
X479625Y1082739D01*
X479649Y1082711D01*
G02X480019Y1081724I-1131J-987D01*
G02X478517Y1080222I-1502J0D01*
G02X477530Y1080592I0J1501D01*
G01X477502Y1080616D01*
X477435Y1080641D01*
X477099D01*
X477032Y1080616D01*
X477004Y1080592D01*
G02X476017Y1080222I-987J1131D01*
G02X474515Y1081724I0J1502D01*
G02X474885Y1082711I1501J0D01*
G01X474909Y1082739D01*
X474934Y1082806D01*
Y1083142D01*
X474909Y1083209D01*
X474885Y1083237D01*
G02Y1085211I1131J987D01*
G01X474909Y1085239D01*
X474934Y1085306D01*
Y1085642D01*
X474909Y1085709D01*
X474885Y1085737D01*
G02X474515Y1086724I1131J987D01*
G02X476017Y1088226I1502J0D01*
G02X477004Y1087856I0J-1501D01*
G01X477032Y1087832D01*
X477099Y1087807D01*
X477435D01*
X477502Y1087832D01*
X477530Y1087856D01*
G02X477846Y1088068I988J-1131D01*
G03X477739Y1088446I-90J179D01*
G02X477607Y1088440I-134J1496D01*
G02X476266Y1089265I0J1502D01*
G01X476242Y1089313D01*
X476155Y1089371D01*
X475706Y1089402D01*
X475612Y1089357D01*
X475581Y1089313D01*
G02X474348Y1088669I-1233J858D01*
G02X472846Y1090171I0J1502D01*
G02X473338Y1091283I1503J0D01*
G01X473371Y1091313D01*
X473405Y1091391D01*
X473395Y1091783D01*
X473357Y1091860D01*
G37*
G36*
G01X434758Y1093314D02*
X434767Y1093363D01*
G02X436244Y1094590I1477J-275D01*
G02X437746Y1093088I0J-1502D01*
G02X437261Y1091982I-1502J-1D01*
G03X437196Y1091835I135J-148D01*
G01Y1091541D01*
G03X437261Y1091394I200J1D01*
G02X437746Y1090288I-1017J-1105D01*
G02X436244Y1088786I-1502J0D01*
G02X435405Y1089042I0J1503D01*
G01X435366Y1089069D01*
X435273Y1089081D01*
X434883Y1088949D01*
X434817Y1088883D01*
X434802Y1088838D01*
G02X434510Y1088329I-1424J478D01*
G01X434486Y1088301D01*
X434461Y1088234D01*
Y1087898D01*
X434486Y1087831D01*
X434510Y1087803D01*
G02Y1085829I-1131J-987D01*
G01X434486Y1085801D01*
X434461Y1085734D01*
Y1085398D01*
X434486Y1085331D01*
X434510Y1085303D01*
G02Y1083329I-1131J-987D01*
G01X434486Y1083301D01*
X434461Y1083234D01*
Y1082898D01*
X434486Y1082831D01*
X434510Y1082803D01*
G02X434880Y1081816I-1131J-987D01*
G02X433378Y1080314I-1502J0D01*
G02X432391Y1080684I0J1501D01*
G01X432363Y1080708D01*
X432296Y1080733D01*
X431960D01*
X431893Y1080708D01*
X431865Y1080684D01*
G02X430878Y1080314I-987J1131D01*
G02X429376Y1081816I0J1502D01*
G02X429746Y1082803I1501J0D01*
G01X429770Y1082831D01*
X429795Y1082898D01*
Y1083234D01*
X429770Y1083301D01*
X429746Y1083329D01*
G02Y1085303I1131J987D01*
G01X429770Y1085331D01*
X429795Y1085398D01*
Y1085734D01*
X429770Y1085801D01*
X429746Y1085829D01*
G02X429376Y1086816I1131J987D01*
G02X430878Y1088318I1502J0D01*
G02X431926Y1087892I0J-1502D01*
G03X432065Y1087835I140J143D01*
G01X432191D01*
G03X432330Y1087892I-1J200D01*
G02X432359Y1087919I1038J-1086D01*
G01Y1088129D01*
G03X432302Y1088268I-200J-1D01*
G02X431876Y1089316I1076J1048D01*
G02X432246Y1090303I1501J0D01*
G01X432270Y1090331D01*
X432295Y1090398D01*
Y1090734D01*
X432270Y1090801D01*
X432246Y1090829D01*
G02X431876Y1091816I1131J987D01*
G02X433378Y1093318I1502J0D01*
G02X434165Y1093096I1J-1502D01*
G01X434208Y1093069D01*
X434305Y1093063D01*
X434698Y1093237D01*
X434758Y1093314D01*
G37*
G36*
G01X407924Y1092771D02*
G02X407345Y1093956I923J1185D01*
G02X410349I1502J0D01*
G02X409770Y1092771I-1502J0D01*
G03X409693Y1092614I123J-158D01*
G01Y1092298D01*
G03X409770Y1092141I200J1D01*
G02X410349Y1090956I-923J-1185D01*
G02X409689Y1089712I-1502J0D01*
G01X409646Y1089683D01*
X409599Y1089589D01*
X409622Y1089142D01*
X409678Y1089054D01*
X409725Y1089029D01*
G02X410051Y1088792I-712J-1322D01*
G01X410086Y1088759D01*
X410175Y1088732D01*
X410585Y1088800D01*
X410660Y1088855D01*
X410682Y1088897D01*
G02X411225Y1089482I1333J-692D01*
G01X411265Y1089507D01*
X411314Y1089587D01*
X411353Y1089999D01*
X411319Y1090086D01*
X411284Y1090118D01*
G02X410795Y1091227I1013J1109D01*
G02X413799I1502J0D01*
G02X413087Y1089950I-1501J0D01*
G01X413047Y1089925D01*
X412998Y1089845D01*
X412959Y1089433D01*
X412993Y1089346D01*
X413028Y1089314D01*
G02X413200Y1089128I-1013J-1109D01*
G03X413357Y1089051I158J123D01*
G01X413673D01*
G03X413830Y1089128I-1J200D01*
G02X415015Y1089707I1185J-923D01*
G02X416517Y1088205I0J-1502D01*
G02X415938Y1087020I-1502J0D01*
G03X415861Y1086863I123J-158D01*
G01Y1086547D01*
G03X415938Y1086390I200J1D01*
G02X416517Y1085205I-923J-1185D01*
G02X416061Y1084127I-1502J0D01*
G01X416032Y1084099D01*
X416001Y1084026D01*
X415997Y1083661D01*
X416027Y1083587D01*
X416056Y1083559D01*
G02X416491Y1082501I-1067J-1057D01*
G02X414989Y1080999I-1502J0D01*
G02X413804Y1081578I0J1502D01*
G03X413647Y1081655I-158J-123D01*
G01X413331D01*
G03X413174Y1081578I1J-200D01*
G02X410804I-1185J923D01*
G03X410647Y1081655I-158J-123D01*
G01X410331D01*
G03X410174Y1081578I1J-200D01*
G02X408989Y1080999I-1185J923D01*
G02X407487Y1082501I0J1502D01*
G02X407943Y1083579I1502J0D01*
G01X407972Y1083607D01*
X408003Y1083680D01*
X408007Y1084045D01*
X407977Y1084119D01*
X407948Y1084147D01*
G02X407513Y1085205I1067J1057D01*
G02X407883Y1086192I1501J0D01*
G01X407907Y1086220D01*
X407932Y1086287D01*
Y1086623D01*
X407907Y1086690D01*
X407883Y1086718D01*
G02X407513Y1087705I1131J987D01*
G02X408173Y1088949I1502J0D01*
G01X408216Y1088978D01*
X408263Y1089072D01*
X408240Y1089519D01*
X408184Y1089607D01*
X408137Y1089632D01*
G02X407345Y1090956I711J1324D01*
G02X407924Y1092141I1502J0D01*
G03X408001Y1092298I-123J158D01*
G01Y1092614D01*
G03X407924Y1092771I-200J-1D01*
G37*
G36*
G01X423604Y1106328D02*
X423588Y1106372D01*
G02X423493Y1106897I1407J526D01*
G02X426497I1502J0D01*
G02X425095Y1105398I-1502J0D01*
G01X425048Y1105395D01*
X424967Y1105347D01*
X424741Y1104998D01*
X424731Y1104904D01*
X424747Y1104860D01*
G02X424842Y1104335I-1407J-526D01*
G02X424785Y1103925I-1503J0D01*
G01X424772Y1103881D01*
X424788Y1103792D01*
X425022Y1103463D01*
X425101Y1103419D01*
X425147Y1103416D01*
G02X426562Y1101917I-86J-1499D01*
G02X423558I-1502J0D01*
G02X423615Y1102327I1503J0D01*
G01X423628Y1102371D01*
X423612Y1102460D01*
X423378Y1102789D01*
X423299Y1102833D01*
X423253Y1102836D01*
G02X421899Y1103910I86J1499D01*
G01X421887Y1103952D01*
X421832Y1104016D01*
X421485Y1104181D01*
X421401Y1104183D01*
X421361Y1104166D01*
G02X420782Y1104050I-579J1387D01*
G02X419340Y1105133I0J1502D01*
G01X419329Y1105171D01*
X419282Y1105231D01*
X418972Y1105409D01*
X418897Y1105419D01*
X418859Y1105410D01*
G02X418798Y1105396I-366J1457D01*
G01X418761Y1105388D01*
X418698Y1105348D01*
X418495Y1105069D01*
X418476Y1104997D01*
X418481Y1104959D01*
G02X418490Y1104792I-1493J-164D01*
G02X417628Y1103433I-1502J0D01*
G01X417596Y1103418D01*
X416260Y1102082D01*
G03X416202Y1101941I142J-141D01*
G01Y1098819D01*
G03X416260Y1098678I200J0D01*
G01X422298Y1092640D01*
G02X422708Y1091649I-991J-990D01*
G01Y1058888D01*
G03X422767Y1058747I200J1D01*
G01X429811Y1051703D01*
G03X429952Y1051644I142J141D01*
G01X435173D01*
G02X436164Y1051234I1J-1401D01*
G01X466745Y1020653D01*
G02X467156Y1019662I-991J-992D01*
G01Y1011362D01*
G03X467214Y1011221I200J0D01*
G01X477034Y1001401D01*
G03X477175Y1001342I142J141D01*
G01X480170D01*
X480203Y1001354D01*
G02X480711Y1001443I509J-1413D01*
G02Y998439I0J-1502D01*
G02X480203Y998528I1J1502D01*
G01X480170Y998540D01*
X476512D01*
G02X475521Y998950I-1J1401D01*
G01X464763Y1009708D01*
G02X464352Y1010699I991J992D01*
G01Y1018999D01*
G03X464294Y1019140I-200J0D01*
G01X434651Y1048783D01*
G03X434510Y1048842I-142J-141D01*
G01X429289D01*
G02X428298Y1049252I-1J1401D01*
G01X420316Y1057234D01*
G02X419906Y1058225I991J990D01*
G01Y1090986D01*
G03X419847Y1091127I-200J-1D01*
G01X413809Y1097165D01*
G02X413398Y1098156I991J992D01*
G01Y1102604D01*
G02X413809Y1103595I1402J-1D01*
G01X415614Y1105400D01*
X415629Y1105432D01*
G02X416685Y1106263I1359J-640D01*
G01X416722Y1106271D01*
X416785Y1106311D01*
X416988Y1106590D01*
X417007Y1106662D01*
X417002Y1106700D01*
G02X416993Y1106867I1493J164D01*
G02X418495Y1108369I1502J0D01*
G02X419937Y1107286I0J-1502D01*
G01X419948Y1107248D01*
X419995Y1107188D01*
X420305Y1107010D01*
X420380Y1107000D01*
X420418Y1107009D01*
G02X420782Y1107054I365J-1457D01*
G02X422223Y1105977I0J-1503D01*
G01X422235Y1105935D01*
X422290Y1105871D01*
X422637Y1105706D01*
X422721Y1105704D01*
X422761Y1105721D01*
G02X423240Y1105834I580J-1386D01*
G01X423287Y1105837D01*
X423368Y1105885D01*
X423594Y1106234D01*
X423604Y1106328D01*
G37*
G36*
G01X455732D02*
X455716Y1106372D01*
G02X455621Y1106897I1407J526D01*
G02X458625I1502J0D01*
G02X457223Y1105398I-1502J0D01*
G01X457176Y1105395D01*
X457095Y1105347D01*
X456869Y1104998D01*
X456859Y1104904D01*
X456875Y1104860D01*
G02X456970Y1104335I-1407J-526D01*
G02X456913Y1103925I-1503J0D01*
G01X456900Y1103881D01*
X456916Y1103792D01*
X457150Y1103463D01*
X457229Y1103419D01*
X457275Y1103416D01*
G02X458690Y1101917I-86J-1499D01*
G02X455686I-1502J0D01*
G02X455743Y1102327I1503J0D01*
G01X455756Y1102371D01*
X455740Y1102460D01*
X455506Y1102789D01*
X455427Y1102833D01*
X455381Y1102836D01*
G02X454027Y1103910I86J1499D01*
G01X454015Y1103952D01*
X453960Y1104016D01*
X453613Y1104181D01*
X453529Y1104183D01*
X453489Y1104166D01*
G02X452910Y1104050I-579J1387D01*
G02X451468Y1105133I0J1502D01*
G01X451457Y1105171D01*
X451410Y1105231D01*
X451100Y1105409D01*
X451025Y1105419D01*
X450987Y1105410D01*
G02X450926Y1105396I-366J1457D01*
G01X450889Y1105388D01*
X450826Y1105348D01*
X450623Y1105069D01*
X450604Y1104997D01*
X450609Y1104959D01*
G02X450618Y1104792I-1493J-164D01*
G02X450529Y1104284I-1502J1D01*
G01X450518Y1104251D01*
Y1096829D01*
G02X450107Y1095838I-1402J1D01*
G01X446306Y1092037D01*
G03X446248Y1091896I142J-141D01*
G01Y1065448D01*
G03X446306Y1065307I200J0D01*
G01X468801Y1042812D01*
G02X469212Y1041821I-991J-992D01*
G01Y1036605D01*
G02X468801Y1035614I-1402J1D01*
G01X467460Y1034273D01*
G03X467402Y1034132I142J-141D01*
G01Y1030518D01*
G03X467460Y1030377I200J0D01*
G01X473244Y1024593D01*
G02X473654Y1023602I-991J-990D01*
G01Y1010642D01*
G03X473713Y1010501I200J1D01*
G01X478465Y1005749D01*
X478497Y1005734D01*
G02X479359Y1004375I-640J-1359D01*
G02X477857Y1002873I-1502J0D01*
G02X476498Y1003735I0J1502D01*
G01X476483Y1003767D01*
X471262Y1008988D01*
G02X470852Y1009979I991J990D01*
G01Y1022939D01*
G03X470793Y1023080I-200J-1D01*
G01X465009Y1028864D01*
G02X464598Y1029855I991J992D01*
G01Y1034795D01*
G02X465009Y1035786I1402J-1D01*
G01X466350Y1037127D01*
G03X466408Y1037268I-142J141D01*
G01Y1041158D01*
G03X466350Y1041299I-200J0D01*
G01X443855Y1063794D01*
G02X443444Y1064785I991J992D01*
G01Y1092559D01*
G02X443855Y1093550I1402J-1D01*
G01X447656Y1097351D01*
G03X447714Y1097492I-142J141D01*
G01Y1104251D01*
X447703Y1104284D01*
G02X447614Y1104792I1413J509D01*
G02X448813Y1106263I1502J0D01*
G01X448850Y1106271D01*
X448913Y1106311D01*
X449116Y1106590D01*
X449135Y1106662D01*
X449130Y1106700D01*
G02X449121Y1106867I1493J164D01*
G02X450623Y1108369I1502J0D01*
G02X452065Y1107286I0J-1502D01*
G01X452076Y1107248D01*
X452123Y1107188D01*
X452433Y1107010D01*
X452508Y1107000D01*
X452546Y1107009D01*
G02X452910Y1107054I365J-1457D01*
G02X454351Y1105977I0J-1503D01*
G01X454363Y1105935D01*
X454418Y1105871D01*
X454765Y1105706D01*
X454849Y1105704D01*
X454889Y1105721D01*
G02X455368Y1105834I580J-1386D01*
G01X455415Y1105837D01*
X455496Y1105885D01*
X455722Y1106234D01*
X455732Y1106328D01*
G37*
G36*
G01X489191D02*
X489175Y1106372D01*
G02X489080Y1106897I1407J526D01*
G02X492084I1502J0D01*
G02X490682Y1105398I-1502J0D01*
G01X490635Y1105395D01*
X490554Y1105347D01*
X490328Y1104998D01*
X490318Y1104904D01*
X490334Y1104860D01*
G02X490429Y1104335I-1407J-526D01*
G02X490372Y1103925I-1503J0D01*
G01X490359Y1103881D01*
X490375Y1103792D01*
X490609Y1103463D01*
X490688Y1103419D01*
X490734Y1103416D01*
G02X492149Y1101917I-86J-1499D01*
G02X489145I-1502J0D01*
G02X489202Y1102327I1503J0D01*
G01X489215Y1102371D01*
X489199Y1102460D01*
X488965Y1102789D01*
X488886Y1102833D01*
X488840Y1102836D01*
G02X487486Y1103910I86J1499D01*
G01X487474Y1103952D01*
X487419Y1104016D01*
X487072Y1104181D01*
X486988Y1104183D01*
X486948Y1104166D01*
G02X486369Y1104050I-579J1387D01*
G02X484927Y1105133I0J1502D01*
G01X484916Y1105171D01*
X484869Y1105231D01*
X484559Y1105409D01*
X484484Y1105419D01*
X484446Y1105410D01*
G02X484385Y1105396I-366J1457D01*
G01X484348Y1105388D01*
X484285Y1105348D01*
X484082Y1105069D01*
X484063Y1104997D01*
X484068Y1104959D01*
G02X484077Y1104792I-1493J-164D01*
G02X483215Y1103433I-1502J0D01*
G01X483183Y1103418D01*
X480588Y1100823D01*
G02X479597Y1100412I-992J991D01*
G01X471985D01*
G03X471844Y1100354I0J-200D01*
G01X466980Y1095490D01*
G03X466922Y1095349I142J-141D01*
G01Y1061904D01*
G03X466980Y1061763I200J0D01*
G01X475514Y1053229D01*
G03X475655Y1053170I142J141D01*
G01X478628D01*
G02X479619Y1052760I1J-1401D01*
G01X491016Y1041363D01*
G02X491426Y1040372I-991J-990D01*
G01Y1031221D01*
G02X491016Y1030230I-1401J-1D01*
G01X487299Y1026513D01*
G03X487240Y1026372I141J-142D01*
G01Y1022299D01*
G03X487315Y1022144I200J1D01*
G01X487592Y1021920D01*
X487680Y1021899D01*
X487725Y1021908D01*
G02X488041Y1021942I318J-1468D01*
G02Y1018938I0J-1502D01*
G02X487725Y1018972I2J1502D01*
G01X487680Y1018981D01*
X487592Y1018960D01*
X487315Y1018736D01*
G03X487240Y1018581I125J-156D01*
G01Y999330D01*
G02X486830Y998339I-1401J-1D01*
G01X483780Y995289D01*
G02X482789Y994878I-992J991D01*
G01X467545D01*
G02X466869Y995052I0J1402D01*
G03X466840Y995066I-101J-173D01*
G02X465843Y996480I504J1414D01*
G02X467345Y997982I1502J0D01*
G02X468197Y997717I0J-1502D01*
G03X468311Y997682I113J165D01*
G01X482126D01*
G03X482267Y997740I0J200D01*
G01X484379Y999852D01*
G03X484438Y999993I-141J142D01*
G01Y1027035D01*
G02X484848Y1028026I1401J1D01*
G01X488565Y1031743D01*
G03X488624Y1031884I-141J142D01*
G01Y1039709D01*
G03X488565Y1039850I-200J-1D01*
G01X478106Y1050309D01*
G03X477965Y1050368I-142J-141D01*
G01X474992D01*
G02X474001Y1050778I-1J1401D01*
G01X464529Y1060250D01*
G02X464118Y1061241I991J992D01*
G01Y1096012D01*
G02X464529Y1097003I1402J-1D01*
G01X470331Y1102805D01*
G02X471322Y1103216I992J-991D01*
G01X478934D01*
G03X479075Y1103274I0J200D01*
G01X481201Y1105400D01*
X481216Y1105432D01*
G02X482272Y1106263I1359J-640D01*
G01X482309Y1106271D01*
X482372Y1106311D01*
X482575Y1106590D01*
X482594Y1106662D01*
X482589Y1106700D01*
G02X482580Y1106867I1493J164D01*
G02X484082Y1108369I1502J0D01*
G02X485524Y1107286I0J-1502D01*
G01X485535Y1107248D01*
X485582Y1107188D01*
X485892Y1107010D01*
X485967Y1107000D01*
X486005Y1107009D01*
G02X486369Y1107054I365J-1457D01*
G02X487810Y1105977I0J-1503D01*
G01X487822Y1105935D01*
X487877Y1105871D01*
X488224Y1105706D01*
X488308Y1105704D01*
X488348Y1105721D01*
G02X488827Y1105834I580J-1386D01*
G01X488874Y1105837D01*
X488955Y1105885D01*
X489181Y1106234D01*
X489191Y1106328D01*
G37*
G36*
G01X521319D02*
X521303Y1106372D01*
G02X521208Y1106897I1407J526D01*
G02X524212I1502J0D01*
G02X522810Y1105398I-1502J0D01*
G01X522763Y1105395D01*
X522682Y1105347D01*
X522456Y1104998D01*
X522446Y1104904D01*
X522462Y1104860D01*
G02X522557Y1104335I-1407J-526D01*
G02X522500Y1103925I-1503J0D01*
G01X522487Y1103881D01*
X522503Y1103792D01*
X522737Y1103463D01*
X522816Y1103419D01*
X522862Y1103416D01*
G02X524277Y1101917I-86J-1499D01*
G02X521273I-1502J0D01*
G02X521330Y1102327I1503J0D01*
G01X521343Y1102371D01*
X521327Y1102460D01*
X521093Y1102789D01*
X521014Y1102833D01*
X520968Y1102836D01*
G02X519614Y1103910I86J1499D01*
G01X519602Y1103952D01*
X519547Y1104016D01*
X519200Y1104181D01*
X519116Y1104183D01*
X519076Y1104166D01*
G02X518497Y1104050I-579J1387D01*
G02X517055Y1105133I0J1502D01*
G01X517044Y1105171D01*
X516997Y1105231D01*
X516687Y1105409D01*
X516612Y1105419D01*
X516574Y1105410D01*
G02X516513Y1105396I-366J1457D01*
G01X516476Y1105388D01*
X516413Y1105348D01*
X516210Y1105069D01*
X516191Y1104997D01*
X516196Y1104959D01*
G02X516205Y1104792I-1493J-164D01*
G02X516116Y1104284I-1502J1D01*
G01X516104Y1104251D01*
Y1098292D01*
G03X516163Y1098151I200J1D01*
G01X519515Y1094799D01*
G02X519926Y1093808I-991J-992D01*
G01Y1050515D01*
G02X519515Y1049524I-1402J1D01*
G01X496422Y1026431D01*
G03X496364Y1026290I142J-141D01*
G01Y1014670D01*
G02X495953Y1013679I-1402J1D01*
G01X492426Y1010152D01*
G03X492368Y1010011I142J-141D01*
G01Y998407D01*
G02X491957Y997416I-1402J1D01*
G01X486118Y991577D01*
G02X485127Y991166I-992J991D01*
G01X475559D01*
X475526Y991155D01*
G02X475018Y991066I-509J1413D01*
G02Y994070I0J1502D01*
G02X475526Y993981I-1J-1502D01*
G01X475559Y993970D01*
X484464D01*
G03X484605Y994028I0J200D01*
G01X489506Y998929D01*
G03X489564Y999070I-142J141D01*
G01Y1010674D01*
G02X489975Y1011665I1402J-1D01*
G01X493502Y1015192D01*
G03X493560Y1015333I-142J141D01*
G01Y1026953D01*
G02X493971Y1027944I1402J-1D01*
G01X517064Y1051037D01*
G03X517122Y1051178I-142J141D01*
G01Y1093145D01*
G03X517064Y1093286I-200J0D01*
G01X513712Y1096638D01*
G02X513302Y1097629I991J990D01*
G01Y1104251D01*
X513290Y1104284D01*
G02X513201Y1104792I1413J509D01*
G02X514400Y1106263I1502J0D01*
G01X514437Y1106271D01*
X514500Y1106311D01*
X514703Y1106590D01*
X514722Y1106662D01*
X514717Y1106700D01*
G02X514708Y1106867I1493J164D01*
G02X516210Y1108369I1502J0D01*
G02X517652Y1107286I0J-1502D01*
G01X517663Y1107248D01*
X517710Y1107188D01*
X518020Y1107010D01*
X518095Y1107000D01*
X518133Y1107009D01*
G02X518497Y1107054I365J-1457D01*
G02X519938Y1105977I0J-1503D01*
G01X519950Y1105935D01*
X520005Y1105871D01*
X520352Y1105706D01*
X520436Y1105704D01*
X520476Y1105721D01*
G02X520955Y1105834I580J-1386D01*
G01X521002Y1105837D01*
X521083Y1105885D01*
X521309Y1106234D01*
X521319Y1106328D01*
G37*
G36*
G01X399181Y335233D02*
X399457Y335487D01*
X399491Y335562D01*
Y335604D01*
G02X400993Y337091I1502J-15D01*
G02Y334087I0J-1502D01*
G02X400882Y334091I-1J1502D01*
G01X400841Y334094D01*
X400763Y334067D01*
X400487Y333813D01*
X400453Y333738D01*
Y333696D01*
G02X400442Y333532I-1502J18D01*
G01X400437Y333487D01*
X400465Y333403D01*
X400743Y333114D01*
X400826Y333082D01*
X400872Y333086D01*
G02X400993Y333091I122J-1497D01*
G02X399491Y331589I0J-1502D01*
G02X399502Y331768I1502J-2D01*
G01X399507Y331813D01*
X399479Y331897D01*
X399201Y332186D01*
X399118Y332218D01*
X399072Y332214D01*
G02X398951Y332209I-122J1497D01*
G02Y335213I0J1502D01*
G02X399062Y335209I1J-1502D01*
G01X399103Y335206D01*
X399181Y335233D01*
G37*
G36*
G01X410682Y330493D02*
G02X409655Y330087I-1027J1096D01*
G02Y333091I0J1502D01*
G02X411121Y331917I0J-1502D01*
G03X411785Y331713I390J87D01*
G02X412812Y332119I1027J-1096D01*
G02Y329115I0J-1502D01*
G02X411346Y330289I0J1502D01*
G03X410682Y330493I-390J-87D01*
G37*
G36*
G01X444775Y336906D02*
G02X443508Y336211I-1267J807D01*
G02Y339215I0J1502D01*
G02X444656Y338681I0J-1501D01*
G03X445299Y338724I306J258D01*
G02X446566Y339419I1267J-807D01*
G02Y336415I0J-1502D01*
G02X445418Y336949I0J1501D01*
G03X444775Y336906I-306J-258D01*
G37*
G36*
G01X598424Y1199824D02*
G02X598638Y1199805I1J-1202D01*
G01X598656Y1199802D01*
X601938D01*
X601955Y1199805D01*
G02X602165Y1199823I207J-1184D01*
G02X602375Y1199805I3J-1202D01*
G01X602392Y1199802D01*
X605678D01*
X605695Y1199805D01*
G02X605905Y1199823I207J-1184D01*
G02X606115Y1199805I3J-1202D01*
G01X606132Y1199802D01*
X609419D01*
X609436Y1199805D01*
G02X609646Y1199823I207J-1184D01*
G02X609856Y1199805I3J-1202D01*
G01X609873Y1199802D01*
X613159D01*
X613176Y1199805D01*
G02X613386Y1199823I207J-1184D01*
G02X613596Y1199805I3J-1202D01*
G01X613613Y1199802D01*
X616899D01*
X616916Y1199805D01*
G02X617126Y1199823I207J-1184D01*
G02X617336Y1199805I3J-1202D01*
G01X617353Y1199802D01*
X620639D01*
X620656Y1199805D01*
G02X620866Y1199823I207J-1184D01*
G02X621076Y1199805I3J-1202D01*
G01X621093Y1199802D01*
X624379D01*
X624396Y1199805D01*
G02X624606Y1199823I207J-1184D01*
G02X624816Y1199805I3J-1202D01*
G01X624833Y1199802D01*
X628119D01*
X628136Y1199805D01*
G02X628346Y1199823I207J-1184D01*
G02X628556Y1199805I3J-1202D01*
G01X628573Y1199802D01*
X631859D01*
X631876Y1199805D01*
G02X632086Y1199823I207J-1184D01*
G02X632296Y1199805I3J-1202D01*
G01X632313Y1199802D01*
X635600D01*
X635617Y1199805D01*
G02X635827Y1199823I207J-1184D01*
G02X636037Y1199805I3J-1202D01*
G01X636054Y1199802D01*
X639861D01*
G03X640015Y1199874I0J200D01*
G01X640241Y1200144D01*
X640263Y1200230D01*
X640255Y1200274D01*
G02X640235Y1200491I1182J218D01*
G02X642639I1202J0D01*
G02X642619Y1200274I-1202J1D01*
G01X642611Y1200230D01*
X642633Y1200144D01*
X642859Y1199874D01*
G03X643013Y1199802I154J128D01*
G01X643601D01*
G03X643755Y1199874I0J200D01*
G01X643981Y1200144D01*
X644003Y1200230D01*
X643995Y1200274D01*
G02X643975Y1200491I1182J218D01*
G02X646379I1202J0D01*
G02X646359Y1200274I-1202J1D01*
G01X646351Y1200230D01*
X646373Y1200144D01*
X646599Y1199874D01*
G03X646753Y1199802I154J128D01*
G01X647341D01*
G03X647495Y1199874I0J200D01*
G01X647721Y1200144D01*
X647743Y1200230D01*
X647735Y1200274D01*
G02X647715Y1200491I1182J218D01*
G02X650119I1202J0D01*
G02X649763Y1199637I-1202J0D01*
G01X649762Y1199636D01*
G03X649763Y1199354I142J-140D01*
G01X651043Y1198074D01*
G02X651102Y1197932I-141J-142D01*
G01Y1197860D01*
G03X651227Y1197675I200J0D01*
G01X651571Y1197536D01*
G03X651790Y1197584I74J186D01*
G02X652657Y1197953I867J-834D01*
G02Y1195549I0J-1202D01*
G02X651790Y1195918I0J1203D01*
G03X651571Y1195966I-145J-138D01*
G01X651227Y1195827D01*
G03X651102Y1195642I75J-185D01*
G01Y1194120D01*
G03X651227Y1193935I200J0D01*
G01X651571Y1193796D01*
G03X651790Y1193844I74J186D01*
G02X652657Y1194213I867J-834D01*
G02Y1191809I0J-1202D01*
G02X651790Y1192178I0J1203D01*
G03X651571Y1192226I-145J-138D01*
G01X651227Y1192087D01*
G03X651102Y1191902I75J-185D01*
G01Y1190380D01*
G03X651227Y1190195I200J0D01*
G01X651571Y1190056D01*
G03X651790Y1190104I74J186D01*
G02X652657Y1190473I867J-834D01*
G02Y1188069I0J-1202D01*
G02X651790Y1188438I0J1203D01*
G03X651571Y1188486I-145J-138D01*
G01X651227Y1188347D01*
G03X651102Y1188162I75J-185D01*
G01Y1186640D01*
G03X651227Y1186455I200J0D01*
G01X651571Y1186316D01*
G03X651790Y1186364I74J186D01*
G02X652657Y1186733I867J-834D01*
G02Y1184329I0J-1202D01*
G02X651790Y1184698I0J1203D01*
G03X651571Y1184746I-145J-138D01*
G01X651227Y1184607D01*
G03X651102Y1184422I75J-185D01*
G01Y1182900D01*
G03X651227Y1182715I200J0D01*
G01X651571Y1182576D01*
G03X651790Y1182624I74J186D01*
G02X652657Y1182993I867J-834D01*
G02Y1180589I0J-1202D01*
G02X651790Y1180958I0J1203D01*
G03X651571Y1181006I-145J-138D01*
G01X651227Y1180867D01*
G03X651102Y1180682I75J-185D01*
G01Y1179160D01*
G03X651227Y1178975I200J0D01*
G01X651571Y1178836D01*
G03X651790Y1178884I74J186D01*
G02X652657Y1179253I867J-834D01*
G02Y1176849I0J-1202D01*
G02X651790Y1177218I0J1203D01*
G03X651571Y1177266I-145J-138D01*
G01X651227Y1177127D01*
G03X651102Y1176942I75J-185D01*
G01Y1175968D01*
G02X651043Y1175826I-200J0D01*
G01X650107Y1174891D01*
G03X650058Y1174687I141J-142D01*
G02X650119Y1174310I-1141J-378D01*
G02X648917Y1173108I-1202J0D01*
G02X647718Y1174225I0J1202D01*
G01Y1174227D01*
G03X647655Y1174358I-199J-15D01*
G01X647456Y1174544D01*
G03X647319Y1174598I-137J-146D01*
G01X646775D01*
G03X646638Y1174544I0J-200D01*
G01X646439Y1174358D01*
G03X646376Y1174227I136J-146D01*
G01Y1174226D01*
G02X643978Y1174225I-1199J84D01*
G01Y1174227D01*
G03X643915Y1174358I-199J-15D01*
G01X643716Y1174544D01*
G03X643579Y1174598I-137J-146D01*
G01X643068D01*
G02X642926Y1174657I0J200D01*
G01X642825Y1174758D01*
G03X642542I-141J-141D01*
G01X642501Y1174717D01*
G02X642411Y1174665I-142J141D01*
G01X642216Y1174613D01*
G03X642069Y1174393I51J-194D01*
G01X642080Y1174317D01*
X642193Y1174219D01*
X642461Y1174221D01*
G02X642562Y1174195I2J-200D01*
G01X643099Y1173889D01*
G02X643706Y1172846I-595J-1044D01*
G01Y1171761D01*
G03X643825Y1171578I200J0D01*
G01X644158Y1171430D01*
G03X644373Y1171464I81J183D01*
G02X645177Y1171772I804J-895D01*
G02Y1169368I0J-1202D01*
G02X644373Y1169676I0J1203D01*
G03X644158Y1169710I-134J-149D01*
G01X643825Y1169562D01*
G03X643706Y1169379I81J-183D01*
G01Y1168294D01*
G02X643099Y1167251I-1202J1D01*
G01X642562Y1166945D01*
G02X642461Y1166919I-99J174D01*
G01X641923Y1166924D01*
G02X641824Y1166951I1J200D01*
G01X641591Y1167087D01*
X641589Y1167089D01*
G03X641438Y1167130I-151J-259D01*
G01X641437D01*
G03X641137Y1166831I0J-300D01*
G03X641149Y1166746I300J-1D01*
G03X641151Y1166739I193J51D01*
G01X641224Y1166516D01*
G02X641231Y1166422I-190J-61D01*
G01X641187Y1166143D01*
G03X641232Y1165983I198J-31D01*
G03X641385Y1165912I153J129D01*
G01X641711D01*
G02X642560Y1165560I-1J-1201D01*
G01X643498Y1164622D01*
G02X643850Y1163773I-849J-850D01*
G01Y1160657D01*
G03X643958Y1160479I200J0D01*
G01X644274Y1160316D01*
G03X644481Y1160331I91J178D01*
G01X644482D01*
G02X645177Y1160552I695J-982D01*
G02Y1158148I0J-1202D01*
G02X644482Y1158369I0J1203D01*
G01X644481D01*
G03X644274Y1158384I-116J-163D01*
G01X643958Y1158221D01*
G03X643850Y1158043I92J-178D01*
G01Y1157459D01*
G02X643498Y1156610I-1201J1D01*
G01X643285Y1156397D01*
G03X643230Y1156222I142J-141D01*
G01X643295Y1155851D01*
X643354Y1155774D01*
X643398Y1155753D01*
G02X643456Y1155724I-508J-1089D01*
G01X643495Y1155703D01*
X643585Y1155698D01*
X643955Y1155851D01*
X644014Y1155917D01*
X644027Y1155960D01*
G02X645177Y1156812I1150J-350D01*
G02Y1154408I0J-1202D01*
G02X644684Y1154514I1J1202D01*
G01X644637Y1154535D01*
X644537Y1154527D01*
X644212Y1154317D01*
G03X644120Y1154149I108J-168D01*
G01Y1153331D01*
G03X644212Y1153163I200J0D01*
G01X644494Y1152981D01*
G03X644684Y1152966I109J168D01*
G02X645177Y1153072I494J-1096D01*
G02X646379Y1151870I0J-1202D01*
G02X645851Y1150875I-1202J0D01*
G01X645810Y1150847D01*
X645764Y1150760D01*
Y1150710D01*
G03X645964Y1150510I200J0D01*
G01X646374D01*
G02X647224Y1150157I-1J-1202D01*
G01X647574Y1149807D01*
G02X647765Y1149558I-850J-850D01*
G02X647847Y1149388I-1038J-606D01*
G01Y1149386D01*
X647852Y1149375D01*
X647912Y1149316D01*
X648225Y1149198D01*
G03X648383Y1149206I70J187D01*
G01X648384D01*
G02X648917Y1149331I534J-1077D01*
G02Y1146927I0J-1202D01*
G02X648474Y1147012I1J1202D01*
G01X648473D01*
G03X648288Y1146992I-73J-186D01*
G01X648014Y1146806D01*
G03X647926Y1146640I112J-166D01*
G01Y1145878D01*
G03X648014Y1145712I200J0D01*
G01X648288Y1145526D01*
G03X648473Y1145506I112J166D01*
G01X648474D01*
G02X648917Y1145591I444J-1117D01*
G02Y1143187I0J-1202D01*
G02X648474Y1143272I1J1202D01*
G01X648473D01*
G03X648288Y1143252I-73J-186D01*
G01X648014Y1143066D01*
G03X647926Y1142900I112J-166D01*
G01Y1142138D01*
G03X648014Y1141972I200J0D01*
G01X648288Y1141786D01*
G03X648473Y1141766I112J166D01*
G01X648474D01*
G02X648917Y1141851I444J-1117D01*
G02Y1139447I0J-1202D01*
G02X647801Y1140202I0J1202D01*
G01X647786Y1140241D01*
X647615Y1140411D01*
X647591Y1140387D01*
G02X647574Y1140369I-882J816D01*
G01X647458Y1140254D01*
G02X646250Y1139957I-849J850D01*
G02X646177Y1139982I353J1148D01*
G02X645769Y1139603I-1000J667D01*
G03X645670Y1139400I99J-174D01*
G01X645702Y1139183D01*
G02X645711Y1138912I-1189J-175D01*
G02X645587Y1138471I-1197J99D01*
G03X645585Y1138465I187J-66D01*
G01X645577Y1138448D01*
X645572Y1138374D01*
X645667Y1138074D01*
G03X645759Y1137960I191J60D01*
G01X645760D01*
G02X646379Y1136909I-583J-1051D01*
G02X643975I-1202J0D01*
G01Y1136922D01*
G03X643917Y1137064I-200J1D01*
G01X643718Y1137267D01*
G03X643575Y1137326I-142J-141D01*
G01X643039D01*
G03X642896Y1137267I-1J-200D01*
G01X642697Y1137064D01*
G03X642639Y1136922I142J-141D01*
G01Y1136909D01*
G02X640235I-1202J0D01*
G01Y1136922D01*
G03X640177Y1137064I-200J1D01*
G01X639978Y1137267D01*
G03X639835Y1137326I-142J-141D01*
G01X639299D01*
G03X639156Y1137267I-1J-200D01*
G01X638957Y1137064D01*
G03X638899Y1136922I142J-141D01*
G01Y1136909D01*
G02X636495I-1202J0D01*
G01Y1136922D01*
G03X636437Y1137064I-200J1D01*
G01X636238Y1137267D01*
G03X636095Y1137326I-142J-141D01*
G01X635559D01*
G03X635416Y1137267I-1J-200D01*
G01X635217Y1137064D01*
G03X635159Y1136922I142J-141D01*
G01Y1136909D01*
G02X632755I-1202J0D01*
G01Y1136922D01*
G03X632697Y1137064I-200J1D01*
G01X632498Y1137267D01*
G03X632355Y1137326I-142J-141D01*
G01X631818D01*
G03X631675Y1137267I-1J-200D01*
G01X631476Y1137064D01*
G03X631418Y1136922I142J-141D01*
G01Y1136909D01*
G02X629014I-1202J0D01*
G02X629028Y1137095I1202J3D01*
G01X629031Y1137110D01*
Y1137126D01*
G03X628831Y1137326I-200J0D01*
G01X628807D01*
G03X628665Y1137267I0J-200D01*
G01X628594Y1137196D01*
Y1137195D01*
G02X627756Y1136842I-851J849D01*
G01X627754D01*
X627676Y1136840D01*
G02X626545Y1135709I-1200J69D01*
G01X626543Y1135637D01*
Y1135633D01*
G02X626190Y1134791I-1202J9D01*
G01X626189D01*
X622694Y1131296D01*
G03X622645Y1131092I141J-142D01*
G01X622757Y1130752D01*
G03X622916Y1130617I190J63D01*
G01X622917D01*
G02X623938Y1129429I-181J-1188D01*
G02X621534I-1202J0D01*
G02X621553Y1129640I1202J-2D01*
G01X621561Y1129688D01*
X621532Y1129781D01*
X621497Y1129816D01*
G03X621215I-141J-142D01*
G01X621195Y1129797D01*
X621114Y1129716D01*
Y1129715D01*
G02X620276Y1129362I-851J849D01*
G01X620274D01*
X620196Y1129360D01*
G02X619065Y1128229I-1200J69D01*
G01X619063Y1128157D01*
Y1128153D01*
G02X618710Y1127311I-1202J9D01*
G01X618709D01*
X618608Y1127210D01*
G03Y1126927I141J-141D01*
G01X618643Y1126892D01*
X618736Y1126863D01*
X618784Y1126871D01*
G02X618996Y1126890I213J-1183D01*
G02X617794Y1125688I0J-1202D01*
G02X617813Y1125900I1202J-1D01*
G01X617821Y1125948D01*
X617792Y1126041D01*
X617698Y1126136D01*
X617617D01*
G03X617475Y1126077I0J-200D01*
G01X617372Y1125973D01*
G02X616535Y1125622I-849J851D01*
G01X616532D01*
X616456Y1125620D01*
G02X615324Y1124488I-1200J68D01*
G01X615322Y1124416D01*
Y1124412D01*
G02X614971Y1123572I-1202J9D01*
G01X614808Y1123410D01*
Y1123246D01*
X614903Y1123152D01*
X614996Y1123123D01*
X615044Y1123131D01*
G02X615256Y1123150I213J-1183D01*
G02X614054Y1121948I0J-1202D01*
G02X614073Y1122160I1202J-1D01*
G01X614081Y1122208D01*
X614052Y1122301D01*
X613958Y1122396D01*
X613877D01*
G03X613735Y1122337I0J-200D01*
G01X613632Y1122233D01*
G02X612795Y1121882I-849J851D01*
G01X612792D01*
X612716Y1121880D01*
G02X611584Y1120748I-1200J68D01*
G01X611582Y1120676D01*
Y1120672D01*
G02X611231Y1119832I-1202J9D01*
G01X611068Y1119670D01*
Y1119506D01*
X611163Y1119412D01*
X611256Y1119383D01*
X611304Y1119391D01*
G02X611516Y1119410I213J-1183D01*
G02X610314Y1118208I0J-1202D01*
G02X610333Y1118420I1202J-1D01*
G01X610341Y1118468D01*
X610312Y1118561D01*
X610218Y1118656D01*
X610137D01*
G03X609995Y1118597I0J-200D01*
G01X609892Y1118493D01*
G02X609055Y1118142I-849J851D01*
G01X609052D01*
X608976Y1118140D01*
G02X607844Y1117008I-1200J68D01*
G01X607842Y1116936D01*
Y1116932D01*
G02X607491Y1116092I-1202J9D01*
G01X607328Y1115930D01*
Y1115766D01*
X607423Y1115672D01*
X607516Y1115643D01*
X607564Y1115651D01*
G02X607776Y1115670I213J-1183D01*
G02Y1113266I0J-1202D01*
G02X606577Y1114384I0J1202D01*
G03X606480Y1114543I-200J-13D01*
G01X606154Y1114736D01*
X606057Y1114741D01*
X606012Y1114720D01*
G02X605805Y1114648I-497J1094D01*
G02X605513Y1114612I-292J1165D01*
G01X605436D01*
G03X605236Y1114420I0J-200D01*
G02X602834I-1201J48D01*
G03X602634Y1114612I-200J-8D01*
G01X601696D01*
G03X601496Y1114420I0J-200D01*
G02X599094I-1201J48D01*
G03X598894Y1114612I-200J-8D01*
G01X583617D01*
X583506Y1114517D01*
X583494Y1114444D01*
G02X582012Y1113189I-1482J248D01*
G02X580510Y1114691I0J1502D01*
G02X580714Y1115446I1502J-1D01*
G01X580748Y1115505D01*
X580731Y1115639D01*
X580140Y1116231D01*
X579871Y1116500D01*
G02X579812Y1116642I141J142D01*
G01Y1125037D01*
G02X579871Y1125179I200J0D01*
G01X580804Y1126112D01*
G03X580822Y1126375I-141J142D01*
G01X580821Y1126376D01*
G02X580510Y1127291I1191J915D01*
G01Y1127294D01*
G02X580583Y1127755I1502J-2D01*
G01X580600Y1127808D01*
X580574Y1127918D01*
X579731Y1128761D01*
G02X579672Y1128903I141J142D01*
G01Y1137282D01*
G02X579731Y1137424I200J0D01*
G01X580960Y1138652D01*
X580963Y1138813D01*
X580908Y1138872D01*
G02X580536Y1139611I1104J1019D01*
G01X580526Y1139664D01*
X580456Y1139745D01*
X579924Y1139928D01*
G02X579114Y1141064I391J1136D01*
G01Y1150274D01*
G02X579466Y1151123I1201J-1D01*
G01X579736Y1151393D01*
G02X580262Y1151701I850J-849D01*
G01X580298Y1151711D01*
X580359Y1151757D01*
X580520Y1152025D01*
G03X580544Y1152171I-171J103D01*
G02X580510Y1152491I1468J318D01*
G02X580579Y1152942I1502J1D01*
G01X580597Y1152998D01*
X580566Y1153112D01*
X580294Y1153355D01*
G02X579892Y1154250I800J897D01*
G01Y1162234D01*
G02X580245Y1163084I1202J-1D01*
G01X580905Y1163744D01*
G02X580926Y1163764I839J-860D01*
G01X580930Y1163967D01*
G03X580881Y1164103I-200J5D01*
G02X580520Y1164921I1131J988D01*
G01Y1164922D01*
G03X580321Y1165098I-199J-24D01*
G01X571211D01*
G03X571012Y1164922I0J-200D01*
G01Y1164921D01*
G02X569520Y1163589I-1492J170D01*
G02X568018Y1165091I0J1502D01*
G02X568602Y1166280I1502J0D01*
G01X568613Y1166288D01*
X568622Y1166297D01*
G03X568621Y1166580I-142J141D01*
G01X568571Y1166630D01*
X568448Y1166754D01*
G02X568296Y1166956I879J820D01*
G02X568126Y1167540I1031J617D01*
G01Y1175825D01*
G02X568285Y1176386I1201J-37D01*
G02X568359Y1176501I1046J-592D01*
G03X568353Y1176745I-161J118D01*
G02Y1178637I1167J946D01*
G03X568359Y1178881I-155J126D01*
G02X568285Y1178996I972J707D01*
G02X568126Y1179557I1042J598D01*
G01Y1191260D01*
G02X568185Y1191402I200J0D01*
G01X576526Y1199743D01*
G02X576668Y1199802I142J-141D01*
G01X598192D01*
X598210Y1199805D01*
G02X598424Y1199824I213J-1183D01*
G37*
G36*
G01X580465Y1105091D02*
G02X583469I1502J0D01*
G02X582908Y1103920I-1503J0D01*
G01X582872Y1103891D01*
X582833Y1103808D01*
X582838Y1103446D01*
G03X582917Y1103289I200J2D01*
G02X583514Y1102091I-905J-1199D01*
G02X580510I-1502J0D01*
G02X581071Y1103262I1503J0D01*
G01X581107Y1103291D01*
X581146Y1103374D01*
X581141Y1103736D01*
G03X581062Y1103893I-200J-2D01*
G02X580465Y1105091I905J1199D01*
G37*
G36*
G01X566502Y1200601D02*
G02X568004Y1202103I0J1502D01*
G02X567995Y1201941I-1502J2D01*
G01X567990Y1201897D01*
X568019Y1201813D01*
X568295Y1201527D01*
X568378Y1201496D01*
X568422Y1201499D01*
G02X568531Y1201503I110J-1498D01*
G01X568532D01*
G02X567030Y1200001I0J-1502D01*
G02X567039Y1200163I1502J-2D01*
G01X567044Y1200207D01*
X567015Y1200291D01*
X566739Y1200577D01*
X566656Y1200608D01*
X566612Y1200605D01*
G02X566503Y1200601I-110J1498D01*
G01X566502D01*
G37*
G36*
G01X626476Y1079605D02*
G02X627678Y1080807I0J1202D01*
G02X627657Y1080584I-1202J1D01*
G01X627648Y1080535D01*
X627677Y1080442D01*
X627946Y1080172D01*
G03X628123Y1080117I141J142D01*
G01X628124D01*
G02X628346Y1080138I224J-1181D01*
G02Y1077734I0J-1202D01*
G02X628124Y1077755I2J1202D01*
G01X628075Y1077764D01*
X627982Y1077735D01*
X627677Y1077430D01*
X627648Y1077337D01*
X627657Y1077288D01*
G02X627678Y1077066I-1181J-224D01*
G02X627657Y1076844I-1202J2D01*
G01X627648Y1076795D01*
X627677Y1076702D01*
X627982Y1076397D01*
X628075Y1076368D01*
X628124Y1076377D01*
G02X628346Y1076398I224J-1181D01*
G02Y1073994I0J-1202D01*
G02X628124Y1074015I2J1202D01*
G01X628075Y1074024D01*
X627982Y1073995D01*
X627677Y1073690D01*
X627648Y1073597D01*
X627657Y1073548D01*
G02X627678Y1073326I-1181J-224D01*
G02X626476Y1074528I-1202J0D01*
G02X626698Y1074507I-2J-1202D01*
G01X626747Y1074498D01*
X626840Y1074527D01*
X627145Y1074832D01*
X627174Y1074925D01*
X627165Y1074974D01*
G02X627144Y1075196I1181J224D01*
G02X627165Y1075418I1202J-2D01*
G01X627174Y1075467D01*
X627145Y1075560D01*
X626840Y1075865D01*
X626747Y1075894D01*
X626698Y1075885D01*
G02X626476Y1075864I-224J1181D01*
G02Y1078268I0J1202D01*
G02X626698Y1078247I-2J-1202D01*
G01X626747Y1078238D01*
X626840Y1078267D01*
X627145Y1078572D01*
X627174Y1078665D01*
X627165Y1078714D01*
G02X627144Y1078936I1181J224D01*
G02X627165Y1079159I1202J-1D01*
G01X627174Y1079208D01*
X627145Y1079301D01*
X626876Y1079571D01*
G03X626699Y1079626I-141J-142D01*
G01X626698D01*
G02X626476Y1079605I-224J1181D01*
G37*
G36*
G01X630884Y1105117D02*
G02X632086Y1103915I1202J0D01*
G02X631864Y1103936I2J1202D01*
G01X631815Y1103945D01*
X631722Y1103916D01*
X631417Y1103611D01*
X631388Y1103518D01*
X631397Y1103469D01*
G02X631418Y1103247I-1181J-224D01*
G02X631397Y1103025I-1202J2D01*
G01X631388Y1102976D01*
X631417Y1102883D01*
X631722Y1102578D01*
X631815Y1102549D01*
X631864Y1102558D01*
G02X632086Y1102579I224J-1181D01*
G02Y1100175I0J-1202D01*
G02X631864Y1100196I2J1202D01*
G01X631815Y1100205D01*
X631722Y1100176D01*
X631417Y1099871D01*
X631388Y1099778D01*
X631397Y1099729D01*
G02X631418Y1099507I-1181J-224D01*
G02X631397Y1099285I-1202J2D01*
G01X631388Y1099236D01*
X631417Y1099143D01*
X631722Y1098838D01*
X631815Y1098809D01*
X631864Y1098818D01*
G02X632086Y1098839I224J-1181D01*
G02X630884Y1097637I0J-1202D01*
G02X630905Y1097859I1202J-2D01*
G01X630914Y1097908D01*
X630885Y1098001D01*
X630580Y1098306D01*
X630487Y1098335D01*
X630438Y1098326D01*
G02X630216Y1098305I-224J1181D01*
G02X629994Y1098326I2J1202D01*
G01X629945Y1098335D01*
X629852Y1098306D01*
X629547Y1098001D01*
X629518Y1097908D01*
X629527Y1097859D01*
G02X629548Y1097637I-1181J-224D01*
G02X628346Y1096435I-1202J0D01*
G02X628124Y1096456I2J1202D01*
G01X628075Y1096465D01*
X627982Y1096436D01*
X627677Y1096131D01*
X627648Y1096038D01*
X627657Y1095989D01*
G02X627678Y1095767I-1181J-224D01*
G02X627657Y1095545I-1202J2D01*
G01X627648Y1095496D01*
X627677Y1095403D01*
X627982Y1095098D01*
X628075Y1095069D01*
X628124Y1095078D01*
G02X628346Y1095099I224J-1181D01*
G02Y1092695I0J-1202D01*
G02X628124Y1092716I2J1202D01*
G01X628075Y1092725D01*
X627982Y1092696D01*
X627677Y1092391D01*
X627648Y1092298D01*
X627657Y1092249D01*
G02X627678Y1092027I-1181J-224D01*
G02X627657Y1091805I-1202J2D01*
G01X627648Y1091756D01*
X627677Y1091663D01*
X627982Y1091358D01*
X628075Y1091329D01*
X628124Y1091338D01*
G02X628346Y1091359I224J-1181D01*
G02Y1088955I0J-1202D01*
G02X628124Y1088976I2J1202D01*
G01X628075Y1088985D01*
X627982Y1088956D01*
X627677Y1088651D01*
X627648Y1088558D01*
X627657Y1088509D01*
G02X627678Y1088287I-1181J-224D01*
G02X626476Y1089489I-1202J0D01*
G02X626698Y1089468I-2J-1202D01*
G01X626747Y1089459D01*
X626840Y1089488D01*
X627145Y1089793D01*
X627174Y1089886D01*
X627165Y1089935D01*
G02X627144Y1090157I1181J224D01*
G02X627165Y1090379I1202J-2D01*
G01X627174Y1090428D01*
X627145Y1090521D01*
X626840Y1090826D01*
X626747Y1090855D01*
X626698Y1090846D01*
G02X626476Y1090825I-224J1181D01*
G02Y1093229I0J1202D01*
G02X626698Y1093208I-2J-1202D01*
G01X626747Y1093199D01*
X626840Y1093228D01*
X627145Y1093533D01*
X627174Y1093626D01*
X627165Y1093675D01*
G02X627144Y1093897I1181J224D01*
G02X627165Y1094119I1202J-2D01*
G01X627174Y1094168D01*
X627145Y1094261D01*
X626840Y1094566D01*
X626747Y1094595D01*
X626698Y1094586D01*
G02X626476Y1094565I-224J1181D01*
G02Y1096969I0J1202D01*
G02X626698Y1096948I-2J-1202D01*
G01X626747Y1096939D01*
X626840Y1096968D01*
X627145Y1097273D01*
X627174Y1097366D01*
X627165Y1097415D01*
G02X627144Y1097637I1181J224D01*
G02X627165Y1097859I1202J-2D01*
G01X627174Y1097908D01*
X627145Y1098001D01*
X626840Y1098306D01*
X626747Y1098335D01*
X626698Y1098326D01*
G02X626476Y1098305I-224J1181D01*
G02X627678Y1099507I0J1202D01*
G02X627657Y1099285I-1202J2D01*
G01X627648Y1099236D01*
X627677Y1099143D01*
X627982Y1098838D01*
X628075Y1098809D01*
X628124Y1098818D01*
G02X628346Y1098839I224J-1181D01*
G02X628568Y1098818I-2J-1202D01*
G01X628617Y1098809D01*
X628710Y1098838D01*
X629015Y1099143D01*
X629044Y1099236D01*
X629035Y1099285D01*
G02X629014Y1099507I1181J224D01*
G02X630216Y1100709I1202J0D01*
G02X630438Y1100688I-2J-1202D01*
G01X630487Y1100679D01*
X630580Y1100708D01*
X630885Y1101013D01*
X630914Y1101106D01*
X630905Y1101155D01*
G02X630884Y1101377I1181J224D01*
G02X630905Y1101599I1202J-2D01*
G01X630914Y1101648D01*
X630885Y1101741D01*
X630580Y1102046D01*
X630487Y1102075D01*
X630438Y1102066D01*
G02X630216Y1102045I-224J1181D01*
G02Y1104449I0J1202D01*
G02X630438Y1104428I-2J-1202D01*
G01X630487Y1104419D01*
X630580Y1104448D01*
X630885Y1104753D01*
X630914Y1104846D01*
X630905Y1104895D01*
G02X630884Y1105117I1181J224D01*
G37*
G36*
G01X636495Y1110728D02*
G02X638899I1202J0D01*
G02X638878Y1110506I-1202J2D01*
G01X638869Y1110457D01*
X638898Y1110364D01*
X639203Y1110059D01*
X639296Y1110030D01*
X639345Y1110039D01*
G02X639567Y1110060I224J-1181D01*
G02X638365Y1108858I0J-1202D01*
G02X638386Y1109080I1202J-2D01*
G01X638395Y1109129D01*
X638366Y1109222D01*
X638061Y1109527D01*
X637968Y1109556D01*
X637919Y1109547D01*
G02X637697Y1109526I-224J1181D01*
G02X637475Y1109547I2J1202D01*
G01X637426Y1109556D01*
X637333Y1109527D01*
X637028Y1109222D01*
X636999Y1109129D01*
X637008Y1109080D01*
G02X637029Y1108858I-1181J-224D01*
G02X634625I-1202J0D01*
G02X634646Y1109080I1202J-2D01*
G01X634655Y1109129D01*
X634626Y1109222D01*
X634321Y1109527D01*
X634228Y1109556D01*
X634179Y1109547D01*
G02X633957Y1109526I-224J1181D01*
G02X633734Y1109547I1J1202D01*
G01X633685Y1109556D01*
X633592Y1109527D01*
X633322Y1109258D01*
G03X633267Y1109081I142J-141D01*
G01Y1109080D01*
G02X633288Y1108858I-1181J-224D01*
G02X630884I-1202J0D01*
G02X630905Y1109080I1202J-2D01*
G01X630914Y1109129D01*
X630885Y1109222D01*
X630580Y1109527D01*
X630487Y1109556D01*
X630438Y1109547D01*
G02X630216Y1109526I-224J1181D01*
G02X631418Y1110728I0J1202D01*
G02X631397Y1110506I-1202J2D01*
G01X631388Y1110457D01*
X631417Y1110364D01*
X631722Y1110059D01*
X631815Y1110030D01*
X631864Y1110039D01*
G02X632086Y1110060I224J-1181D01*
G02X632309Y1110039I-1J-1202D01*
G01X632358Y1110030D01*
X632451Y1110059D01*
X632721Y1110328D01*
G03X632776Y1110505I-142J141D01*
G01Y1110506D01*
G02X632755Y1110728I1181J224D01*
G02X635159I1202J0D01*
G02X635138Y1110506I-1202J2D01*
G01X635129Y1110457D01*
X635158Y1110364D01*
X635463Y1110059D01*
X635556Y1110030D01*
X635605Y1110039D01*
G02X635827Y1110060I224J-1181D01*
G02X636049Y1110039I-2J-1202D01*
G01X636098Y1110030D01*
X636191Y1110059D01*
X636496Y1110364D01*
X636525Y1110457D01*
X636516Y1110506D01*
G02X636495Y1110728I1181J224D01*
G37*
G36*
G01X642105Y1221062D02*
G02X643307Y1219860I1202J0D01*
G02X643085Y1219881I2J1202D01*
G01X643036Y1219890D01*
X642943Y1219861D01*
X642638Y1219556D01*
X642609Y1219463D01*
X642618Y1219414D01*
G02X642639Y1219192I-1181J-224D01*
G02X640235I-1202J0D01*
G02X640256Y1219414I1202J-2D01*
G01X640265Y1219463D01*
X640236Y1219556D01*
X639931Y1219861D01*
X639838Y1219890D01*
X639789Y1219881D01*
G02X639567Y1219860I-224J1181D01*
G02X640769Y1221062I0J1202D01*
G02X640748Y1220840I-1202J2D01*
G01X640739Y1220791D01*
X640768Y1220698D01*
X641073Y1220393D01*
X641166Y1220364D01*
X641215Y1220373D01*
G02X641437Y1220394I224J-1181D01*
G02X641659Y1220373I-2J-1202D01*
G01X641708Y1220364D01*
X641801Y1220393D01*
X642106Y1220698D01*
X642135Y1220791D01*
X642126Y1220840D01*
G02X642105Y1221062I1181J224D01*
G37*
G36*
G01X653325D02*
G02X654527Y1219860I1202J0D01*
G02X654305Y1219881I2J1202D01*
G01X654256Y1219890D01*
X654163Y1219861D01*
X653858Y1219556D01*
X653829Y1219463D01*
X653838Y1219414D01*
G02X653859Y1219192I-1181J-224D01*
G02X651455I-1202J0D01*
G02X651476Y1219414I1202J-2D01*
G01X651485Y1219463D01*
X651456Y1219556D01*
X651151Y1219861D01*
X651058Y1219890D01*
X651009Y1219881D01*
G02X650787Y1219860I-224J1181D01*
G02X650565Y1219881I2J1202D01*
G01X650516Y1219890D01*
X650423Y1219861D01*
X650118Y1219556D01*
X650089Y1219463D01*
X650098Y1219414D01*
G02X650119Y1219192I-1181J-224D01*
G02X647715I-1202J0D01*
G02X647736Y1219414I1202J-2D01*
G01X647745Y1219463D01*
X647716Y1219556D01*
X647411Y1219861D01*
X647318Y1219890D01*
X647269Y1219881D01*
G02X647047Y1219860I-224J1181D01*
G02X648249Y1221062I0J1202D01*
G02X648228Y1220840I-1202J2D01*
G01X648219Y1220791D01*
X648248Y1220698D01*
X648553Y1220393D01*
X648646Y1220364D01*
X648695Y1220373D01*
G02X648917Y1220394I224J-1181D01*
G02X649139Y1220373I-2J-1202D01*
G01X649188Y1220364D01*
X649281Y1220393D01*
X649586Y1220698D01*
X649615Y1220791D01*
X649606Y1220840D01*
G02X649585Y1221062I1181J224D01*
G02X651989I1202J0D01*
G02X651968Y1220840I-1202J2D01*
G01X651959Y1220791D01*
X651988Y1220698D01*
X652293Y1220393D01*
X652386Y1220364D01*
X652435Y1220373D01*
G02X652657Y1220394I224J-1181D01*
G02X652879Y1220373I-2J-1202D01*
G01X652928Y1220364D01*
X653021Y1220393D01*
X653326Y1220698D01*
X653355Y1220791D01*
X653346Y1220840D01*
G02X653325Y1221062I1181J224D01*
G37*
G36*
G01X679507D02*
G02X680709Y1219860I1202J0D01*
G02X680486Y1219881I1J1202D01*
G01X680437Y1219890D01*
X680344Y1219861D01*
X680074Y1219592D01*
G03X680019Y1219415I142J-141D01*
G01Y1219414D01*
G02X680040Y1219192I-1181J-224D01*
G02X677636I-1202J0D01*
G02X677657Y1219414I1202J-2D01*
G01X677666Y1219463D01*
X677637Y1219556D01*
X677332Y1219861D01*
X677239Y1219890D01*
X677190Y1219881D01*
G02X676968Y1219860I-224J1181D01*
G02X678170Y1221062I0J1202D01*
G02X678149Y1220840I-1202J2D01*
G01X678140Y1220791D01*
X678169Y1220698D01*
X678474Y1220393D01*
X678567Y1220364D01*
X678616Y1220373D01*
G02X678838Y1220394I224J-1181D01*
G02X679061Y1220373I-1J-1202D01*
G01X679110Y1220364D01*
X679203Y1220393D01*
X679473Y1220662D01*
G03X679528Y1220839I-142J141D01*
G01Y1220840D01*
G02X679507Y1221062I1181J224D01*
G37*
G36*
G01X514363Y1285868D02*
G02Y1288872I0J1502D01*
G02X515597Y1288226I0J-1502D01*
G01X515624Y1288188D01*
X515704Y1288143D01*
X516068Y1288125D01*
G03X516230Y1288195I10J200D01*
G02X517374Y1288724I1144J-972D01*
G02X518638Y1288033I0J-1502D01*
G01X518665Y1287991D01*
X518753Y1287942D01*
X519188Y1287937D01*
X519277Y1287983D01*
X519305Y1288025D01*
G02X520548Y1288683I1243J-845D01*
G02Y1285679I0J-1502D01*
G02X519284Y1286370I0J1502D01*
G01X519257Y1286412D01*
X519169Y1286461D01*
X518734Y1286466D01*
X518645Y1286420D01*
X518617Y1286378D01*
G02X517374Y1285720I-1243J845D01*
G02X516140Y1286366I0J1502D01*
G01X516113Y1286404D01*
X516033Y1286449D01*
X515669Y1286467D01*
G03X515507Y1286397I-10J-200D01*
G02X514363Y1285868I-1144J972D01*
G37*
G36*
G01X511258Y477078D02*
Y477372D01*
G03X511193Y477519I-200J-1D01*
G02X510708Y478625I1017J1105D01*
G02X513712I1502J0D01*
G02X513227Y477519I-1502J-1D01*
G03X513162Y477372I135J-148D01*
G01Y477078D01*
G03X513227Y476931I200J1D01*
G02X513712Y475825I-1017J-1105D01*
G02X510708I-1502J0D01*
G02X511193Y476931I1502J1D01*
G03X511258Y477078I-135J148D01*
G37*
G36*
G01X509407Y486221D02*
X509743D01*
X509810Y486246D01*
X509838Y486270D01*
G02X511812I987J-1131D01*
G01X511840Y486246D01*
X511907Y486221D01*
X512243D01*
X512310Y486246D01*
X512338Y486270D01*
G02X513325Y486640I987J-1131D01*
G02X514827Y485138I0J-1502D01*
G02X514560Y484283I-1502J0D01*
G01X514536Y484249D01*
X514520Y484168D01*
X514599Y483801D01*
X514647Y483734D01*
X514683Y483713D01*
G02X515412Y482425I-773J-1288D01*
G02X512408I-1502J0D01*
G02X512675Y483280I1502J0D01*
G01X512699Y483314D01*
X512715Y483395D01*
X512636Y483762D01*
X512588Y483829D01*
X512552Y483850D01*
G02X512338Y484006I774J1287D01*
G01X512310Y484030D01*
X512243Y484055D01*
X511907D01*
X511840Y484030D01*
X511812Y484006D01*
G02X509838I-987J1131D01*
G01X509810Y484030D01*
X509743Y484055D01*
X509407D01*
X509340Y484030D01*
X509312Y484006D01*
G02X508325Y483636I-987J1131D01*
G02X507204Y484139I0J1501D01*
G01X507175Y484171D01*
X507097Y484206D01*
X506711Y484205D01*
X506633Y484169D01*
X506604Y484137D01*
G02X505476Y483626I-1129J991D01*
G02Y486630I0J1502D01*
G02X506597Y486127I0J-1501D01*
G01X506626Y486095D01*
X506704Y486060D01*
X507090Y486061D01*
X507168Y486097D01*
X507197Y486129D01*
G02X508325Y486640I1129J-991D01*
G02X509312Y486270I0J-1501D01*
G01X509340Y486246D01*
X509407Y486221D01*
G37*
G36*
G01X518703Y492296D02*
Y492632D01*
X518678Y492699D01*
X518654Y492727D01*
G02X518284Y493714I1131J987D01*
G02X521288I1502J0D01*
G02X520918Y492727I-1501J0D01*
G01X520894Y492699D01*
X520869Y492632D01*
Y492296D01*
X520894Y492229D01*
X520918Y492201D01*
G02X521288Y491214I-1131J-987D01*
G02X518284I-1502J0D01*
G02X518654Y492201I1501J0D01*
G01X518678Y492229D01*
X518703Y492296D01*
G37*
G36*
G01X522406Y494069D02*
Y494405D01*
X522381Y494472D01*
X522357Y494500D01*
G02X521987Y495487I1131J987D01*
G02X524991I1502J0D01*
G02X524621Y494500I-1501J0D01*
G01X524597Y494472D01*
X524572Y494405D01*
Y494069D01*
X524597Y494002D01*
X524621Y493974D01*
G02X524991Y492987I-1131J-987D01*
G02X521987I-1502J0D01*
G02X522357Y493974I1501J0D01*
G01X522381Y494002D01*
X522406Y494069D01*
G37*
G36*
G01X534036Y497215D02*
Y497551D01*
X534011Y497618D01*
X533987Y497646D01*
G02X533617Y498633I1131J987D01*
G02X536621I1502J0D01*
G02X536251Y497646I-1501J0D01*
G01X536227Y497618D01*
X536202Y497551D01*
Y497215D01*
X536227Y497148D01*
X536251Y497120D01*
G02Y495146I-1131J-987D01*
G01X536227Y495118D01*
X536202Y495051D01*
Y494715D01*
X536227Y494648D01*
X536251Y494620D01*
G02Y492646I-1131J-987D01*
G01X536227Y492618D01*
X536202Y492551D01*
Y492215D01*
X536227Y492148D01*
X536251Y492120D01*
G02X536621Y491133I-1131J-987D01*
G02X533617I-1502J0D01*
G02X533987Y492120I1501J0D01*
G01X534011Y492148D01*
X534036Y492215D01*
Y492551D01*
X534011Y492618D01*
X533987Y492646D01*
G02Y494620I1131J987D01*
G01X534011Y494648D01*
X534036Y494715D01*
Y495051D01*
X534011Y495118D01*
X533987Y495146D01*
G02Y497120I1131J987D01*
G01X534011Y497148D01*
X534036Y497215D01*
G37*
G36*
G01X497910Y518484D02*
X498246D01*
X498313Y518509D01*
X498341Y518533D01*
G02X500315I987J-1131D01*
G01X500343Y518509D01*
X500410Y518484D01*
X500746D01*
X500813Y518509D01*
X500841Y518533D01*
G02X501828Y518903I987J-1131D01*
G02Y515899I0J-1502D01*
G02X500841Y516269I0J1501D01*
G01X500813Y516293D01*
X500746Y516318D01*
X500410D01*
X500343Y516293D01*
X500315Y516269D01*
G02X498341I-987J1131D01*
G01X498313Y516293D01*
X498246Y516318D01*
X497910D01*
X497843Y516293D01*
X497815Y516269D01*
G02X496828Y515899I-987J1131D01*
G02Y518903I0J1502D01*
G02X497815Y518533I0J-1501D01*
G01X497843Y518509D01*
X497910Y518484D01*
G37*
G36*
G01X501427Y523822D02*
Y524116D01*
G03X501362Y524263I-200J-1D01*
G02X500877Y525369I1017J1105D01*
G02X503881I1502J0D01*
G02X503396Y524263I-1502J-1D01*
G03X503331Y524116I135J-148D01*
G01Y523822D01*
G03X503396Y523675I200J1D01*
G02X503881Y522569I-1017J-1105D01*
G02X500877I-1502J0D01*
G02X501362Y523675I1502J1D01*
G03X501427Y523822I-135J148D01*
G37*
G36*
G01X508872Y539040D02*
Y539376D01*
X508847Y539443D01*
X508823Y539471D01*
G02X508453Y540458I1131J987D01*
G02X511457I1502J0D01*
G02X511087Y539471I-1501J0D01*
G01X511063Y539443D01*
X511038Y539376D01*
Y539040D01*
X511063Y538973D01*
X511087Y538945D01*
G02X511457Y537958I-1131J-987D01*
G02X508453I-1502J0D01*
G02X508823Y538945I1501J0D01*
G01X508847Y538973D01*
X508872Y539040D01*
G37*
G36*
G01X512575Y540813D02*
Y541149D01*
X512550Y541216D01*
X512526Y541244D01*
G02X512156Y542231I1131J987D01*
G02X515160I1502J0D01*
G02X514790Y541244I-1501J0D01*
G01X514766Y541216D01*
X514741Y541149D01*
Y540813D01*
X514766Y540746D01*
X514790Y540718D01*
G02X515160Y539731I-1131J-987D01*
G02X512156I-1502J0D01*
G02X512526Y540718I1501J0D01*
G01X512550Y540746D01*
X512575Y540813D01*
G37*
G36*
G01X502476Y554242D02*
X502182D01*
G03X502035Y554177I1J-200D01*
G02X500929Y553692I-1105J1017D01*
G02Y556696I0J1502D01*
G02X502035Y556211I1J-1502D01*
G03X502182Y556146I148J135D01*
G01X502476D01*
G03X502623Y556211I-1J200D01*
G02X503729Y556696I1105J-1017D01*
G02Y553692I0J-1502D01*
G02X502623Y554177I-1J1502D01*
G03X502476Y554242I-148J-135D01*
G37*
G36*
G01Y562242D02*
X502182D01*
G03X502035Y562177I1J-200D01*
G02X500929Y561692I-1105J1017D01*
G02Y564696I0J1502D01*
G02X502035Y564211I1J-1502D01*
G03X502182Y564146I148J135D01*
G01X502476D01*
G03X502623Y564211I-1J200D01*
G02X503729Y564696I1105J-1017D01*
G02Y561692I0J-1502D01*
G02X502623Y562177I-1J1502D01*
G03X502476Y562242I-148J-135D01*
G37*
G36*
G01Y570242D02*
X502182D01*
G03X502035Y570177I1J-200D01*
G02X500929Y569692I-1105J1017D01*
G02Y572696I0J1502D01*
G02X502035Y572211I1J-1502D01*
G03X502182Y572146I148J135D01*
G01X502476D01*
G03X502623Y572211I-1J200D01*
G02X503729Y572696I1105J-1017D01*
G02Y569692I0J-1502D01*
G02X502623Y570177I-1J1502D01*
G03X502476Y570242I-148J-135D01*
G37*
G36*
G01X503739Y582174D02*
X504033D01*
G03X504180Y582239I-1J200D01*
G02X505286Y582724I1105J-1017D01*
G02X506392Y582239I1J-1502D01*
G03X506539Y582174I148J135D01*
G01X506833D01*
G03X506980Y582239I-1J200D01*
G02X508086Y582724I1105J-1017D01*
G02Y579720I0J-1502D01*
G02X506980Y580205I-1J1502D01*
G03X506833Y580270I-148J-135D01*
G01X506539D01*
G03X506392Y580205I1J-200D01*
G02X505286Y579720I-1105J1017D01*
G02X504180Y580205I-1J1502D01*
G03X504033Y580270I-148J-135D01*
G01X503739D01*
G03X503592Y580205I1J-200D01*
G02X502486Y579720I-1105J1017D01*
G02Y582724I0J1502D01*
G02X503592Y582239I1J-1502D01*
G03X503739Y582174I148J135D01*
G37*
G36*
G01Y592167D02*
X504033D01*
G03X504180Y592232I-1J200D01*
G02X505286Y592717I1105J-1017D01*
G02X506392Y592232I1J-1502D01*
G03X506539Y592167I148J135D01*
G01X506833D01*
G03X506980Y592232I-1J200D01*
G02X508086Y592717I1105J-1017D01*
G02Y589713I0J-1502D01*
G02X506980Y590198I-1J1502D01*
G03X506833Y590263I-148J-135D01*
G01X506539D01*
G03X506392Y590198I1J-200D01*
G02X505286Y589713I-1105J1017D01*
G02X504180Y590198I-1J1502D01*
G03X504033Y590263I-148J-135D01*
G01X503739D01*
G03X503592Y590198I1J-200D01*
G02X502486Y589713I-1105J1017D01*
G02Y592717I0J1502D01*
G02X503592Y592232I1J-1502D01*
G03X503739Y592167I148J135D01*
G37*
G36*
G01X506711Y611514D02*
X507005D01*
G03X507152Y611579I-1J200D01*
G02X508258Y612064I1105J-1017D01*
G02X509364Y611579I1J-1502D01*
G03X509511Y611514I148J135D01*
G01X509805D01*
G03X509952Y611579I-1J200D01*
G02X511058Y612064I1105J-1017D01*
G02X512560Y610562I0J-1502D01*
G02X512075Y609456I-1502J-1D01*
G03X512010Y609309I135J-148D01*
G01Y609015D01*
G03X512075Y608868I200J1D01*
G02X512560Y607762I-1017J-1105D01*
G02X511058Y606260I-1502J0D01*
G02X509952Y606745I-1J1502D01*
G03X509805Y606810I-148J-135D01*
G01X509511D01*
G03X509364Y606745I1J-200D01*
G02X508258Y606260I-1105J1017D01*
G02X507152Y606745I-1J1502D01*
G03X507005Y606810I-148J-135D01*
G01X506711D01*
G03X506564Y606745I1J-200D01*
G02X505458Y606260I-1105J1017D01*
G02X504352Y606745I-1J1502D01*
G03X504205Y606810I-148J-135D01*
G01X503911D01*
G03X503764Y606745I1J-200D01*
G02X502658Y606260I-1105J1017D01*
G02X501156Y607762I0J1502D01*
G02X501641Y608868I1502J1D01*
G03X501706Y609015I-135J148D01*
G01Y609309D01*
G03X501641Y609456I-200J-1D01*
G02X501156Y610562I1017J1105D01*
G02X502658Y612064I1502J0D01*
G02X503764Y611579I1J-1502D01*
G03X503911Y611514I148J135D01*
G01X504205D01*
G03X504352Y611579I-1J200D01*
G02X505458Y612064I1105J-1017D01*
G02X506564Y611579I1J-1502D01*
G03X506711Y611514I148J135D01*
G37*
G36*
G01X525804Y617966D02*
Y618260D01*
G03X525739Y618407I-200J-1D01*
G02X525254Y619513I1017J1105D01*
G02X528258I1502J0D01*
G02X527773Y618407I-1502J-1D01*
G03X527708Y618260I135J-148D01*
G01Y617966D01*
G03X527773Y617819I200J1D01*
G02X528258Y616713I-1017J-1105D01*
G02X527773Y615607I-1502J-1D01*
G03X527708Y615460I135J-148D01*
G01Y615166D01*
G03X527773Y615019I200J1D01*
G02X528258Y613913I-1017J-1105D01*
G02X525254I-1502J0D01*
G02X525739Y615019I1502J1D01*
G03X525804Y615166I-135J148D01*
G01Y615460D01*
G03X525739Y615607I-200J-1D01*
G02X525254Y616713I1017J1105D01*
G02X525739Y617819I1502J1D01*
G03X525804Y617966I-135J148D01*
G37*
G36*
G01X537874Y618211D02*
Y618505D01*
G03X537809Y618652I-200J-1D01*
G02X537324Y619758I1017J1105D01*
G02X540328I1502J0D01*
G02X539843Y618652I-1502J-1D01*
G03X539778Y618505I135J-148D01*
G01Y618211D01*
G03X539843Y618064I200J1D01*
G02X540328Y616958I-1017J-1105D01*
G02X539843Y615852I-1502J-1D01*
G03X539778Y615705I135J-148D01*
G01Y615411D01*
G03X539843Y615264I200J1D01*
G02X540328Y614158I-1017J-1105D01*
G02X537324I-1502J0D01*
G02X537809Y615264I1502J1D01*
G03X537874Y615411I-135J148D01*
G01Y615705D01*
G03X537809Y615852I-200J-1D01*
G02X537324Y616958I1017J1105D01*
G02X537809Y618064I1502J1D01*
G03X537874Y618211I-135J148D01*
G37*
G36*
G01X517988Y619106D02*
Y619400D01*
G03X517923Y619547I-200J-1D01*
G02X517438Y620653I1017J1105D01*
G02X520442I1502J0D01*
G02X519957Y619547I-1502J-1D01*
G03X519892Y619400I135J-148D01*
G01Y619106D01*
G03X519957Y618959I200J1D01*
G02X520442Y617853I-1017J-1105D01*
G02X517438I-1502J0D01*
G02X517923Y618959I1502J1D01*
G03X517988Y619106I-135J148D01*
G37*
G36*
G01X529500Y499103D02*
X529794D01*
G03X529941Y499168I-1J200D01*
G02X531047Y499653I1105J-1017D01*
G02X532549Y498151I0J-1502D01*
G02X531970Y496966I-1502J0D01*
G03X531893Y496809I123J-158D01*
G01Y496493D01*
G03X531970Y496336I200J1D01*
G02X532549Y495151I-923J-1185D01*
G02X531047Y493649I-1502J0D01*
G02X530060Y494019I0J1501D01*
G01X530032Y494043D01*
X529965Y494068D01*
X529629D01*
X529562Y494043D01*
X529534Y494019D01*
G02X528547Y493649I-987J1131D01*
G02X527045Y495151I0J1502D01*
G02X527517Y496244I1502J0D01*
G01X527552Y496277D01*
X527584Y496363D01*
X527543Y496773D01*
X527494Y496850D01*
X527454Y496875D01*
G02X526745Y498151I794J1276D01*
G02X528247Y499653I1502J0D01*
G02X529353Y499168I1J-1502D01*
G03X529500Y499103I148J135D01*
G37*
G36*
G01X496658Y531062D02*
X496629Y531025D01*
G02X495444Y530446I-1185J923D01*
G02Y533450I0J1502D01*
G02X496668Y532819I0J-1503D01*
G01X496695Y532780D01*
X496779Y532736D01*
X497194Y532727D01*
X497280Y532768D01*
X497309Y532805D01*
G02X498494Y533384I1185J-923D01*
G02X499481Y533014I0J-1501D01*
G01X499509Y532990D01*
X499576Y532965D01*
X499912D01*
X499979Y532990D01*
X500007Y533014D01*
G02X501981I987J-1131D01*
G01X502009Y532990D01*
X502076Y532965D01*
X502412D01*
X502479Y532990D01*
X502507Y533014D01*
G02X503494Y533384I987J-1131D01*
G02X504996Y531882I0J-1502D01*
G02X504729Y531027I-1502J0D01*
G01X504705Y530993D01*
X504689Y530912D01*
X504768Y530545D01*
X504816Y530478D01*
X504852Y530457D01*
G02X505581Y529169I-773J-1288D01*
G02X502577I-1502J0D01*
G02X502844Y530024I1502J0D01*
G01X502868Y530058D01*
X502884Y530139D01*
X502805Y530506D01*
X502757Y530573D01*
X502721Y530594D01*
G02X502507Y530750I774J1287D01*
G01X502479Y530774D01*
X502412Y530799D01*
X502076D01*
X502009Y530774D01*
X501981Y530750D01*
G02X500007I-987J1131D01*
G01X499979Y530774D01*
X499912Y530799D01*
X499576D01*
X499509Y530774D01*
X499481Y530750D01*
G02X498494Y530380I-987J1131D01*
G02X497270Y531011I0J1503D01*
G01X497243Y531050D01*
X497159Y531094D01*
X496744Y531103D01*
X496658Y531062D01*
G37*
G36*
G01X519669Y545847D02*
X519963D01*
G03X520110Y545912I-1J200D01*
G02X521216Y546397I1105J-1017D01*
G02X522718Y544895I0J-1502D01*
G02X522139Y543710I-1502J0D01*
G03X522062Y543553I123J-158D01*
G01Y543237D01*
G03X522139Y543080I200J1D01*
G02X522718Y541895I-923J-1185D01*
G02X521216Y540393I-1502J0D01*
G02X520229Y540763I0J1501D01*
G01X520201Y540787D01*
X520134Y540812D01*
X519798D01*
X519731Y540787D01*
X519703Y540763D01*
G02X518716Y540393I-987J1131D01*
G02X517214Y541895I0J1502D01*
G02X517686Y542988I1502J0D01*
G01X517721Y543021D01*
X517753Y543107D01*
X517712Y543517D01*
X517663Y543594D01*
X517623Y543619D01*
G02X516914Y544895I794J1276D01*
G02X518416Y546397I1502J0D01*
G02X519522Y545912I1J-1502D01*
G03X519669Y545847I148J135D01*
G37*
G36*
G01X532070Y549427D02*
X532406D01*
X532473Y549452D01*
X532501Y549476D01*
G02X533488Y549846I987J-1131D01*
G02Y546842I0J-1502D01*
G02X532501Y547212I0J1501D01*
G01X532473Y547236D01*
X532406Y547261D01*
X532070D01*
X532003Y547236D01*
X531975Y547212D01*
G02X530001I-987J1131D01*
G01X529973Y547236D01*
X529906Y547261D01*
X529570D01*
X529503Y547236D01*
X529475Y547212D01*
G02X527501I-987J1131D01*
G01X527473Y547236D01*
X527406Y547261D01*
X527070D01*
X527003Y547236D01*
X526975Y547212D01*
G02X526586Y546966I-988J1131D01*
G01X526542Y546947D01*
X526482Y546876D01*
X526386Y546470D01*
X526408Y546379D01*
X526439Y546342D01*
G02X526790Y545377I-1151J-965D01*
G02X526420Y544390I-1501J0D01*
G01X526396Y544362D01*
X526371Y544295D01*
Y543959D01*
X526396Y543892D01*
X526420Y543864D01*
G02Y541890I-1131J-987D01*
G01X526396Y541862D01*
X526371Y541795D01*
Y541459D01*
X526396Y541392D01*
X526420Y541364D01*
G02Y539390I-1131J-987D01*
G01X526396Y539362D01*
X526371Y539295D01*
Y538959D01*
X526396Y538892D01*
X526420Y538864D01*
G02X526790Y537877I-1131J-987D01*
G02X523786I-1502J0D01*
G02X524156Y538864I1501J0D01*
G01X524180Y538892D01*
X524205Y538959D01*
Y539295D01*
X524180Y539362D01*
X524156Y539390D01*
G02Y541364I1131J987D01*
G01X524180Y541392D01*
X524205Y541459D01*
Y541795D01*
X524180Y541862D01*
X524156Y541890D01*
G02Y543864I1131J987D01*
G01X524180Y543892D01*
X524205Y543959D01*
Y544295D01*
X524180Y544362D01*
X524156Y544390D01*
G02X523786Y545377I1131J987D01*
G02X524690Y546755I1502J0D01*
G01X524734Y546774D01*
X524794Y546845D01*
X524890Y547251D01*
X524868Y547342D01*
X524837Y547379D01*
G02X524486Y548344I1151J965D01*
G02X525988Y549846I1502J0D01*
G02X526975Y549476I0J-1501D01*
G01X527003Y549452D01*
X527070Y549427D01*
X527406D01*
X527473Y549452D01*
X527501Y549476D01*
G02X529475I987J-1131D01*
G01X529503Y549452D01*
X529570Y549427D01*
X529906D01*
X529973Y549452D01*
X530001Y549476D01*
G02X531975I987J-1131D01*
G01X532003Y549452D01*
X532070Y549427D01*
G37*
G36*
G01X534349Y565573D02*
G02X533717Y566797I869J1224D01*
G02X536721I1502J0D01*
G02X536089Y565573I-1501J0D01*
G03X536005Y565410I116J-163D01*
G01Y565084D01*
G03X536089Y564921I200J0D01*
G02X536721Y563697I-869J-1224D01*
G02X536315Y562670I-1502J0D01*
G01X536289Y562642D01*
X536261Y562573D01*
Y562221D01*
X536289Y562152D01*
X536315Y562124D01*
G02Y560070I-1096J-1027D01*
G01X536289Y560042D01*
X536261Y559973D01*
Y559621D01*
X536289Y559552D01*
X536315Y559524D01*
G02Y557470I-1096J-1027D01*
G01X536289Y557442D01*
X536261Y557373D01*
Y557021D01*
X536289Y556952D01*
X536315Y556924D01*
G02Y554870I-1096J-1027D01*
G01X536289Y554842D01*
X536261Y554773D01*
Y554421D01*
X536289Y554352D01*
X536315Y554324D01*
G02X536721Y553297I-1096J-1027D01*
G02X533717I-1502J0D01*
G02X534123Y554324I1502J0D01*
G01X534149Y554352D01*
X534177Y554421D01*
Y554773D01*
X534149Y554842D01*
X534123Y554870D01*
G02Y556924I1096J1027D01*
G01X534149Y556952D01*
X534177Y557021D01*
Y557373D01*
X534149Y557442D01*
X534123Y557470D01*
G02Y559524I1096J1027D01*
G01X534149Y559552D01*
X534177Y559621D01*
Y559973D01*
X534149Y560042D01*
X534123Y560070D01*
G02Y562124I1096J1027D01*
G01X534149Y562152D01*
X534177Y562221D01*
Y562573D01*
X534149Y562642D01*
X534123Y562670D01*
G02X533717Y563697I1096J1027D01*
G02X534349Y564921I1501J0D01*
G03X534433Y565084I-116J163D01*
G01Y565410D01*
G03X534349Y565573I-200J0D01*
G37*
G36*
G01X531312Y575476D02*
X531284Y575508D01*
G02X530924Y576484I1143J976D01*
G02X533928I1502J0D01*
G02X533286Y575253I-1501J0D01*
G01X533251Y575228D01*
X533207Y575156D01*
X533159Y574778D01*
X533183Y574697D01*
X533211Y574665D01*
G02X533571Y573689I-1143J-976D01*
G02X532850Y572406I-1502J0D01*
G01X532806Y572379D01*
X532755Y572291D01*
X532747Y571849D01*
X532794Y571759D01*
X532837Y571731D01*
G02X533511Y570478I-828J-1253D01*
G02X532009Y568976I-1502J0D01*
G02X530830Y569547I0J1503D01*
G01X530803Y569581D01*
X530731Y569620D01*
X530351Y569648D01*
X530274Y569621D01*
X530242Y569591D01*
G02X529214Y569184I-1028J1095D01*
G02X527712Y570686I0J1502D01*
G02X528213Y571806I1502J0D01*
G01X528242Y571832D01*
X528276Y571900D01*
X528304Y572253D01*
X528282Y572326D01*
X528257Y572356D01*
G02X527921Y573303I1167J947D01*
G02X529423Y574805I1502J0D01*
G02X530314Y574512I0J-1501D01*
G01X530346Y574489D01*
X530421Y574470D01*
X530779Y574522D01*
X530846Y574562D01*
X530870Y574594D01*
G02X531209Y574920I1198J-906D01*
G01X531244Y574945D01*
X531288Y575017D01*
X531336Y575395D01*
X531312Y575476D01*
G37*
G36*
G01X501010Y619590D02*
G02X500448Y620661I739J1071D01*
G02X503052I1302J0D01*
G02X502490Y619590I-1301J0D01*
G03Y618932I228J-329D01*
G02X503052Y617861I-739J-1071D01*
G02X500448I-1302J0D01*
G02X501010Y618932I1301J0D01*
G03Y619590I-228J329D01*
G37*
G36*
G01X504553D02*
G02X503991Y620661I739J1071D01*
G02X506595I1302J0D01*
G02X506033Y619590I-1301J0D01*
G03Y618932I228J-329D01*
G02X506595Y617861I-739J-1071D01*
G02X503991I-1302J0D01*
G02X504553Y618932I1301J0D01*
G03Y619590I-228J329D01*
G37*
G36*
G01X508096D02*
G02X507534Y620661I739J1071D01*
G02X510138I1302J0D01*
G02X509576Y619590I-1301J0D01*
G03Y618932I228J-329D01*
G02X510138Y617861I-739J-1071D01*
G02X507534I-1302J0D01*
G02X508096Y618932I1301J0D01*
G03Y619590I-228J329D01*
G37*
G36*
G01X511640D02*
G02X511078Y620661I739J1071D01*
G02X513682I1302J0D01*
G02X513120Y619590I-1301J0D01*
G03Y618932I228J-329D01*
G02X513682Y617861I-739J-1071D01*
G02X511078I-1302J0D01*
G02X511640Y618932I1301J0D01*
G03Y619590I-228J329D01*
G37*
G36*
G01X499528Y656341D02*
G02Y659345I0J1502D01*
G02X500839Y658576I0J-1502D01*
G03X501517Y658545I349J196D01*
G02X502755Y659196I1238J-852D01*
G02Y656192I0J-1502D01*
G02X501444Y656961I0J1502D01*
G03X500766Y656992I-349J-196D01*
G02X499528Y656341I-1238J852D01*
G37*
G36*
G01X526264Y665858D02*
X529664D01*
G02Y662254I0J-1802D01*
G01X526264D01*
G02Y665858I0J1802D01*
G37*
G36*
G01X496782Y681453D02*
G02X499786I1502J0D01*
G02X499416Y680466I-1501J0D01*
G01Y680465D01*
X499415D01*
G03X499367Y680335I152J-130D01*
G01Y680071D01*
G03X499415Y679941I200J0D01*
G01X499416Y679940D01*
G02X499786Y678953I-1131J-987D01*
G02X496782I-1502J0D01*
G02X497152Y679940I1501J0D01*
G01Y679941D01*
X497153D01*
G03X497201Y680071I-152J130D01*
G01Y680335D01*
G03X497153Y680465I-200J0D01*
G01X497152Y680466D01*
G02X496782Y681453I1131J987D01*
G37*
G36*
G01X535738Y688991D02*
G02X536812Y688539I0J-1502D01*
G03X536945Y688479I143J140D01*
G01X537254Y688463D01*
X537325Y688487D01*
X537354Y688511D01*
G02X538315Y688859I961J-1154D01*
G01X538316D01*
G02Y685855I0J-1502D01*
G02X537242Y686307I0J1502D01*
G03X537109Y686367I-143J-140D01*
G01X536800Y686383D01*
X536729Y686359D01*
X536700Y686335D01*
G02X535739Y685987I-961J1154D01*
G01X535738D01*
G02Y688991I0J1502D01*
G37*
G36*
G01X514017Y695757D02*
G02X516951I1467J0D01*
G02X516193Y694473I-1467J0D01*
G01X516144Y694446D01*
X516089Y694351D01*
X516098Y693884D01*
X516156Y693791D01*
X516206Y693766D01*
G02X516677Y693379I-633J-1251D01*
G01X516678Y693378D01*
G03X516826Y693302I157J124D01*
G01X517171Y693285D01*
X517252Y693318D01*
X517282Y693350D01*
G02X518299Y693786I1016J-966D01*
G02X519272Y693394I1J-1402D01*
G01X519301Y693366D01*
X519371Y693338D01*
X519727D01*
X519797Y693366D01*
X519826Y693394D01*
G02X520798Y693786I972J-1010D01*
G01X520799D01*
G02Y690982I0J-1402D01*
G01X520798D01*
G02X519826Y691374I0J1402D01*
G01X519797Y691402D01*
X519727Y691430D01*
X519371D01*
X519301Y691402D01*
X519272Y691374D01*
G02X518300Y690982I-972J1010D01*
G01X518299D01*
G02X517195Y691520I0J1402D01*
G01X517194Y691521D01*
G03X517046Y691597I-157J-124D01*
G01X516701Y691614D01*
X516620Y691581D01*
X516590Y691549D01*
G02X515575Y691113I-1016J966D01*
G01X515573D01*
G02X514171Y692515I0J1402D01*
G02X514872Y693729I1402J0D01*
G01X514873Y693730D01*
G03X514973Y693910I-100J173D01*
G01X514957Y694319D01*
X514896Y694412D01*
X514846Y694436D01*
G02X514017Y695757I638J1321D01*
G37*
G36*
G01X512530Y719803D02*
G02X514032Y718298I0J-1502D01*
G03X514094Y718153I200J0D01*
G01X514334Y717924D01*
X514412Y717896D01*
X514453Y717898D01*
G02X514530Y717900I77J-1500D01*
G01X514531D01*
G02Y714896I0J-1502D01*
G02X513029Y716401I0J1502D01*
G03X512967Y716546I-200J0D01*
G01X512727Y716775D01*
X512649Y716803D01*
X512608Y716801D01*
G02X512531Y716799I-77J1500D01*
G01X512530D01*
G02Y719803I0J1502D01*
G37*
G36*
G01X535585Y738396D02*
X538985D01*
G02Y734790I0J-1803D01*
G01X535585D01*
G02Y738396I0J1803D01*
G37*
G36*
G01X508324Y742838D02*
X511724D01*
G02Y739232I0J-1803D01*
G01X508324D01*
G02Y742838I0J1803D01*
G37*
G36*
G01X517731Y742874D02*
X521131D01*
G02Y739268I0J-1803D01*
G01X517731D01*
G02Y742874I0J1803D01*
G37*
G36*
G01X527585Y743396D02*
X530985D01*
G02Y739790I0J-1803D01*
G01X527585D01*
G02Y743396I0J1803D01*
G37*
G36*
G01X553089Y783953D02*
X552792D01*
G03X552643Y783887I-1J-200D01*
G02X551524Y783387I-1119J1002D01*
G02Y786391I0J1502D01*
G02X552643Y785891I0J-1502D01*
G03X552792Y785825I148J134D01*
G01X553089D01*
G03X553238Y785891I1J200D01*
G02X554357Y786391I1119J-1002D01*
G02Y783387I0J-1502D01*
G02X553238Y783887I0J1502D01*
G03X553089Y783953I-148J-134D01*
G37*
G36*
G01X529758Y794934D02*
G02X532762I1502J0D01*
G02X532442Y794007I-1503J0D01*
G01Y794006D01*
G03X532400Y793865I157J-124D01*
G01X532426Y793590D01*
G03X532491Y793460I199J18D01*
G01X532492Y793459D01*
G02X533003Y792331I-991J-1129D01*
G02X529999I-1502J0D01*
G02X530319Y793258I1503J0D01*
G01Y793259D01*
G03X530361Y793400I-157J124D01*
G01X530335Y793675D01*
G03X530270Y793805I-199J-18D01*
G01X530269Y793806D01*
G02X529758Y794934I991J1129D01*
G37*
G36*
G01X530164Y815724D02*
G02X533168I1502J0D01*
G02X532493Y814470I-1502J0D01*
G01X532457Y814447D01*
X532410Y814371D01*
X532368Y814025D01*
G03X532419Y813866I199J-24D01*
G02X532815Y812850I-1105J-1016D01*
G02X529811I-1502J0D01*
G02X530486Y814104I1502J0D01*
G01X530522Y814127D01*
X530569Y814203D01*
X530611Y814549D01*
G03X530560Y814708I-199J24D01*
G02X530164Y815724I1105J1016D01*
G37*
G36*
G01X560263Y828487D02*
G02Y831491I0J1502D01*
G02X561399Y830972I0J-1503D01*
G01X561400Y830971D01*
G03X561547Y830903I150J132D01*
G01X561888Y830897D01*
X561967Y830931D01*
X561995Y830962D01*
G02X563099Y831445I1104J-1020D01*
G02Y828441I0J-1502D01*
G02X561963Y828960I0J1503D01*
G01X561962Y828961D01*
G03X561815Y829029I-150J-132D01*
G01X561474Y829035D01*
X561395Y829001D01*
X561367Y828970D01*
G02X560263Y828487I-1104J1020D01*
G37*
G36*
G01X566618Y804894D02*
G02X565814Y806224I698J1330D01*
G02X568818I1502J0D01*
G02X568206Y805014I-1502J0D01*
G03X568257Y804338I237J-322D01*
G02X569061Y803008I-698J-1330D01*
G02X566057I-1502J0D01*
G02X566669Y804218I1502J0D01*
G03X566618Y804894I-237J322D01*
G37*
G36*
G01X560267Y805579D02*
G02X559499Y806889I733J1310D01*
G02X562503I1502J0D01*
G02X561783Y805607I-1501J0D01*
G03X561795Y804916I208J-342D01*
G02X562563Y803606I-733J-1310D01*
G02X559559I-1502J0D01*
G02X560279Y804888I1501J0D01*
G03X560267Y805579I-208J342D01*
G37*
G36*
G01X566529Y826445D02*
G02X565814Y827724I786J1279D01*
G02X568818I1502J0D01*
G02X568295Y826585I-1502J0D01*
G03X568346Y825940I260J-304D01*
G02X569061Y824661I-786J-1279D01*
G02X566057I-1502J0D01*
G02X566580Y825800I1502J0D01*
G03X566529Y826445I-260J304D01*
G37*
G36*
G01X571549Y844353D02*
G02X570974Y845535I927J1182D01*
G02X573978I1502J0D01*
G02X573162Y844199I-1502J0D01*
G03X573098Y843528I182J-356D01*
G02X573673Y842346I-927J-1182D01*
G02X570669I-1502J0D01*
G02X571485Y843682I1502J0D01*
G03X571549Y844353I-182J356D01*
G37*
G36*
G01X545306Y845047D02*
G02X544479Y846389I675J1342D01*
G02X547483I1502J0D01*
G02X546861Y845172I-1502J0D01*
G03X546916Y844491I235J-324D01*
G02X547743Y843149I-675J-1342D01*
G02X544739I-1502J0D01*
G02X545361Y844366I1502J0D01*
G03X545306Y845047I-235J324D01*
G37*
G36*
G01X605733Y939336D02*
G02Y942940I0J1802D01*
G01X609133D01*
G02Y939336I0J-1802D01*
G01X605733D01*
G37*
G36*
G01X592792Y1010637D02*
X592786Y1011046D01*
X592745Y1011127D01*
X592708Y1011156D01*
G02X592111Y1012354I905J1199D01*
G02X595115I1502J0D01*
G02X594554Y1011183I-1503J0D01*
G01X594518Y1011154D01*
X594479Y1011071D01*
X594485Y1010662D01*
X594526Y1010581D01*
X594563Y1010552D01*
G02X595160Y1009354I-905J-1199D01*
G02X592156I-1502J0D01*
G02X592717Y1010525I1503J0D01*
G01X592753Y1010554D01*
X592792Y1010637D01*
G37*
G36*
G01Y1023237D02*
X592786Y1023646D01*
X592745Y1023727D01*
X592708Y1023756D01*
G02X592111Y1024954I905J1199D01*
G02X595115I1502J0D01*
G02X594554Y1023783I-1503J0D01*
G01X594518Y1023754D01*
X594479Y1023671D01*
X594485Y1023262D01*
X594526Y1023181D01*
X594563Y1023152D01*
G02X595160Y1021954I-905J-1199D01*
G02X592156I-1502J0D01*
G02X592717Y1023125I1503J0D01*
G01X592753Y1023154D01*
X592792Y1023237D01*
G37*
G36*
G01X620860Y1032550D02*
G02X620090Y1033862I733J1312D01*
G02X623094I1502J0D01*
G02X622235Y1032504I-1503J0D01*
G03X622211Y1031794I171J-361D01*
G02X622981Y1030482I-733J-1312D01*
G02X619977I-1502J0D01*
G02X620836Y1031840I1503J0D01*
G03X620860Y1032550I-171J361D01*
G37*
G36*
G01X1098792Y1588423D02*
G03X1098427Y1588935I-384J112D01*
G02X1096996Y1590435I71J1500D01*
G02X1100000I1502J0D01*
G02X1099939Y1590012I-1502J1D01*
G03X1100304Y1589500I384J-112D01*
G02X1101735Y1588000I-71J-1500D01*
G02X1098731I-1502J0D01*
G02X1098792Y1588423I1502J-1D01*
G37*
G36*
G01X1090904Y1597545D02*
G02Y1600549I0J1502D01*
G02X1091865Y1600201I0J-1501D01*
G03X1092029Y1600158I128J154D01*
G01X1092332Y1600213D01*
G03X1092470Y1600312I-37J197D01*
G02X1093778Y1601076I1308J-738D01*
G02Y1598072I0J-1502D01*
G02X1092817Y1598420I0J1501D01*
G03X1092653Y1598463I-128J-154D01*
G01X1092350Y1598408D01*
G03X1092212Y1598309I37J-197D01*
G02X1090904Y1597545I-1308J738D01*
G37*
G36*
G01X627954Y1613250D02*
Y1614376D01*
G02X628157Y1614578I203J-1D01*
G01X630977D01*
G02X631180Y1614376I1J-202D01*
G01Y1613250D01*
G03X631208Y1613147I200J-1D01*
G02Y1611185I-1642J-981D01*
G03X631180Y1611082I172J-102D01*
G01Y1608132D01*
G03X631208Y1608029I200J-1D01*
G02Y1606067I-1642J-981D01*
G03X631180Y1605964I172J-102D01*
G01Y1604838D01*
G02X630977Y1604636I-203J1D01*
G01X628157D01*
G02X627954Y1604838I-1J202D01*
G01Y1605964D01*
G03X627926Y1606067I-200J1D01*
G02Y1608029I1642J981D01*
G03X627954Y1608132I-172J102D01*
G01Y1611082D01*
G03X627926Y1611185I-200J1D01*
G02Y1613147I1642J981D01*
G03X627954Y1613250I-172J102D01*
G37*
G36*
G01X645278D02*
Y1614376D01*
G02X645480Y1614578I202J0D01*
G01X648300D01*
G02X648502Y1614376I0J-202D01*
G01Y1613250D01*
G03X648530Y1613147I200J-1D01*
G02X648802Y1612166I-1640J-983D01*
G02X648530Y1611185I-1912J2D01*
G03X648502Y1611082I172J-102D01*
G01Y1608132D01*
G03X648530Y1608029I200J-1D01*
G02X648802Y1607048I-1640J-983D01*
G02X648530Y1606067I-1912J2D01*
G03X648502Y1605964I172J-102D01*
G01Y1604838D01*
G02X648300Y1604636I-202J0D01*
G01X645480D01*
G02X645278Y1604838I0J202D01*
G01Y1605964D01*
G03X645250Y1606067I-200J1D01*
G02X644978Y1607048I1640J983D01*
G02X645250Y1608029I1912J-2D01*
G03X645278Y1608132I-172J102D01*
G01Y1611082D01*
G03X645250Y1611185I-200J1D01*
G02X644978Y1612166I1640J983D01*
G02X645250Y1613147I1912J-2D01*
G03X645278Y1613250I-172J102D01*
G37*
G36*
G01X662600D02*
Y1614376D01*
G02X662803Y1614578I203J-1D01*
G01X665623D01*
G02X665826Y1614376I1J-202D01*
G01Y1613250D01*
G03X665854Y1613147I200J-1D01*
G02Y1611185I-1642J-981D01*
G03X665826Y1611082I172J-102D01*
G01Y1608132D01*
G03X665854Y1608029I200J-1D01*
G02Y1606067I-1642J-981D01*
G03X665826Y1605964I172J-102D01*
G01Y1604838D01*
G02X665623Y1604636I-203J1D01*
G01X662803D01*
G02X662600Y1604838I-1J202D01*
G01Y1605964D01*
G03X662572Y1606067I-200J1D01*
G02Y1608029I1642J981D01*
G03X662600Y1608132I-172J102D01*
G01Y1611082D01*
G03X662572Y1611185I-200J1D01*
G02Y1613147I1642J981D01*
G03X662600Y1613250I-172J102D01*
G37*
G36*
G01X679922D02*
Y1614376D01*
G02X680125Y1614578I203J-1D01*
G01X682945D01*
G02X683148Y1614376I1J-202D01*
G01Y1613250D01*
G03X683176Y1613147I200J-1D01*
G02Y1611185I-1642J-981D01*
G03X683148Y1611082I172J-102D01*
G01Y1608132D01*
G03X683176Y1608029I200J-1D01*
G02Y1606067I-1642J-981D01*
G03X683148Y1605964I172J-102D01*
G01Y1604838D01*
G02X682945Y1604636I-203J1D01*
G01X680125D01*
G02X679922Y1604838I-1J202D01*
G01Y1605964D01*
G03X679894Y1606067I-200J1D01*
G02Y1608029I1642J981D01*
G03X679922Y1608132I-172J102D01*
G01Y1611082D01*
G03X679894Y1611185I-200J1D01*
G02Y1613147I1642J981D01*
G03X679922Y1613250I-172J102D01*
G37*
G36*
G01X636616Y1617580D02*
Y1618706D01*
G02X636818Y1618908I202J0D01*
G01X639638D01*
G02X639840Y1618706I0J-202D01*
G01Y1617580D01*
G03X639868Y1617477I200J-1D01*
G02X640140Y1616496I-1640J-983D01*
G02X639868Y1615515I-1912J2D01*
G03X639840Y1615412I172J-102D01*
G01Y1612462D01*
G03X639868Y1612359I200J-1D01*
G02X640140Y1611378I-1640J-983D01*
G02X639868Y1610397I-1912J2D01*
G03X639840Y1610294I172J-102D01*
G01Y1609168D01*
G02X639638Y1608966I-202J0D01*
G01X636818D01*
G02X636616Y1609168I0J202D01*
G01Y1610294D01*
G03X636588Y1610397I-200J1D01*
G02X636316Y1611378I1640J983D01*
G02X636588Y1612359I1912J-2D01*
G03X636616Y1612462I-172J102D01*
G01Y1615412D01*
G03X636588Y1615515I-200J1D01*
G02X636316Y1616496I1640J983D01*
G02X636588Y1617477I1912J-2D01*
G03X636616Y1617580I-172J102D01*
G37*
G36*
G01X653938D02*
Y1618706D01*
G02X654141Y1618908I203J-1D01*
G01X656961D01*
G02X657164Y1618706I1J-202D01*
G01Y1617580D01*
G03X657192Y1617477I200J-1D01*
G02Y1615515I-1642J-981D01*
G03X657164Y1615412I172J-102D01*
G01Y1612462D01*
G03X657192Y1612359I200J-1D01*
G02Y1610397I-1642J-981D01*
G03X657164Y1610294I172J-102D01*
G01Y1609168D01*
G02X656961Y1608966I-203J1D01*
G01X654141D01*
G02X653938Y1609168I-1J202D01*
G01Y1610294D01*
G03X653910Y1610397I-200J1D01*
G02Y1612359I1642J981D01*
G03X653938Y1612462I-172J102D01*
G01Y1615412D01*
G03X653910Y1615515I-200J1D01*
G02Y1617477I1642J981D01*
G03X653938Y1617580I-172J102D01*
G37*
G36*
G01X671262D02*
Y1618706D01*
G02X671464Y1618908I202J0D01*
G01X674284D01*
G02X674486Y1618706I0J-202D01*
G01Y1617580D01*
G03X674514Y1617477I200J-1D01*
G02X674786Y1616496I-1640J-983D01*
G02X674514Y1615515I-1912J2D01*
G03X674486Y1615412I172J-102D01*
G01Y1612462D01*
G03X674514Y1612359I200J-1D01*
G02X674786Y1611378I-1640J-983D01*
G02X674514Y1610397I-1912J2D01*
G03X674486Y1610294I172J-102D01*
G01Y1609168D01*
G02X674284Y1608966I-202J0D01*
G01X671464D01*
G02X671262Y1609168I0J202D01*
G01Y1610294D01*
G03X671234Y1610397I-200J1D01*
G02X670962Y1611378I1640J983D01*
G02X671234Y1612359I1912J-2D01*
G03X671262Y1612462I-172J102D01*
G01Y1615412D01*
G03X671234Y1615515I-200J1D01*
G02X670962Y1616496I1640J983D01*
G02X671234Y1617477I1912J-2D01*
G03X671262Y1617580I-172J102D01*
G37*
G36*
G01X688584D02*
Y1618706D01*
G02X688787Y1618908I203J-1D01*
G01X691607D01*
G02X691810Y1618706I1J-202D01*
G01Y1617580D01*
G03X691838Y1617477I200J-1D01*
G02Y1615515I-1642J-981D01*
G03X691810Y1615412I172J-102D01*
G01Y1612462D01*
G03X691838Y1612359I200J-1D01*
G02Y1610397I-1642J-981D01*
G03X691810Y1610294I172J-102D01*
G01Y1609168D01*
G02X691607Y1608966I-203J1D01*
G01X688787D01*
G02X688584Y1609168I-1J202D01*
G01Y1610294D01*
G03X688556Y1610397I-200J1D01*
G02Y1612359I1642J981D01*
G03X688584Y1612462I-172J102D01*
G01Y1615412D01*
G03X688556Y1615515I-200J1D01*
G02Y1617477I1642J981D01*
G03X688584Y1617580I-172J102D01*
G37*
G36*
G01X1082871Y1528610D02*
G02X1082498Y1529600I1129J991D01*
G02X1085502I1502J0D01*
G02X1084563Y1528208I-1501J0D01*
G03X1084412Y1527573I150J-371D01*
G02X1084785Y1526583I-1129J-991D01*
G02X1081781I-1502J0D01*
G02X1082720Y1527975I1501J0D01*
G03X1082871Y1528610I-150J371D01*
G37*
G36*
G01X1092482Y1581529D02*
G02X1092180Y1582432I1200J903D01*
G01Y1582433D01*
G02X1095184I1502J0D01*
G02X1093970Y1580959I-1502J0D01*
G03X1093727Y1580326I76J-392D01*
G02X1094029Y1579423I-1200J-903D01*
G01Y1579422D01*
G02X1091025I-1502J0D01*
G02X1092239Y1580896I1502J0D01*
G03X1092482Y1581529I-76J392D01*
G37*
G36*
G01X748730Y1140378D02*
X748721Y1140427D01*
G02X748700Y1140649I1181J224D01*
G02X749902Y1139447I1202J0D01*
G02X749679Y1139468I1J1202D01*
G01X749631Y1139477D01*
X749536Y1139448D01*
X749232Y1139144D01*
X749203Y1139050D01*
X749212Y1139001D01*
G02X749233Y1138779I-1181J-224D01*
G02X746829I-1202J0D01*
G02X746850Y1139001I1202J-2D01*
G01X746859Y1139050D01*
X746830Y1139143D01*
X746525Y1139448D01*
X746432Y1139477D01*
X746383Y1139468D01*
G02X746161Y1139447I-224J1181D01*
G02X747363Y1140649I0J1202D01*
G02X747342Y1140427I-1202J2D01*
G01X747333Y1140378D01*
X747362Y1140285D01*
X747667Y1139980D01*
X747760Y1139951D01*
X747809Y1139960D01*
G02X748031Y1139981I224J-1181D01*
G02X748254Y1139960I-1J-1202D01*
G01X748302Y1139951D01*
X748397Y1139980D01*
X748701Y1140284D01*
X748730Y1140378D01*
G37*
G36*
G01X824902Y1148843D02*
G02X824242Y1150087I842J1244D01*
G02X827246I1502J0D01*
G02X826586Y1148843I-1502J0D01*
G03Y1148181I224J-331D01*
G02X827246Y1146937I-842J-1244D01*
G02X824242I-1502J0D01*
G02X824902Y1148181I1502J0D01*
G03Y1148843I-224J331D01*
G37*
G36*
G01X809723Y1158669D02*
G02X809623Y1158666I-95J1499D01*
G02X811125Y1160168I0J1502D01*
G02X811011Y1159594I-1502J0D01*
G03X811407Y1159043I370J-152D01*
G02X811507Y1159046I95J-1499D01*
G02X810005Y1157544I0J-1502D01*
G02X810119Y1158118I1502J0D01*
G03X809723Y1158669I-370J152D01*
G37*
G36*
G01X907953Y1095002D02*
Y1095316D01*
G03X907876Y1095474I-200J0D01*
G02X907297Y1096659I923J1185D01*
G02X910301I1502J0D01*
G02X909722Y1095474I-1502J0D01*
G03X909645Y1095316I123J-158D01*
G01Y1095002D01*
G03X909722Y1094844I200J0D01*
G02X910301Y1093659I-923J-1185D01*
G02X907297I-1502J0D01*
G02X907876Y1094844I1502J0D01*
G03X907953Y1095002I-123J158D01*
G37*
G36*
G01X868022Y1146578D02*
G02Y1149582I0J1502D01*
G02X869009Y1149212I0J-1501D01*
G01X869010D01*
Y1149211D01*
G03X869140Y1149163I130J152D01*
G01X869404D01*
G03X869534Y1149211I0J200D01*
G01X869535Y1149212D01*
G02X870522Y1149582I987J-1131D01*
G02Y1146578I0J-1502D01*
G02X869535Y1146948I0J1501D01*
G01X869534D01*
Y1146949D01*
G03X869404Y1146997I-130J-152D01*
G01X869140D01*
G03X869010Y1146949I0J-200D01*
G01X869009Y1146948D01*
G02X868022Y1146578I-987J1131D01*
G37*
G36*
G01X890375Y1264190D02*
X890376Y1264189D01*
G03X890506Y1264141I130J152D01*
G01X890770D01*
G03X890900Y1264189I0J200D01*
G01X890901Y1264190D01*
G02X891888Y1264560I987J-1131D01*
G02X893390Y1263058I0J-1502D01*
G02X893020Y1262071I-1501J0D01*
G01Y1262070D01*
X893019D01*
G03X892971Y1261940I152J-130D01*
G01Y1261676D01*
G03X893019Y1261546I200J0D01*
G01X893020Y1261545D01*
G02X893390Y1260558I-1131J-987D01*
G02X891888Y1259056I-1502J0D01*
G02X890901Y1259426I0J1501D01*
G01X890900D01*
Y1259427D01*
G03X890770Y1259475I-130J-152D01*
G01X890506D01*
G03X890376Y1259427I0J-200D01*
G01X890375Y1259426D01*
G02X888401I-987J1131D01*
G01X888400D01*
Y1259427D01*
G03X888270Y1259475I-130J-152D01*
G01X888006D01*
G03X887876Y1259427I0J-200D01*
G01X887875Y1259426D01*
G02X886888Y1259056I-987J1131D01*
G02X885386Y1260558I0J1502D01*
G02X885756Y1261545I1501J0D01*
G01Y1261546D01*
X885757D01*
G03X885805Y1261676I-152J130D01*
G01Y1261940D01*
G03X885757Y1262070I-200J0D01*
G01X885756Y1262071D01*
G02X885386Y1263058I1131J987D01*
G02X886888Y1264560I1502J0D01*
G02X887875Y1264190I0J-1501D01*
G01X887876D01*
Y1264189D01*
G03X888006Y1264141I130J152D01*
G01X888270D01*
G03X888400Y1264189I0J200D01*
G01X888401Y1264190D01*
G02X890375I987J-1131D01*
G37*
G36*
G01X909508Y623418D02*
X912908D01*
G02Y619814I0J-1802D01*
G01X909508D01*
G02Y623418I0J1802D01*
G37*
G36*
G01X900676Y623338D02*
X904076D01*
G02Y619734I0J-1802D01*
G01X900676D01*
G02Y623338I0J1802D01*
G37*
G36*
G01X900245Y403492D02*
G02X903249I1502J0D01*
G02X902879Y402505I-1501J0D01*
G01Y402504D01*
X902878D01*
G03X902830Y402374I152J-130D01*
G01Y402110D01*
G03X902878Y401980I200J0D01*
G01X902879Y401979D01*
G02Y400005I-1131J-987D01*
G01Y400004D01*
X902878D01*
G03X902830Y399874I152J-130D01*
G01Y399610D01*
G03X902878Y399480I200J0D01*
G01X902879Y399479D01*
G02X903249Y398492I-1131J-987D01*
G02X900245I-1502J0D01*
G02X900615Y399479I1501J0D01*
G01Y399480D01*
X900616D01*
G03X900664Y399610I-152J130D01*
G01Y399874D01*
G03X900616Y400004I-200J0D01*
G01X900615Y400005D01*
G02Y401979I1131J987D01*
G01Y401980D01*
X900616D01*
G03X900664Y402110I-152J130D01*
G01Y402374D01*
G03X900616Y402504I-200J0D01*
G01X900615Y402505D01*
G02X900245Y403492I1131J987D01*
G37*
G36*
G01X912821Y403551D02*
G02X915825I1502J0D01*
G02X915455Y402564I-1501J0D01*
G01Y402563D01*
X915454D01*
G03X915406Y402433I152J-130D01*
G01Y402169D01*
G03X915454Y402039I200J0D01*
G01X915455Y402038D01*
G02Y400064I-1131J-987D01*
G01Y400063D01*
X915454D01*
G03X915406Y399933I152J-130D01*
G01Y399669D01*
G03X915454Y399539I200J0D01*
G01X915455Y399538D01*
G02X915825Y398551I-1131J-987D01*
G02X912821I-1502J0D01*
G02X913191Y399538I1501J0D01*
G01Y399539D01*
X913192D01*
G03X913240Y399669I-152J130D01*
G01Y399933D01*
G03X913192Y400063I-200J0D01*
G01X913191Y400064D01*
G02Y402038I1131J987D01*
G01Y402039D01*
X913192D01*
G03X913240Y402169I-152J130D01*
G01Y402433D01*
G03X913192Y402563I-200J0D01*
G01X913191Y402564D01*
G02X912821Y403551I1131J987D01*
G37*
G36*
G01X895326Y403091D02*
X895032D01*
G03X894885Y403026I1J-200D01*
G02X893779Y402541I-1106J1019D01*
G02Y405545I0J1502D01*
G02X894885Y405060I0J-1504D01*
G03X895032Y404995I148J135D01*
G01X895326D01*
G03X895473Y405060I-1J200D01*
G02X896579Y405545I1106J-1019D01*
G02Y402541I0J-1502D01*
G02X895473Y403026I0J1504D01*
G03X895326Y403091I-148J-135D01*
G37*
G36*
G01X885764Y405158D02*
G02X887266Y406660I1502J0D01*
G02X888121Y406393I0J-1502D01*
G01X888155Y406370D01*
X888236Y406353D01*
X888603Y406433D01*
X888670Y406481D01*
X888691Y406516D01*
G02X889979Y407245I1288J-773D01*
G02Y404241I0J-1502D01*
G02X889124Y404508I0J1502D01*
G01X889090Y404531D01*
X889009Y404548D01*
X888642Y404468D01*
X888575Y404420D01*
X888554Y404385D01*
G02X888398Y404172I-1285J777D01*
G03X888397Y404170I173J-88D01*
G03X888349Y404040I152J-130D01*
G01Y403776D01*
G03X888397Y403646I200J0D01*
G01X888398Y403645D01*
G02Y401671I-1131J-987D01*
G01Y401670D01*
X888397D01*
G03X888349Y401540I152J-130D01*
G01Y401276D01*
G03X888397Y401146I200J0D01*
G01X888398Y401145D01*
G02X888768Y400158I-1131J-987D01*
G02X885764I-1502J0D01*
G02X886134Y401145I1501J0D01*
G01Y401146D01*
X886135D01*
G03X886183Y401276I-152J130D01*
G01Y401540D01*
G03X886135Y401670I-200J0D01*
G01X886134Y401671D01*
G02Y403645I1131J987D01*
G01Y403646D01*
X886135D01*
G03X886183Y403776I-152J130D01*
G01Y404040D01*
G03X886135Y404170I-200J0D01*
G01X886134Y404171D01*
G02X885764Y405158I1131J987D01*
G37*
G36*
G01X878690Y410117D02*
G02Y413121I0J1502D01*
G02X879677Y412751I0J-1501D01*
G01X879678D01*
Y412750D01*
G03X879808Y412702I130J152D01*
G01X880072D01*
G03X880202Y412750I0J200D01*
G01X880203Y412751D01*
G02X881190Y413121I987J-1131D01*
G02Y410117I0J-1502D01*
G02X880203Y410487I0J1501D01*
G01X880202D01*
Y410488D01*
G03X880072Y410536I-130J-152D01*
G01X879808D01*
G03X879678Y410488I0J-200D01*
G01X879677Y410487D01*
G02X878690Y410117I-987J1131D01*
G37*
G36*
G01X876917Y413820D02*
G02Y416824I0J1502D01*
G02X877904Y416454I0J-1501D01*
G01X877905D01*
Y416453D01*
G03X878035Y416405I130J152D01*
G01X878299D01*
G03X878429Y416453I0J200D01*
G01X878430Y416454D01*
G02X879417Y416824I987J-1131D01*
G02Y413820I0J-1502D01*
G02X878430Y414190I0J1501D01*
G01X878429D01*
Y414191D01*
G03X878299Y414239I-130J-152D01*
G01X878035D01*
G03X877905Y414191I0J-200D01*
G01X877904Y414190D01*
G02X876917Y413820I-987J1131D01*
G37*
G36*
G01X923216Y425397D02*
X923510D01*
G03X923657Y425462I-1J200D01*
G02X925869I1106J-1017D01*
G03X926016Y425397I148J135D01*
G01X926310D01*
G03X926457Y425462I-1J200D01*
G02X927563Y425947I1106J-1019D01*
G02Y422943I0J-1502D01*
G02X926457Y423428I0J1504D01*
G03X926310Y423493I-148J-135D01*
G01X926016D01*
G03X925869Y423428I1J-200D01*
G02X923657I-1106J1017D01*
G03X923510Y423493I-148J-135D01*
G01X923216D01*
G03X923069Y423428I1J-200D01*
G02X921963Y422943I-1106J1019D01*
G02Y425947I0J1502D01*
G02X923069Y425462I0J-1504D01*
G03X923216Y425397I148J135D01*
G37*
G36*
G01X879758Y428084D02*
X879759Y428083D01*
G03X879889Y428035I130J152D01*
G01X880153D01*
G03X880283Y428083I0J200D01*
G01X880284Y428084D01*
G02X881271Y428454I987J-1131D01*
G02Y425450I0J-1502D01*
G02X880284Y425820I0J1501D01*
G01X880283D01*
Y425821D01*
G03X880153Y425869I-130J-152D01*
G01X879889D01*
G03X879759Y425821I0J-200D01*
G01X879758Y425820D01*
G02X877784I-987J1131D01*
G01X877783D01*
Y425821D01*
G03X877653Y425869I-130J-152D01*
G01X877389D01*
G03X877259Y425821I0J-200D01*
G01X877258Y425820D01*
G02X875284I-987J1131D01*
G01X875283D01*
Y425821D01*
G03X875153Y425869I-130J-152D01*
G01X874889D01*
G03X874759Y425821I0J-200D01*
G01X874758Y425820D01*
G02X873771Y425450I-987J1131D01*
G02Y428454I0J1502D01*
G02X874758Y428084I0J-1501D01*
G01X874759D01*
Y428083D01*
G03X874889Y428035I130J152D01*
G01X875153D01*
G03X875283Y428083I0J200D01*
G01X875284Y428084D01*
G02X877258I987J-1131D01*
G01X877259D01*
Y428083D01*
G03X877389Y428035I130J152D01*
G01X877653D01*
G03X877783Y428083I0J200D01*
G01X877784Y428084D01*
G02X879758I987J-1131D01*
G37*
G36*
G01X922933Y437668D02*
X923227D01*
G03X923374Y437733I-1J200D01*
G02X925586I1106J-1017D01*
G03X925733Y437668I148J135D01*
G01X926027D01*
G03X926174Y437733I-1J200D01*
G02X927280Y438218I1106J-1019D01*
G02Y435214I0J-1502D01*
G02X926174Y435699I0J1504D01*
G03X926027Y435764I-148J-135D01*
G01X925733D01*
G03X925586Y435699I1J-200D01*
G02X923374I-1106J1017D01*
G03X923227Y435764I-148J-135D01*
G01X922933D01*
G03X922786Y435699I1J-200D01*
G02X921680Y435214I-1106J1019D01*
G02Y438218I0J1502D01*
G02X922786Y437733I0J-1504D01*
G03X922933Y437668I148J135D01*
G37*
G36*
G01X879523Y438540D02*
X879524Y438539D01*
G03X879654Y438491I130J152D01*
G01X879918D01*
G03X880048Y438539I0J200D01*
G01X880049Y438540D01*
G02X881036Y438910I987J-1131D01*
G02Y435906I0J-1502D01*
G02X880049Y436276I0J1501D01*
G01X880048D01*
Y436277D01*
G03X879918Y436325I-130J-152D01*
G01X879654D01*
G03X879524Y436277I0J-200D01*
G01X879523Y436276D01*
G02X877549I-987J1131D01*
G01X877548D01*
Y436277D01*
G03X877418Y436325I-130J-152D01*
G01X877154D01*
G03X877024Y436277I0J-200D01*
G01X877023Y436276D01*
G02X875049I-987J1131D01*
G01X875048D01*
Y436277D01*
G03X874918Y436325I-130J-152D01*
G01X874654D01*
G03X874524Y436277I0J-200D01*
G01X874523Y436276D01*
G02X873536Y435906I-987J1131D01*
G02Y438910I0J1502D01*
G02X874523Y438540I0J-1501D01*
G01X874524D01*
Y438539D01*
G03X874654Y438491I130J152D01*
G01X874918D01*
G03X875048Y438539I0J200D01*
G01X875049Y438540D01*
G02X877023I987J-1131D01*
G01X877024D01*
Y438539D01*
G03X877154Y438491I130J152D01*
G01X877418D01*
G03X877548Y438539I0J200D01*
G01X877549Y438540D01*
G02X879523I987J-1131D01*
G37*
G36*
G01X916039Y443780D02*
G02X919043I1502J0D01*
G02X918673Y442793I-1501J0D01*
G01Y442792D01*
X918672D01*
G03X918624Y442662I152J-130D01*
G01Y442398D01*
G03X918672Y442268I200J0D01*
G01X918673Y442267D01*
G02X919043Y441280I-1131J-987D01*
G02X916039I-1502J0D01*
G02X916409Y442267I1501J0D01*
G01Y442268D01*
X916410D01*
G03X916458Y442398I-152J130D01*
G01Y442662D01*
G03X916410Y442792I-200J0D01*
G01X916409Y442793D01*
G02X916039Y443780I1131J987D01*
G37*
G36*
G01X906498Y458515D02*
Y458809D01*
G03X906433Y458956I-200J-1D01*
G02X905948Y460062I1019J1106D01*
G02X907450Y461564I1502J0D01*
G02X908556Y461079I0J-1504D01*
G03X908703Y461014I148J135D01*
G01X908997D01*
G03X909144Y461079I-1J200D01*
G02X910250Y461564I1106J-1019D01*
G02X911752Y460062I0J-1502D01*
G02X911267Y458956I-1504J0D01*
G03X911202Y458809I135J-148D01*
G01Y458515D01*
G03X911267Y458368I200J1D01*
G02Y456156I-1017J-1106D01*
G03X911202Y456009I135J-148D01*
G01Y455715D01*
G03X911267Y455568I200J1D01*
G02Y453356I-1017J-1106D01*
G03X911202Y453209I135J-148D01*
G01Y452915D01*
G03X911267Y452768I200J1D01*
G02X911752Y451662I-1019J-1106D01*
G02X910250Y450160I-1502J0D01*
G02X909144Y450645I0J1504D01*
G03X908997Y450710I-148J-135D01*
G01X908703D01*
G03X908556Y450645I1J-200D01*
G02X907450Y450160I-1106J1019D01*
G02X905948Y451662I0J1502D01*
G02X906433Y452768I1504J0D01*
G03X906498Y452915I-135J148D01*
G01Y453209D01*
G03X906433Y453356I-200J-1D01*
G02Y455568I1017J1106D01*
G03X906498Y455715I-135J148D01*
G01Y456009D01*
G03X906433Y456156I-200J-1D01*
G02Y458368I1017J1106D01*
G03X906498Y458515I-135J148D01*
G37*
G36*
G01X879958Y458687D02*
Y458981D01*
G03X879893Y459128I-200J-1D01*
G02X879408Y460234I1019J1106D01*
G02X882412I1502J0D01*
G02X881927Y459128I-1504J0D01*
G03X881862Y458981I135J-148D01*
G01Y458687D01*
G03X881927Y458540I200J1D01*
G02Y456328I-1017J-1106D01*
G03X881862Y456181I135J-148D01*
G01Y455887D01*
G03X881927Y455740I200J1D01*
G02X882412Y454634I-1019J-1106D01*
G02X879408I-1502J0D01*
G02X879893Y455740I1504J0D01*
G03X879958Y455887I-135J148D01*
G01Y456181D01*
G03X879893Y456328I-200J-1D01*
G02Y458540I1017J1106D01*
G03X879958Y458687I-135J148D01*
G37*
G36*
G01X889951D02*
Y458981D01*
G03X889886Y459128I-200J-1D01*
G02X889401Y460234I1019J1106D01*
G02X892405I1502J0D01*
G02X891920Y459128I-1504J0D01*
G03X891855Y458981I135J-148D01*
G01Y458687D01*
G03X891920Y458540I200J1D01*
G02Y456328I-1017J-1106D01*
G03X891855Y456181I135J-148D01*
G01Y455887D01*
G03X891920Y455740I200J1D01*
G02X892405Y454634I-1019J-1106D01*
G02X889401I-1502J0D01*
G02X889886Y455740I1504J0D01*
G03X889951Y455887I-135J148D01*
G01Y456181D01*
G03X889886Y456328I-200J-1D01*
G02Y458540I1017J1106D01*
G03X889951Y458687I-135J148D01*
G37*
G36*
G01X983801Y464652D02*
G02X985303Y466154I1502J0D01*
G02X986290Y465784I0J-1501D01*
G01X986291D01*
Y465783D01*
G03X986421Y465735I130J152D01*
G01X986685D01*
G03X986815Y465783I0J200D01*
G01X986816Y465784D01*
G02X987803Y466154I987J-1131D01*
G02X989305Y464652I0J-1502D01*
G02X988935Y463665I-1501J0D01*
G01Y463664D01*
X988934D01*
G03X988886Y463534I152J-130D01*
G01Y463270D01*
G03X988934Y463140I200J0D01*
G01X988935Y463139D01*
G02Y461165I-1131J-987D01*
G01Y461164D01*
X988934D01*
G03X988886Y461034I152J-130D01*
G01Y460770D01*
G03X988934Y460640I200J0D01*
G01X988935Y460639D01*
G02X989305Y459652I-1131J-987D01*
G02X987803Y458150I-1502J0D01*
G02X986816Y458520I0J1501D01*
G01X986815D01*
Y458521D01*
G03X986685Y458569I-130J-152D01*
G01X986421D01*
G03X986291Y458521I0J-200D01*
G01X986290Y458520D01*
G02X985303Y458150I-987J1131D01*
G02X983801Y459652I0J1502D01*
G02X984171Y460639I1501J0D01*
G01Y460640D01*
X984172D01*
G03X984220Y460770I-152J130D01*
G01Y461034D01*
G03X984172Y461164I-200J0D01*
G01X984171Y461165D01*
G02Y463139I1131J987D01*
G01Y463140D01*
X984172D01*
G03X984220Y463270I-152J130D01*
G01Y463534D01*
G03X984172Y463664I-200J0D01*
G01X984171Y463665D01*
G02X983801Y464652I1131J987D01*
G37*
G36*
G01X968345Y477078D02*
Y477372D01*
G03X968280Y477519I-200J-1D01*
G02X967795Y478625I1019J1106D01*
G02X970799I1502J0D01*
G02X970314Y477519I-1504J0D01*
G03X970249Y477372I135J-148D01*
G01Y477078D01*
G03X970314Y476931I200J1D01*
G02X970799Y475825I-1019J-1106D01*
G02X967795I-1502J0D01*
G02X968280Y476931I1504J0D01*
G03X968345Y477078I-135J148D01*
G37*
G36*
G01X968899Y486270D02*
X968900Y486269D01*
G03X969030Y486221I130J152D01*
G01X969294D01*
G03X969424Y486269I0J200D01*
G01X969425Y486270D01*
G02X970412Y486640I987J-1131D01*
G02X971914Y485138I0J-1502D01*
G02X971647Y484283I-1502J0D01*
G01X971624Y484249D01*
X971607Y484168D01*
X971687Y483801D01*
X971735Y483734D01*
X971770Y483713D01*
G02X972499Y482425I-773J-1288D01*
G02X969495I-1502J0D01*
G02X969762Y483280I1502J0D01*
G01X969785Y483314D01*
X969802Y483395D01*
X969722Y483762D01*
X969674Y483829D01*
X969639Y483850D01*
G02X969426Y484006I777J1285D01*
G03X969424Y484007I-88J-173D01*
G03X969294Y484055I-130J-152D01*
G01X969030D01*
G03X968900Y484007I0J-200D01*
G01X968899Y484006D01*
G02X966925I-987J1131D01*
G01X966924D01*
Y484007D01*
G03X966794Y484055I-130J-152D01*
G01X966530D01*
G03X966400Y484007I0J-200D01*
G01X966399Y484006D01*
G02X965412Y483636I-987J1131D01*
G02X964291Y484139I0J1501D01*
G01X964262Y484172D01*
X964185Y484206D01*
X963840Y484204D01*
G03X963692Y484138I0J-200D01*
G01X963691Y484137D01*
G02X962563Y483626I-1129J991D01*
G02Y486630I0J1502D01*
G02X963684Y486127I0J-1501D01*
G01X963713Y486094D01*
X963790Y486060D01*
X964135Y486062D01*
G03X964283Y486128I0J200D01*
G01X964284Y486129D01*
G02X965412Y486640I1129J-991D01*
G02X966399Y486270I0J-1501D01*
G01X966400D01*
Y486269D01*
G03X966530Y486221I130J152D01*
G01X966794D01*
G03X966924Y486269I0J200D01*
G01X966925Y486270D01*
G02X968899I987J-1131D01*
G37*
G36*
G01X975371Y493714D02*
G02X978375I1502J0D01*
G02X978005Y492727I-1501J0D01*
G01Y492726D01*
X978004D01*
G03X977956Y492596I152J-130D01*
G01Y492332D01*
G03X978004Y492202I200J0D01*
G01X978005Y492201D01*
G02X978375Y491214I-1131J-987D01*
G02X975371I-1502J0D01*
G02X975741Y492201I1501J0D01*
G01Y492202D01*
X975742D01*
G03X975790Y492332I-152J130D01*
G01Y492596D01*
G03X975742Y492726I-200J0D01*
G01X975741Y492727D01*
G02X975371Y493714I1131J987D01*
G37*
G36*
G01X979074Y495487D02*
G02X982078I1502J0D01*
G02X981708Y494500I-1501J0D01*
G01Y494499D01*
X981707D01*
G03X981659Y494369I152J-130D01*
G01Y494105D01*
G03X981707Y493975I200J0D01*
G01X981708Y493974D01*
G02X982078Y492987I-1131J-987D01*
G02X979074I-1502J0D01*
G02X979444Y493974I1501J0D01*
G01Y493975D01*
X979445D01*
G03X979493Y494105I-152J130D01*
G01Y494369D01*
G03X979445Y494499I-200J0D01*
G01X979444Y494500D01*
G02X979074Y495487I1131J987D01*
G37*
G36*
G01X990704Y498633D02*
G02X993708I1502J0D01*
G02X993338Y497646I-1501J0D01*
G01Y497645D01*
X993337D01*
G03X993289Y497515I152J-130D01*
G01Y497251D01*
G03X993337Y497121I200J0D01*
G01X993338Y497120D01*
G02Y495146I-1131J-987D01*
G01Y495145D01*
X993337D01*
G03X993289Y495015I152J-130D01*
G01Y494751D01*
G03X993337Y494621I200J0D01*
G01X993338Y494620D01*
G02Y492646I-1131J-987D01*
G01Y492645D01*
X993337D01*
G03X993289Y492515I152J-130D01*
G01Y492251D01*
G03X993337Y492121I200J0D01*
G01X993338Y492120D01*
G02X993708Y491133I-1131J-987D01*
G02X990704I-1502J0D01*
G02X991074Y492120I1501J0D01*
G01Y492121D01*
X991075D01*
G03X991123Y492251I-152J130D01*
G01Y492515D01*
G03X991075Y492645I-200J0D01*
G01X991074Y492646D01*
G02Y494620I1131J987D01*
G01Y494621D01*
X991075D01*
G03X991123Y494751I-152J130D01*
G01Y495015D01*
G03X991075Y495145I-200J0D01*
G01X991074Y495146D01*
G02Y497120I1131J987D01*
G01Y497121D01*
X991075D01*
G03X991123Y497251I-152J130D01*
G01Y497515D01*
G03X991075Y497645I-200J0D01*
G01X991074Y497646D01*
G02X990704Y498633I1131J987D01*
G37*
G36*
G01X957402Y518533D02*
X957403Y518532D01*
G03X957533Y518484I130J152D01*
G01X957797D01*
G03X957927Y518532I0J200D01*
G01X957928Y518533D01*
G02X958915Y518903I987J-1131D01*
G02Y515899I0J-1502D01*
G02X957928Y516269I0J1501D01*
G01X957927D01*
Y516270D01*
G03X957797Y516318I-130J-152D01*
G01X957533D01*
G03X957403Y516270I0J-200D01*
G01X957402Y516269D01*
G02X955428I-987J1131D01*
G01X955427D01*
Y516270D01*
G03X955297Y516318I-130J-152D01*
G01X955033D01*
G03X954903Y516270I0J-200D01*
G01X954902Y516269D01*
G02X953915Y515899I-987J1131D01*
G02Y518903I0J1502D01*
G02X954902Y518533I0J-1501D01*
G01X954903D01*
Y518532D01*
G03X955033Y518484I130J152D01*
G01X955297D01*
G03X955427Y518532I0J200D01*
G01X955428Y518533D01*
G02X957402I987J-1131D01*
G37*
G36*
G01X958514Y523822D02*
Y524116D01*
G03X958449Y524263I-200J-1D01*
G02X957964Y525369I1019J1106D01*
G02X960968I1502J0D01*
G02X960483Y524263I-1504J0D01*
G03X960418Y524116I135J-148D01*
G01Y523822D01*
G03X960483Y523675I200J1D01*
G02X960968Y522569I-1019J-1106D01*
G02X957964I-1502J0D01*
G02X958449Y523675I1504J0D01*
G03X958514Y523822I-135J148D01*
G37*
G36*
G01X966090Y538911D02*
Y539205D01*
G03X966025Y539352I-200J-1D01*
G02X965540Y540458I1019J1106D01*
G02X968544I1502J0D01*
G02X968059Y539352I-1504J0D01*
G03X967994Y539205I135J-148D01*
G01Y538911D01*
G03X968059Y538764I200J1D01*
G02X968544Y537658I-1019J-1106D01*
G02X965540I-1502J0D01*
G02X966025Y538764I1504J0D01*
G03X966090Y538911I-135J148D01*
G37*
G36*
G01X969243Y542231D02*
G02X972247I1502J0D01*
G02X971877Y541244I-1501J0D01*
G01Y541243D01*
X971876D01*
G03X971828Y541113I152J-130D01*
G01Y540849D01*
G03X971876Y540719I200J0D01*
G01X971877Y540718D01*
G02X972247Y539731I-1131J-987D01*
G02X969243I-1502J0D01*
G02X969613Y540718I1501J0D01*
G01Y540719D01*
X969614D01*
G03X969662Y540849I-152J130D01*
G01Y541113D01*
G03X969614Y541243I-200J0D01*
G01X969613Y541244D01*
G02X969243Y542231I1131J987D01*
G37*
G36*
G01X988375Y549498D02*
X988376Y549497D01*
G03X988506Y549449I130J152D01*
G01X988770D01*
G03X988900Y549497I0J200D01*
G01X988901Y549498D01*
G02X989888Y549868I987J-1131D01*
G02Y546864I0J-1502D01*
G02X988901Y547234I0J1501D01*
G01X988900D01*
Y547235D01*
G03X988770Y547283I-130J-152D01*
G01X988506D01*
G03X988376Y547235I0J-200D01*
G01X988375Y547234D01*
G02X986401I-987J1131D01*
G01X986400D01*
Y547235D01*
G03X986270Y547283I-130J-152D01*
G01X986006D01*
G03X985876Y547235I0J-200D01*
G01X985875Y547234D01*
G02X983901I-987J1131D01*
G01X983900D01*
Y547235D01*
G03X983770Y547283I-130J-152D01*
G01X983506D01*
G03X983376Y547235I0J-200D01*
G01X983375Y547234D01*
G02X983312Y547182I-987J1132D01*
G03X983235Y547025I123J-158D01*
G01X983233Y546710D01*
G03X983308Y546554I200J0D01*
G01X983309Y546553D01*
G02X983877Y545377I-933J-1176D01*
G02X983507Y544390I-1501J0D01*
G01Y544389D01*
X983506D01*
G03X983458Y544259I152J-130D01*
G01Y543995D01*
G03X983506Y543865I200J0D01*
G01X983507Y543864D01*
G02Y541890I-1131J-987D01*
G01Y541889D01*
X983506D01*
G03X983458Y541759I152J-130D01*
G01Y541495D01*
G03X983506Y541365I200J0D01*
G01X983507Y541364D01*
G02Y539390I-1131J-987D01*
G01Y539389D01*
X983506D01*
G03X983458Y539259I152J-130D01*
G01Y538995D01*
G03X983506Y538865I200J0D01*
G01X983507Y538864D01*
G02X983877Y537877I-1131J-987D01*
G02X980873I-1502J0D01*
G02X981243Y538864I1501J0D01*
G01Y538865D01*
X981244D01*
G03X981292Y538995I-152J130D01*
G01Y539259D01*
G03X981244Y539389I-200J0D01*
G01X981243Y539390D01*
G02Y541364I1131J987D01*
G01Y541365D01*
X981244D01*
G03X981292Y541495I-152J130D01*
G01Y541759D01*
G03X981244Y541889I-200J0D01*
G01X981243Y541890D01*
G02Y543864I1131J987D01*
G01Y543865D01*
X981244D01*
G03X981292Y543995I-152J130D01*
G01Y544259D01*
G03X981244Y544389I-200J0D01*
G01X981243Y544390D01*
G02X980873Y545377I1131J987D01*
G02X981451Y546561I1502J0D01*
G03X981528Y546718I-123J158D01*
G01X981530Y547033D01*
G03X981455Y547189I-200J0D01*
G01X981454Y547190D01*
G02X980886Y548366I933J1176D01*
G02X982388Y549868I1502J0D01*
G02X983375Y549498I0J-1501D01*
G01X983376D01*
Y549497D01*
G03X983506Y549449I130J152D01*
G01X983770D01*
G03X983900Y549497I0J200D01*
G01X983901Y549498D01*
G02X985875I987J-1131D01*
G01X985876D01*
Y549497D01*
G03X986006Y549449I130J152D01*
G01X986270D01*
G03X986400Y549497I0J200D01*
G01X986401Y549498D01*
G02X988375I987J-1131D01*
G37*
G36*
G01X959563Y554242D02*
X959269D01*
G03X959122Y554177I1J-200D01*
G02X958016Y553692I-1106J1019D01*
G02Y556696I0J1502D01*
G02X959122Y556211I0J-1504D01*
G03X959269Y556146I148J135D01*
G01X959563D01*
G03X959710Y556211I-1J200D01*
G02X960816Y556696I1106J-1019D01*
G02Y553692I0J-1502D01*
G02X959710Y554177I0J1504D01*
G03X959563Y554242I-148J-135D01*
G37*
G36*
G01Y562242D02*
X959269D01*
G03X959122Y562177I1J-200D01*
G02X958016Y561692I-1106J1019D01*
G02Y564696I0J1502D01*
G02X959122Y564211I0J-1504D01*
G03X959269Y564146I148J135D01*
G01X959563D01*
G03X959710Y564211I-1J200D01*
G02X960816Y564696I1106J-1019D01*
G02Y561692I0J-1502D01*
G02X959710Y562177I0J1504D01*
G03X959563Y562242I-148J-135D01*
G37*
G36*
G01Y570242D02*
X959269D01*
G03X959122Y570177I1J-200D01*
G02X958016Y569692I-1106J1019D01*
G02Y572696I0J1502D01*
G02X959122Y572211I0J-1504D01*
G03X959269Y572146I148J135D01*
G01X959563D01*
G03X959710Y572211I-1J200D01*
G02X960816Y572696I1106J-1019D01*
G02Y569692I0J-1502D01*
G02X959710Y570177I0J1504D01*
G03X959563Y570242I-148J-135D01*
G37*
G36*
G01X919038Y577876D02*
G02Y580880I0J1502D01*
G02X920272Y580235I0J-1503D01*
G01X920292Y580205D01*
X920354Y580163D01*
X920650Y580093D01*
G03X920791Y580111I47J194D01*
G02X921507Y580293I717J-1320D01*
G02Y577289I0J-1502D01*
G02X920273Y577934I0J1503D01*
G01X920253Y577964D01*
X920191Y578006D01*
X919895Y578076D01*
G03X919754Y578058I-47J-194D01*
G02X919038Y577876I-717J1320D01*
G37*
G36*
G01X960826Y582174D02*
X961120D01*
G03X961267Y582239I-1J200D01*
G02X963479I1106J-1017D01*
G03X963626Y582174I148J135D01*
G01X963920D01*
G03X964067Y582239I-1J200D01*
G02X965173Y582724I1106J-1019D01*
G02Y579720I0J-1502D01*
G02X964067Y580205I0J1504D01*
G03X963920Y580270I-148J-135D01*
G01X963626D01*
G03X963479Y580205I1J-200D01*
G02X961267I-1106J1017D01*
G03X961120Y580270I-148J-135D01*
G01X960826D01*
G03X960679Y580205I1J-200D01*
G02X959573Y579720I-1106J1019D01*
G02Y582724I0J1502D01*
G02X960679Y582239I0J-1504D01*
G03X960826Y582174I148J135D01*
G37*
G36*
G01Y592167D02*
X961120D01*
G03X961267Y592232I-1J200D01*
G02X963479I1106J-1017D01*
G03X963626Y592167I148J135D01*
G01X963920D01*
G03X964067Y592232I-1J200D01*
G02X965173Y592717I1106J-1019D01*
G02Y589713I0J-1502D01*
G02X964067Y590198I0J1504D01*
G03X963920Y590263I-148J-135D01*
G01X963626D01*
G03X963479Y590198I1J-200D01*
G02X961267I-1106J1017D01*
G03X961120Y590263I-148J-135D01*
G01X960826D01*
G03X960679Y590198I1J-200D01*
G02X959573Y589713I-1106J1019D01*
G02Y592717I0J1502D01*
G02X960679Y592232I0J-1504D01*
G03X960826Y592167I148J135D01*
G37*
G36*
G01X897984Y605797D02*
X895568Y608213D01*
G03X895488Y608262I-142J-141D01*
G01X895487D01*
G02X894431Y609696I446J1434D01*
G02X895933Y611198I1502J0D01*
G02X897367Y610143I0J-1502D01*
G01Y610141D01*
G03X897416Y610061I190J62D01*
G01X899390Y608087D01*
G03X899532Y608028I142J141D01*
G01X909763D01*
G02X910687Y607645I0J-1306D01*
G01X914922Y603410D01*
G02X915304Y602488I-924J-923D01*
G01Y598610D01*
G03X915504Y598410I200J0D01*
G01X916670D01*
G02X917594Y598027I0J-1306D01*
G01X922141Y593480D01*
G02X922524Y592556I-923J-924D01*
G01Y590006D01*
G03X922545Y589917I200J0D01*
G01X922546Y589915D01*
G02X922719Y589216I-1329J-700D01*
G02X921217Y587714I-1502J0D01*
G01X921216D01*
G02X921012Y587728I1J1502D01*
G01X921011D01*
G03X920866Y587691I-27J-198D01*
G01X920609Y587502D01*
X920568Y587436D01*
X920562Y587397D01*
G02X919080Y586138I-1482J243D01*
G02Y589142I0J1502D01*
G01X919081D01*
G02X919285Y589128I-1J-1502D01*
G01X919286D01*
G03X919431Y589165I27J198D01*
G01X919688Y589354D01*
X919729Y589420D01*
X919735Y589459D01*
G02X919887Y589913I1482J-244D01*
G03X919889Y589917I-178J91D01*
G01X919900Y589938D01*
X919910Y589982D01*
Y591932D01*
G03X919851Y592074I-200J0D01*
G01X916188Y595737D01*
G03X916046Y595796I-142J-141D01*
G01X914788D01*
G03X914699Y595775I0J-200D01*
G01X914697Y595774D01*
G02X913998Y595601I-700J1329D01*
G02X912496Y597103I0J1502D01*
G02X912669Y597802I1502J-1D01*
G03X912692Y597895I-177J93D01*
G01Y601862D01*
G03X912633Y602004I-200J0D01*
G01X909281Y605355D01*
G03X909139Y605414I-142J-141D01*
G01X898908D01*
G02X897984Y605797I0J1306D01*
G37*
G36*
G01X963798Y611514D02*
X964092D01*
G03X964239Y611579I-1J200D01*
G02X966451I1106J-1017D01*
G03X966598Y611514I148J135D01*
G01X966892D01*
G03X967039Y611579I-1J200D01*
G02X968145Y612064I1106J-1019D01*
G02X969647Y610562I0J-1502D01*
G02X969162Y609456I-1504J0D01*
G03X969097Y609309I135J-148D01*
G01Y609015D01*
G03X969162Y608868I200J1D01*
G02X969647Y607762I-1019J-1106D01*
G02X968145Y606260I-1502J0D01*
G02X967039Y606745I0J1504D01*
G03X966892Y606810I-148J-135D01*
G01X966598D01*
G03X966451Y606745I1J-200D01*
G02X964239I-1106J1017D01*
G03X964092Y606810I-148J-135D01*
G01X963798D01*
G03X963651Y606745I1J-200D01*
G02X961439I-1106J1017D01*
G03X961292Y606810I-148J-135D01*
G01X960998D01*
G03X960851Y606745I1J-200D01*
G02X959745Y606260I-1106J1019D01*
G02X958243Y607762I0J1502D01*
G02X958728Y608868I1504J0D01*
G03X958793Y609015I-135J148D01*
G01Y609309D01*
G03X958728Y609456I-200J-1D01*
G02X958243Y610562I1019J1106D01*
G02X959745Y612064I1502J0D01*
G02X960851Y611579I0J-1504D01*
G03X960998Y611514I148J135D01*
G01X961292D01*
G03X961439Y611579I-1J200D01*
G02X963651I1106J-1017D01*
G03X963798Y611514I148J135D01*
G37*
G36*
G01X982891Y617966D02*
Y618260D01*
G03X982826Y618407I-200J-1D01*
G02X982341Y619513I1019J1106D01*
G02X985345I1502J0D01*
G02X984860Y618407I-1504J0D01*
G03X984795Y618260I135J-148D01*
G01Y617966D01*
G03X984860Y617819I200J1D01*
G02Y615607I-1017J-1106D01*
G03X984795Y615460I135J-148D01*
G01Y615166D01*
G03X984860Y615019I200J1D01*
G02X985345Y613913I-1019J-1106D01*
G02X982341I-1502J0D01*
G02X982826Y615019I1504J0D01*
G03X982891Y615166I-135J148D01*
G01Y615460D01*
G03X982826Y615607I-200J-1D01*
G02Y617819I1017J1106D01*
G03X982891Y617966I-135J148D01*
G37*
G36*
G01X994961Y618211D02*
Y618505D01*
G03X994896Y618652I-200J-1D01*
G02X994411Y619758I1019J1106D01*
G02X997415I1502J0D01*
G02X996930Y618652I-1504J0D01*
G03X996865Y618505I135J-148D01*
G01Y618211D01*
G03X996930Y618064I200J1D01*
G02Y615852I-1017J-1106D01*
G03X996865Y615705I135J-148D01*
G01Y615411D01*
G03X996930Y615264I200J1D01*
G02X997415Y614158I-1019J-1106D01*
G02X994411I-1502J0D01*
G02X994896Y615264I1504J0D01*
G03X994961Y615411I-135J148D01*
G01Y615705D01*
G03X994896Y615852I-200J-1D01*
G02Y618064I1017J1106D01*
G03X994961Y618211I-135J148D01*
G37*
G36*
G01X975075Y619106D02*
Y619400D01*
G03X975010Y619547I-200J-1D01*
G02X974525Y620653I1019J1106D01*
G02X977529I1502J0D01*
G02X977044Y619547I-1504J0D01*
G03X976979Y619400I135J-148D01*
G01Y619106D01*
G03X977044Y618959I200J1D01*
G02X977529Y617853I-1019J-1106D01*
G02X974525I-1502J0D01*
G02X975010Y618959I1504J0D01*
G03X975075Y619106I-135J148D01*
G37*
G36*
G01X915800Y628198D02*
G02Y631202I0J1502D01*
G02X916787Y630832I0J-1501D01*
G01X916788D01*
Y630831D01*
G03X916918Y630783I130J152D01*
G01X917182D01*
G03X917312Y630831I0J200D01*
G01X917313Y630832D01*
G02X918300Y631202I987J-1131D01*
G02Y628198I0J-1502D01*
G02X917313Y628568I0J1501D01*
G01X917312D01*
Y628569D01*
G03X917182Y628617I-130J-152D01*
G01X916918D01*
G03X916788Y628569I0J-200D01*
G01X916787Y628568D01*
G02X915800Y628198I-987J1131D01*
G37*
G36*
G01X857325Y419896D02*
G02X858827Y421398I1502J0D01*
G02X860006Y420827I0J-1503D01*
G01X860032Y420794D01*
X860106Y420755D01*
X860485Y420726D01*
X860563Y420754D01*
X860594Y420783D01*
G02X861622Y421190I1028J-1095D01*
G02X863124Y419688I0J-1502D01*
G02X862623Y418568I-1502J0D01*
G01X862594Y418543D01*
X862560Y418473D01*
X862535Y418159D01*
G03X862579Y418018I199J-15D01*
G02X862915Y417071I-1167J-947D01*
G02X861413Y415569I-1502J0D01*
G02X860522Y415862I0J1501D01*
G01X860521D01*
X860490Y415885D01*
X860414Y415904D01*
X860058Y415852D01*
X859989Y415811D01*
X859966Y415780D01*
G02X859627Y415454I-1198J906D01*
G03X859543Y415315I114J-164D01*
G01X859500Y414979D01*
X859524Y414898D01*
X859552Y414866D01*
G02X859912Y413890I-1143J-976D01*
G02X856908I-1502J0D01*
G02X857550Y415121I1501J0D01*
G03X857634Y415260I-114J164D01*
G01X857677Y415596D01*
X857653Y415677D01*
X857625Y415709D01*
G02X857265Y416685I1143J976D01*
G02X857986Y417968I1502J0D01*
G01X858030Y417995D01*
X858081Y418083D01*
X858089Y418525D01*
X858042Y418615D01*
X857999Y418643D01*
G02X857325Y419896I828J1253D01*
G37*
G36*
G01X875596Y423726D02*
X875910D01*
G03X876068Y423803I0J200D01*
G02X877253Y424382I1185J-923D01*
G02X878755Y422880I0J-1502D01*
G02X878385Y421893I-1501J0D01*
G01Y421892D01*
X878384D01*
G03X878336Y421762I152J-130D01*
G01Y421498D01*
G03X878384Y421368I200J0D01*
G01X878385Y421367D01*
G02X878755Y420380I-1131J-987D01*
G02X877253Y418878I-1502J0D01*
G02X876160Y419350I0J1502D01*
G01X876159Y419351D01*
G03X875994Y419412I-145J-138D01*
G01X875679Y419381D01*
G03X875529Y419287I20J-199D01*
G02X874253Y418578I-1276J794D01*
G02X872751Y420080I0J1502D01*
G02X873236Y421186I1504J0D01*
G03X873301Y421333I-135J148D01*
G01Y421627D01*
G03X873236Y421774I-200J-1D01*
G02X872751Y422880I1019J1106D01*
G02X874253Y424382I1502J0D01*
G02X875438Y423803I0J-1502D01*
G03X875596Y423726I158J123D01*
G37*
G36*
G01X918620Y449600D02*
G02X917549Y449038I-1071J739D01*
G02Y451642I0J1302D01*
G02X918620Y451080I0J-1301D01*
G03X919278I329J228D01*
G02X920349Y451642I1071J-739D01*
G02Y449038I0J-1302D01*
G02X919278Y449600I0J1301D01*
G03X918620I-329J-228D01*
G37*
G36*
G01Y453144D02*
G02X917549Y452582I-1071J739D01*
G02Y455186I0J1302D01*
G02X918620Y454624I0J-1301D01*
G03X919278I329J228D01*
G02X920349Y455186I1071J-739D01*
G02Y452582I0J-1302D01*
G02X919278Y453144I0J1301D01*
G03X918620I-329J-228D01*
G37*
G36*
G01Y456687D02*
G02X917549Y456125I-1071J739D01*
G02Y458729I0J1302D01*
G02X918620Y458167I0J-1301D01*
G03X919278I329J228D01*
G02X920349Y458729I1071J-739D01*
G02Y456125I0J-1302D01*
G02X919278Y456687I0J1301D01*
G03X918620I-329J-228D01*
G37*
G36*
G01Y460230D02*
G02X917549Y459668I-1071J739D01*
G02Y462272I0J1302D01*
G02X918620Y461710I0J-1301D01*
G03X919278I329J228D01*
G02X920349Y462272I1071J-739D01*
G02Y459668I0J-1302D01*
G02X919278Y460230I0J1301D01*
G03X918620I-329J-228D01*
G37*
G36*
G01X970895Y465004D02*
G02X973899I1502J0D01*
G02X972540Y463509I-1502J0D01*
G03X972386Y463411I19J-199D01*
G01X972223Y463131D01*
G03X972213Y462948I173J-101D01*
G02X972342Y462339I-1373J-609D01*
G02X971972Y461352I-1501J0D01*
G01Y461351D01*
X971971D01*
G03X971923Y461221I152J-130D01*
G01Y460957D01*
G03X971971Y460827I200J0D01*
G01X971972Y460826D01*
G02Y458852I-1131J-987D01*
G01Y458851D01*
X971971D01*
G03X971923Y458721I152J-130D01*
G01Y458457D01*
G03X971971Y458327I200J0D01*
G01X971972Y458326D01*
G02X972342Y457339I-1131J-987D01*
G02X970840Y455837I-1502J0D01*
G02X969853Y456207I0J1501D01*
G01X969852D01*
Y456208D01*
G03X969722Y456256I-130J-152D01*
G01X969458D01*
G03X969328Y456208I0J-200D01*
G01X969327Y456207D01*
G02X968340Y455837I-987J1131D01*
G02X966838Y457339I0J1502D01*
G02X967208Y458326I1501J0D01*
G01Y458327D01*
X967209D01*
G03X967257Y458457I-152J130D01*
G01Y458721D01*
G03X967209Y458851I-200J0D01*
G01X967208Y458852D01*
G02Y460826I1131J987D01*
G01Y460827D01*
X967209D01*
G03X967257Y460957I-152J130D01*
G01Y461221D01*
G03X967209Y461351I-200J0D01*
G01X967208Y461352D01*
G02X966838Y462339I1131J987D01*
G02X968340Y463841I1502J0D01*
G02X969327Y463471I0J-1501D01*
G01X969328D01*
Y463470D01*
G03X969458Y463422I130J152D01*
G01X969722D01*
G03X969852Y463470I0J200D01*
G01X969853Y463471D01*
G02X970697Y463834I987J-1132D01*
G03X970851Y463932I-19J199D01*
G01X971014Y464212D01*
G03X971024Y464395I-173J101D01*
G02X970895Y465004I1373J609D01*
G37*
G36*
G01X986587Y499103D02*
X986881D01*
G03X987028Y499168I-1J200D01*
G02X988134Y499653I1106J-1019D01*
G02X989636Y498151I0J-1502D01*
G02X989057Y496966I-1502J0D01*
G03X988980Y496808I123J-158D01*
G01Y496494D01*
G03X989057Y496336I200J0D01*
G02X989636Y495151I-923J-1185D01*
G02X988134Y493649I-1502J0D01*
G02X987147Y494019I0J1501D01*
G01X987146D01*
Y494020D01*
G03X987016Y494068I-130J-152D01*
G01X986752D01*
G03X986622Y494020I0J-200D01*
G01X986621Y494019D01*
G02X985634Y493649I-987J1131D01*
G02X984132Y495151I0J1502D01*
G02X984604Y496244I1502J0D01*
G01X984605Y496245D01*
G03X984666Y496410I-138J145D01*
G01X984635Y496725D01*
G03X984541Y496875I-199J-20D01*
G02X983832Y498151I794J1276D01*
G02X985334Y499653I1502J0D01*
G02X986440Y499168I0J-1504D01*
G03X986587Y499103I148J135D01*
G37*
G36*
G01X952531Y530446D02*
G02Y533450I0J1502D01*
G02X953755Y532819I0J-1503D01*
G01X953782Y532780D01*
X953866Y532736D01*
X954234Y532728D01*
G03X954396Y532805I4J200D01*
G02X955581Y533384I1185J-923D01*
G02X956568Y533014I0J-1501D01*
G01X956569D01*
Y533013D01*
G03X956699Y532965I130J152D01*
G01X956963D01*
G03X957093Y533013I0J200D01*
G01X957094Y533014D01*
G02X959068I987J-1131D01*
G01X959069D01*
Y533013D01*
G03X959199Y532965I130J152D01*
G01X959463D01*
G03X959593Y533013I0J200D01*
G01X959594Y533014D01*
G02X960581Y533384I987J-1131D01*
G02X962083Y531882I0J-1502D01*
G02X961816Y531027I-1502J0D01*
G01X961793Y530993D01*
X961776Y530912D01*
X961856Y530545D01*
X961904Y530478D01*
X961939Y530457D01*
G02X962668Y529169I-773J-1288D01*
G02X959664I-1502J0D01*
G02X959931Y530024I1502J0D01*
G01X959954Y530058D01*
X959971Y530139D01*
X959891Y530506D01*
X959843Y530573D01*
X959808Y530594D01*
G02X959595Y530750I777J1285D01*
G03X959593Y530751I-88J-173D01*
G03X959463Y530799I-130J-152D01*
G01X959199D01*
G03X959069Y530751I0J-200D01*
G01X959068Y530750D01*
G02X957094I-987J1131D01*
G01X957093D01*
Y530751D01*
G03X956963Y530799I-130J-152D01*
G01X956699D01*
G03X956569Y530751I0J-200D01*
G01X956568Y530750D01*
G02X955581Y530380I-987J1131D01*
G02X954357Y531011I0J1503D01*
G01X954330Y531050D01*
X954246Y531094D01*
X953878Y531102D01*
G03X953716Y531025I-4J-200D01*
G02X952531Y530446I-1185J923D01*
G37*
G36*
G01X976756Y545847D02*
X977050D01*
G03X977197Y545912I-1J200D01*
G02X978303Y546397I1106J-1019D01*
G02X979805Y544895I0J-1502D01*
G02X979226Y543710I-1502J0D01*
G03X979149Y543552I123J-158D01*
G01Y543238D01*
G03X979226Y543080I200J0D01*
G02X979805Y541895I-923J-1185D01*
G02X978303Y540393I-1502J0D01*
G02X977316Y540763I0J1501D01*
G01X977315D01*
Y540764D01*
G03X977185Y540812I-130J-152D01*
G01X976921D01*
G03X976791Y540764I0J-200D01*
G01X976790Y540763D01*
G02X975803Y540393I-987J1131D01*
G02X974301Y541895I0J1502D01*
G02X974773Y542988I1502J0D01*
G01X974774Y542989D01*
G03X974835Y543154I-138J145D01*
G01X974804Y543469D01*
G03X974710Y543619I-199J-20D01*
G02X974001Y544895I794J1276D01*
G02X975503Y546397I1502J0D01*
G02X976609Y545912I0J-1504D01*
G03X976756Y545847I148J135D01*
G37*
G36*
G01X990804Y566797D02*
G02X993808I1502J0D01*
G02X993176Y565573I-1501J0D01*
G03X993092Y565410I116J-163D01*
G01Y565084D01*
G03X993176Y564921I200J0D01*
G02X993808Y563697I-869J-1224D01*
G02X993402Y562670I-1502J0D01*
G01X993376Y562643D01*
X993348Y562572D01*
Y562222D01*
X993376Y562151D01*
X993402Y562124D01*
G02Y560070I-1096J-1027D01*
G01X993376Y560043D01*
X993348Y559972D01*
Y559622D01*
X993376Y559551D01*
X993402Y559524D01*
G02Y557470I-1096J-1027D01*
G01X993376Y557443D01*
X993348Y557372D01*
Y557022D01*
X993376Y556951D01*
X993402Y556924D01*
G02Y554870I-1096J-1027D01*
G01X993376Y554843D01*
X993348Y554772D01*
Y554422D01*
X993376Y554351D01*
X993402Y554324D01*
G02X993808Y553297I-1096J-1027D01*
G02X990804I-1502J0D01*
G02X991210Y554324I1502J0D01*
G01X991236Y554351D01*
X991264Y554422D01*
Y554772D01*
X991236Y554843D01*
X991210Y554870D01*
G02Y556924I1096J1027D01*
G01X991236Y556951D01*
X991264Y557022D01*
Y557372D01*
X991236Y557443D01*
X991210Y557470D01*
G02Y559524I1096J1027D01*
G01X991236Y559551D01*
X991264Y559622D01*
Y559972D01*
X991236Y560043D01*
X991210Y560070D01*
G02Y562124I1096J1027D01*
G01X991236Y562151D01*
X991264Y562222D01*
Y562572D01*
X991236Y562643D01*
X991210Y562670D01*
G02X990804Y563697I1096J1027D01*
G02X991436Y564921I1501J0D01*
G03X991520Y565084I-116J163D01*
G01Y565410D01*
G03X991436Y565573I-200J0D01*
G02X990804Y566797I869J1224D01*
G37*
G36*
G01X988011Y576484D02*
G02X991015I1502J0D01*
G02X990373Y575253I-1501J0D01*
G03X990289Y575114I114J-164D01*
G01X990246Y574778D01*
X990270Y574697D01*
X990298Y574665D01*
G02X990658Y573689I-1143J-976D01*
G02X989937Y572406I-1502J0D01*
G01X989893Y572379D01*
X989842Y572291D01*
X989834Y571849D01*
X989881Y571759D01*
X989924Y571731D01*
G02X990598Y570478I-828J-1253D01*
G02X989096Y568976I-1502J0D01*
G02X987917Y569547I0J1503D01*
G01X987891Y569580D01*
X987817Y569619D01*
X987438Y569648D01*
X987360Y569620D01*
X987329Y569591D01*
G02X986301Y569184I-1028J1095D01*
G02X984799Y570686I0J1502D01*
G02X985300Y571806I1502J0D01*
G01X985329Y571831D01*
X985363Y571901D01*
X985388Y572215D01*
G03X985344Y572356I-199J15D01*
G02X985008Y573303I1167J947D01*
G02X986510Y574805I1502J0D01*
G02X987401Y574512I0J-1501D01*
G01X987402D01*
X987433Y574489D01*
X987509Y574470D01*
X987865Y574522D01*
X987934Y574563D01*
X987957Y574594D01*
G02X988296Y574920I1198J-906D01*
G03X988380Y575059I-114J164D01*
G01X988423Y575395D01*
X988399Y575476D01*
X988371Y575508D01*
G02X988011Y576484I1143J976D01*
G37*
G36*
G01X907596Y592839D02*
G02X907244Y591990I-1201J1D01*
G01X907003Y591750D01*
G03X907001Y591748I140J-142D01*
G01X906862Y591604D01*
G02X906794Y591558I-144J139D01*
G01X906417Y591405D01*
G02X906342Y591390I-76J185D01*
G01X892598D01*
G03X892456Y591331I0J-200D01*
G01X889647Y588522D01*
G03X889588Y588380I141J-142D01*
G01Y569757D01*
G03X889647Y569615I200J0D01*
G01X893042Y566220D01*
G02X893394Y565371I-849J-850D01*
G01Y554552D01*
G02X893042Y553703I-1201J1D01*
G01X890386Y551048D01*
G03X890384Y551046I140J-142D01*
G01X890245Y550902D01*
G02X890177Y550856I-144J139D01*
G01X889800Y550703D01*
G02X889725Y550688I-76J185D01*
G01X886325D01*
G02X885938Y550753I3J1202D01*
G01X885884Y550771D01*
X885774Y550746D01*
X885732Y550704D01*
G03Y550422I142J-141D01*
G01X889331Y546823D01*
G03X889473Y546764I142J141D01*
G01X889557D01*
G03X889706Y546830I0J200D01*
G01X889933Y547084D01*
X889959Y547164D01*
X889955Y547206D01*
G02X889947Y547363I1494J155D01*
G02X891449Y548865I1502J0D01*
G02X892436Y548495I0J-1501D01*
G01X892437D01*
Y548494D01*
G03X892567Y548446I130J152D01*
G01X892831D01*
G03X892961Y548494I0J200D01*
G01X892962Y548495D01*
G02X893949Y548865I987J-1131D01*
G02X895451Y547363I0J-1502D01*
G02X895443Y547206I-1502J-2D01*
G01X895439Y547164D01*
X895465Y547084D01*
X895692Y546830D01*
G03X895841Y546764I149J134D01*
G01X897462D01*
G03X897604Y546823I0J200D01*
G01X903509Y552729D01*
G03X903568Y552871I-141J142D01*
G01Y556848D01*
G02X904155Y558263I2002J-1D01*
G01X907431Y561539D01*
G02X908846Y562126I1416J-1415D01*
G02X910848Y560124I0J-2002D01*
G02X910261Y558709I-2002J1D01*
G01X907631Y556078D01*
G03X907572Y555936I141J-142D01*
G01Y551959D01*
G02X906985Y550544I-2002J1D01*
G01X899789Y543348D01*
G02X898374Y542762I-1415J1415D01*
G01X888559D01*
G02X887453Y543096I1J2001D01*
G01X887452D01*
G03X887294Y543124I-111J-166D01*
G01X887007Y543052D01*
G03X886879Y542953I48J-194D01*
G02X885556Y542162I-1323J711D01*
G02X884054Y543664I0J1502D01*
G02X884811Y544968I1502J0D01*
G01X884852Y544991D01*
X884904Y545069D01*
X884952Y545430D01*
G03X884895Y545598I-198J26D01*
G01X876967Y553527D01*
G02X876380Y554942I1415J1416D01*
G02X878382Y556944I2002J0D01*
G02X878580Y556934I-2J-2002D01*
G01X878643Y556928D01*
X878753Y556990D01*
X878942Y557388D01*
G03X878902Y557615I-181J85D01*
G01X875060Y561457D01*
G03X875058Y561459I-142J-140D01*
G01X874914Y561598D01*
G02X874868Y561666I139J144D01*
G01X874715Y562043D01*
G02X874700Y562118I185J76D01*
G01Y569717D01*
G02X875268Y570737I1202J-1D01*
G01X875407Y570823D01*
G03X875495Y571043I-106J170D01*
G02X875447Y571419I1454J377D01*
G02X875495Y571795I1502J-1D01*
G03X875407Y572015I-194J50D01*
G01X875268Y572101D01*
G02X874700Y573121I634J1021D01*
G01Y577251D01*
X874642Y577346D01*
X874593Y577372D01*
G02Y580034I698J1331D01*
G01X874642Y580060D01*
X874700Y580155D01*
Y593628D01*
G02X875053Y594478I1202J-1D01*
G01X883280Y602705D01*
G02X884130Y603058I851J-849D01*
G01X905341D01*
G02X906191Y602705I-1J-1202D01*
G01X907244Y601652D01*
G02X907596Y600803I-849J-850D01*
G01Y592839D01*
G37*
G36*
G01X958097Y619590D02*
G02X957535Y620661I739J1071D01*
G02X960139I1302J0D01*
G02X959577Y619590I-1301J0D01*
G03Y618932I228J-329D01*
G02X960139Y617861I-739J-1071D01*
G02X957535I-1302J0D01*
G02X958097Y618932I1301J0D01*
G03Y619590I-228J329D01*
G37*
G36*
G01X961640D02*
G02X961078Y620661I739J1071D01*
G02X963682I1302J0D01*
G02X963120Y619590I-1301J0D01*
G03Y618932I228J-329D01*
G02X963682Y617861I-739J-1071D01*
G02X961078I-1302J0D01*
G02X961640Y618932I1301J0D01*
G03Y619590I-228J329D01*
G37*
G36*
G01X965183D02*
G02X964621Y620661I739J1071D01*
G02X967225I1302J0D01*
G02X966663Y619590I-1301J0D01*
G03Y618932I228J-329D01*
G02X967225Y617861I-739J-1071D01*
G02X964621I-1302J0D01*
G02X965183Y618932I1301J0D01*
G03Y619590I-228J329D01*
G37*
G36*
G01X968727D02*
G02X968165Y620661I739J1071D01*
G02X970769I1302J0D01*
G02X970207Y619590I-1301J0D01*
G03Y618932I228J-329D01*
G02X970769Y617861I-739J-1071D01*
G02X968165I-1302J0D01*
G02X968727Y618932I1301J0D01*
G03Y619590I-228J329D01*
G37*
G36*
G01X930573Y830527D02*
X930558Y830578D01*
G02X930498Y831000I1442J420D01*
G02X932000Y832502I1502J0D01*
G02X933131Y831988I0J-1501D01*
G01X933164Y831951D01*
X933256Y831915D01*
X933684Y831968D01*
X933765Y832024D01*
X933788Y832069D01*
G02X935124Y832884I1336J-688D01*
G02Y829880I0J-1502D01*
G02X933993Y830394I0J1501D01*
G01X933960Y830431D01*
X933868Y830467D01*
X933440Y830414D01*
X933359Y830358D01*
X933336Y830313D01*
G02X932000Y829498I-1336J688D01*
G02X931696Y829529I0J1502D01*
G01X931644Y829540D01*
X931545Y829508D01*
X931240Y829178D01*
X931217Y829076D01*
X931232Y829025D01*
G02X931292Y828603I-1442J-420D01*
G02X929790Y830105I-1502J0D01*
G02X930094Y830074I0J-1502D01*
G01X930146Y830063D01*
X930245Y830095D01*
X930550Y830425D01*
X930573Y830527D01*
G37*
G36*
G01X983337Y1080154D02*
X983493Y1080477D01*
X983498Y1080554D01*
X983485Y1080592D01*
G02X983407Y1081071I1424J478D01*
G02X986411I1502J0D01*
G02X985418Y1079658I-1502J0D01*
G01X985381Y1079644D01*
X985323Y1079592D01*
X985167Y1079269D01*
X985162Y1079192D01*
X985175Y1079154D01*
G02X985253Y1078675I-1424J-478D01*
G02X982249I-1502J0D01*
G02X983242Y1080088I1502J0D01*
G01X983279Y1080102D01*
X983337Y1080154D01*
G37*
G36*
G01X971930Y1095001D02*
Y1095317D01*
G03X971853Y1095474I-200J-1D01*
G02X971274Y1096659I923J1185D01*
G02X974278I1502J0D01*
G02X973699Y1095474I-1502J0D01*
G03X973622Y1095317I123J-158D01*
G01Y1095001D01*
G03X973699Y1094844I200J1D01*
G02X974278Y1093659I-923J-1185D01*
G02X971274I-1502J0D01*
G02X971853Y1094844I1502J0D01*
G03X971930Y1095001I-123J158D01*
G37*
G36*
G01X933418Y1146625D02*
X933082D01*
X933015Y1146600D01*
X932987Y1146576D01*
G02X932000Y1146206I-987J1131D01*
G02Y1149210I0J1502D01*
G02X932987Y1148840I0J-1501D01*
G01X933015Y1148816D01*
X933082Y1148791D01*
X933418D01*
X933485Y1148816D01*
X933513Y1148840D01*
G02X934500Y1149210I987J-1131D01*
G02Y1146206I0J-1502D01*
G02X933513Y1146576I0J1501D01*
G01X933485Y1146600D01*
X933418Y1146625D01*
G37*
G36*
G01X951947Y1264141D02*
X952283D01*
X952350Y1264166D01*
X952378Y1264190D01*
G02X954352I987J-1131D01*
G01X954380Y1264166D01*
X954447Y1264141D01*
X954783D01*
X954850Y1264166D01*
X954878Y1264190D01*
G02X955865Y1264560I987J-1131D01*
G02X957367Y1263058I0J-1502D01*
G02X956997Y1262071I-1501J0D01*
G01X956973Y1262043D01*
X956948Y1261976D01*
Y1261640D01*
X956973Y1261573D01*
X956997Y1261545D01*
G02X957367Y1260558I-1131J-987D01*
G02X955865Y1259056I-1502J0D01*
G02X954878Y1259426I0J1501D01*
G01X954850Y1259450D01*
X954783Y1259475D01*
X954447D01*
X954380Y1259450D01*
X954352Y1259426D01*
G02X952378I-987J1131D01*
G01X952350Y1259450D01*
X952283Y1259475D01*
X951947D01*
X951880Y1259450D01*
X951852Y1259426D01*
G02X950865Y1259056I-987J1131D01*
G02X949363Y1260558I0J1502D01*
G02X949733Y1261545I1501J0D01*
G01X949757Y1261573D01*
X949782Y1261640D01*
Y1261976D01*
X949757Y1262043D01*
X949733Y1262071D01*
G02X949363Y1263058I1131J987D01*
G02X950865Y1264560I1502J0D01*
G02X951852Y1264190I0J-1501D01*
G01X951880Y1264166D01*
X951947Y1264141D01*
G37*
G36*
G01X970091Y721470D02*
X969755Y721443D01*
X969691Y721412D01*
X969665Y721386D01*
G02X968589Y720932I-1076J1048D01*
G02Y723936I0J1502D01*
G02X969481Y723642I-1J-1502D01*
G01X969511Y723620D01*
X969579Y723601D01*
X969915Y723628D01*
X969979Y723659D01*
X970005Y723685D01*
G02X971081Y724139I1076J-1048D01*
G02X972346Y723447I0J-1502D01*
G01X972367Y723414D01*
X972432Y723368D01*
X972787Y723291D01*
X972865Y723305D01*
X972899Y723327D01*
G02X973712Y723566I813J-1263D01*
G02Y720562I0J-1502D01*
G02X972447Y721254I0J1502D01*
G01X972426Y721287D01*
X972361Y721333D01*
X972006Y721410D01*
X971928Y721396D01*
X971894Y721374D01*
G02X971081Y721135I-813J1263D01*
G02X970189Y721429I1J1502D01*
G01X970159Y721451D01*
X970091Y721470D01*
G37*
G36*
G01X965149Y668385D02*
X965173Y668434D01*
G02X966797Y669456I1625J-781D01*
G01X970197D01*
G02X971585Y668803I0J-1802D01*
G01X971611Y668772D01*
X971681Y668735D01*
X972048Y668705D01*
X972123Y668729D01*
X972155Y668756D01*
G02X973138Y669123I984J-1135D01*
G02Y666119I0J-1502D01*
G02X972130Y666507I0J1503D01*
G01X972100Y666535D01*
X972025Y666561D01*
X971657Y666539D01*
X971586Y666504D01*
X971559Y666473D01*
G02X970197Y665850I-1363J1180D01*
G01X966797D01*
G02X965187Y666842I0J1803D01*
G01X965163Y666891D01*
X965070Y666950D01*
X964608Y666964D01*
X964512Y666911D01*
X964485Y666863D01*
G02X963187Y666118I-1298J758D01*
G02Y669122I0J1502D01*
G02X964471Y668400I0J-1503D01*
G01X964499Y668353D01*
X964596Y668302D01*
X965057Y668324D01*
X965149Y668385D01*
G37*
G36*
G01X1037551Y1117691D02*
G02X1040555I1502J0D01*
G02X1039994Y1116520I-1503J0D01*
G01X1039958Y1116491D01*
X1039919Y1116408D01*
X1039924Y1116046D01*
G03X1040003Y1115889I200J2D01*
G02X1040600Y1114691I-905J-1199D01*
G02X1037596I-1502J0D01*
G02X1038157Y1115862I1503J0D01*
G01X1038193Y1115891D01*
X1038232Y1115974D01*
X1038227Y1116336D01*
G03X1038148Y1116493I-200J-2D01*
G02X1037551Y1117691I905J1199D01*
G37*
G36*
G01Y1130291D02*
G02X1040555I1502J0D01*
G02X1039994Y1129120I-1503J0D01*
G01X1039958Y1129091D01*
X1039919Y1129008D01*
X1039924Y1128646D01*
G03X1040003Y1128489I200J2D01*
G02X1040600Y1127291I-905J-1199D01*
G02X1037596I-1502J0D01*
G02X1038157Y1128462I1503J0D01*
G01X1038193Y1128491D01*
X1038232Y1128574D01*
X1038227Y1128936D01*
G03X1038148Y1129093I-200J-2D01*
G02X1037551Y1130291I905J1199D01*
G37*
G36*
G01Y1142891D02*
G02X1040555I1502J0D01*
G02X1039994Y1141720I-1503J0D01*
G01X1039958Y1141691D01*
X1039919Y1141608D01*
X1039924Y1141246D01*
G03X1040003Y1141089I200J2D01*
G02X1040600Y1139891I-905J-1199D01*
G02X1037596I-1502J0D01*
G02X1038157Y1141062I1503J0D01*
G01X1038193Y1141091D01*
X1038232Y1141174D01*
X1038227Y1141536D01*
G03X1038148Y1141693I-200J-2D01*
G02X1037551Y1142891I905J1199D01*
G37*
G36*
G01Y1155491D02*
G02X1040555I1502J0D01*
G02X1039994Y1154320I-1503J0D01*
G01X1039958Y1154291D01*
X1039919Y1154208D01*
X1039924Y1153846D01*
G03X1040003Y1153689I200J2D01*
G02X1040600Y1152491I-905J-1199D01*
G02X1037596I-1502J0D01*
G02X1038157Y1153662I1503J0D01*
G01X1038193Y1153691D01*
X1038232Y1153774D01*
X1038227Y1154136D01*
G03X1038148Y1154293I-200J-2D01*
G02X1037551Y1155491I905J1199D01*
G37*
G36*
G01Y1168091D02*
G02X1040555I1502J0D01*
G02X1039994Y1166920I-1503J0D01*
G01X1039958Y1166891D01*
X1039919Y1166808D01*
X1039924Y1166446D01*
G03X1040003Y1166289I200J2D01*
G02X1040600Y1165091I-905J-1199D01*
G02X1037596I-1502J0D01*
G02X1038157Y1166262I1503J0D01*
G01X1038193Y1166291D01*
X1038232Y1166374D01*
X1038227Y1166736D01*
G03X1038148Y1166893I-200J-2D01*
G02X1037551Y1168091I905J1199D01*
G37*
G36*
G01Y1105091D02*
G02X1040555I1502J0D01*
G02X1039994Y1103920I-1503J0D01*
G01X1039958Y1103891D01*
X1039919Y1103808D01*
X1039924Y1103446D01*
G03X1040003Y1103289I200J2D01*
G02X1040600Y1102091I-905J-1199D01*
G02X1039958Y1100859I-1503J0D01*
G01X1039913Y1100828D01*
X1039867Y1100726D01*
X1039916Y1100321D01*
G03X1040041Y1100158I199J23D01*
G01X1040042D01*
G02X1041001Y1098758I-542J-1400D01*
G02X1037997I-1502J0D01*
G02X1038639Y1099990I1503J0D01*
G01X1038684Y1100021D01*
X1038730Y1100123D01*
X1038681Y1100528D01*
G03X1038556Y1100691I-199J-23D01*
G01X1038555D01*
G02X1037596Y1102091I542J1400D01*
G02X1038157Y1103262I1503J0D01*
G01X1038193Y1103291D01*
X1038232Y1103374D01*
X1038227Y1103736D01*
G03X1038148Y1103893I-200J-2D01*
G02X1037551Y1105091I905J1199D01*
G37*
G36*
G01X1183233Y1134362D02*
X1182119D01*
G02X1181796Y1134404I0J1265D01*
G03X1181785Y1134406I-41J-196D01*
G03X1181611Y1134062I-40J-196D01*
G02X1182008Y1133169I-806J-893D01*
G02X1179604I-1202J0D01*
G02X1180001Y1134062I1203J0D01*
G03X1179827Y1134406I-134J148D01*
G03X1179816Y1134404I30J-198D01*
G02X1179493Y1134362I-323J1223D01*
G01X1178379D01*
G02X1178056Y1134404I0J1265D01*
G03X1178045Y1134406I-41J-196D01*
G03X1177871Y1134062I-40J-196D01*
G02X1178268Y1133169I-806J-893D01*
G02X1175864I-1202J0D01*
G02X1176261Y1134062I1203J0D01*
G03X1176087Y1134406I-134J148D01*
G03X1176076Y1134404I30J-198D01*
G02X1175753Y1134362I-323J1223D01*
G01X1174639D01*
G02X1174316Y1134404I0J1265D01*
G03X1174305Y1134406I-41J-196D01*
G03X1174131Y1134062I-40J-196D01*
G02X1174528Y1133169I-806J-893D01*
G02X1172124I-1202J0D01*
G02X1172521Y1134062I1203J0D01*
G03X1172347Y1134406I-134J148D01*
G03X1172336Y1134404I30J-198D01*
G02X1172013Y1134362I-323J1223D01*
G01X1170899D01*
G02X1170576Y1134404I0J1265D01*
G03X1170565Y1134406I-41J-196D01*
G03X1170391Y1134062I-40J-196D01*
G02X1170788Y1133169I-806J-893D01*
G02X1168384I-1202J0D01*
G02X1168781Y1134062I1203J0D01*
G03X1168607Y1134406I-134J148D01*
G03X1168596Y1134404I30J-198D01*
G02X1168273Y1134362I-323J1223D01*
G01X1167159D01*
G02X1166836Y1134404I0J1265D01*
G03X1166825Y1134406I-41J-196D01*
G03X1166651Y1134062I-40J-196D01*
G02X1167048Y1133169I-806J-893D01*
G02X1164644I-1202J0D01*
G02X1165041Y1134062I1203J0D01*
G03X1164867Y1134406I-134J148D01*
G03X1164856Y1134404I30J-198D01*
G02X1164533Y1134362I-323J1223D01*
G01X1163419D01*
G02X1163096Y1134404I0J1265D01*
G03X1163085Y1134406I-41J-196D01*
G03X1162911Y1134062I-40J-196D01*
G02X1163308Y1133169I-806J-893D01*
G02X1160904I-1202J0D01*
G02X1161301Y1134062I1203J0D01*
G03X1161127Y1134406I-134J148D01*
G03X1161116Y1134404I30J-198D01*
G02X1160793Y1134362I-323J1223D01*
G01X1159678D01*
G02X1159355Y1134404I0J1265D01*
G03X1159344Y1134406I-41J-196D01*
G03X1159170Y1134062I-40J-196D01*
G02X1159567Y1133169I-806J-893D01*
G02X1157163I-1202J0D01*
G02X1157560Y1134062I1203J0D01*
G03X1157386Y1134406I-134J148D01*
G03X1157375Y1134404I30J-198D01*
G02X1157052Y1134362I-323J1223D01*
G01X1155938D01*
G02X1155615Y1134404I0J1265D01*
G03X1155604Y1134406I-41J-196D01*
G03X1155430Y1134062I-40J-196D01*
G02X1155827Y1133169I-806J-893D01*
G02X1153423I-1202J0D01*
G02X1153820Y1134062I1203J0D01*
G03X1153646Y1134406I-134J148D01*
G03X1153635Y1134404I30J-198D01*
G02X1153312Y1134362I-323J1223D01*
G01X1152199D01*
G02X1152113Y1134365I1J1265D01*
G03X1152074Y1134364I-14J-200D01*
G03X1151926Y1134065I25J-199D01*
G02X1152087Y1133465I-1040J-601D01*
G01Y1133464D01*
G02X1149683I-1202J0D01*
G01Y1133465D01*
G02X1149844Y1134065I1201J-1D01*
G03X1149696Y1134364I-173J100D01*
G03X1149657Y1134365I-25J-199D01*
G02X1149571Y1134362I-87J1262D01*
G01X1144719D01*
G02X1143721Y1134850I0J1265D01*
G03X1143563Y1134927I-158J-123D01*
G01X1143247D01*
G03X1143089Y1134850I0J-200D01*
G02X1142091Y1134362I-998J777D01*
G01X1140978D01*
G02X1140655Y1134404I0J1265D01*
G03X1140644Y1134406I-41J-196D01*
G03X1140470Y1134062I-40J-196D01*
G02X1140867Y1133169I-806J-893D01*
G02X1138463I-1202J0D01*
G02X1138860Y1134062I1203J0D01*
G03X1138686Y1134406I-134J148D01*
G03X1138675Y1134404I30J-198D01*
G02X1138352Y1134362I-323J1223D01*
G01X1137237D01*
G02X1136914Y1134404I0J1265D01*
G03X1136903Y1134406I-41J-196D01*
G03X1136729Y1134062I-40J-196D01*
G02X1137126Y1133169I-806J-893D01*
G02X1134722I-1202J0D01*
G02X1135119Y1134062I1203J0D01*
G03X1134945Y1134406I-134J148D01*
G03X1134934Y1134404I30J-198D01*
G02X1134611Y1134362I-323J1223D01*
G01X1133497D01*
G02X1133174Y1134404I0J1265D01*
G03X1133163Y1134406I-41J-196D01*
G03X1132989Y1134062I-40J-196D01*
G02X1133386Y1133169I-806J-893D01*
G02X1130982I-1202J0D01*
G02X1131379Y1134062I1203J0D01*
G03X1131205Y1134406I-134J148D01*
G03X1131194Y1134404I30J-198D01*
G02X1130871Y1134362I-323J1223D01*
G01X1129757D01*
G02X1129434Y1134404I0J1265D01*
G03X1129423Y1134406I-41J-196D01*
G03X1129249Y1134062I-40J-196D01*
G02X1129646Y1133169I-806J-893D01*
G02X1127242I-1202J0D01*
G02X1127639Y1134062I1203J0D01*
G03X1127465Y1134406I-134J148D01*
G03X1127454Y1134404I30J-198D01*
G02X1127131Y1134362I-323J1223D01*
G01X1126017D01*
G02X1125694Y1134404I0J1265D01*
G03X1125683Y1134406I-41J-196D01*
G03X1125509Y1134062I-40J-196D01*
G02X1125906Y1133169I-806J-893D01*
G02X1123502I-1202J0D01*
G02X1123899Y1134062I1203J0D01*
G03X1123725Y1134406I-134J148D01*
G03X1123714Y1134404I30J-198D01*
G02X1123391Y1134362I-323J1223D01*
G01X1122277D01*
G02X1121954Y1134404I0J1265D01*
G03X1121943Y1134406I-41J-196D01*
G03X1121769Y1134062I-40J-196D01*
G02X1122166Y1133169I-806J-893D01*
G02X1119762I-1202J0D01*
G02X1120159Y1134062I1203J0D01*
G03X1119985Y1134406I-134J148D01*
G03X1119974Y1134404I30J-198D01*
G02X1119651Y1134362I-323J1223D01*
G01X1118537D01*
G02X1118214Y1134404I0J1265D01*
G03X1118203Y1134406I-41J-196D01*
G03X1118029Y1134062I-40J-196D01*
G02X1118426Y1133169I-806J-893D01*
G02X1116022I-1202J0D01*
G02X1116419Y1134062I1203J0D01*
G03X1116245Y1134406I-134J148D01*
G03X1116234Y1134404I30J-198D01*
G02X1115911Y1134362I-323J1223D01*
G01X1114797D01*
G02X1114474Y1134404I0J1265D01*
G03X1114463Y1134406I-41J-196D01*
G03X1114289Y1134062I-40J-196D01*
G02X1114686Y1133169I-806J-893D01*
G02X1112282I-1202J0D01*
G02X1112679Y1134062I1203J0D01*
G03X1112505Y1134406I-134J148D01*
G03X1112494Y1134404I30J-198D01*
G02X1112171Y1134362I-323J1223D01*
G01X1111348D01*
G02X1110453Y1134733I0J1265D01*
G01X1109779Y1135407D01*
G02X1109721Y1135533I142J142D01*
G01Y1135541D01*
G03X1109553Y1135723I-199J-16D01*
G02X1108557Y1136719I190J1186D01*
G03X1108375Y1136887I-198J-31D01*
G01X1108367D01*
G02X1108241Y1136945I16J200D01*
G01X1106993Y1138193D01*
X1106949Y1138208D01*
G02X1106214Y1138850I400J1200D01*
G01X1106182Y1138915D01*
G03X1106003Y1139026I-179J-89D01*
G01X1105946D01*
X1105849Y1138966D01*
X1105792Y1138850D01*
G02X1104658Y1138142I-1136J558D01*
G01X1103608D01*
G02X1103170Y1138221I2J1266D01*
G03X1102981Y1137873I-70J-187D01*
G02X1103465Y1136909I-718J-964D01*
G02X1101061I-1202J0D01*
G02X1101545Y1137873I1202J0D01*
G03X1101356Y1138221I-119J161D01*
G02X1100918Y1138142I-440J1187D01*
G01X1099868D01*
G02X1099430Y1138221I2J1266D01*
G03X1099241Y1137873I-70J-187D01*
G02X1099725Y1136909I-718J-964D01*
G02X1097321I-1202J0D01*
G02X1097805Y1137873I1202J0D01*
G03X1097616Y1138221I-119J161D01*
G02X1097178Y1138142I-440J1187D01*
G01X1096128D01*
G02X1095690Y1138221I2J1266D01*
G03X1095501Y1137873I-70J-187D01*
G02X1095985Y1136909I-718J-964D01*
G02X1093581I-1202J0D01*
G02X1094065Y1137873I1202J0D01*
G03X1093876Y1138221I-119J161D01*
G02X1093438Y1138142I-440J1187D01*
G01X1092388D01*
G02X1091950Y1138221I2J1266D01*
G03X1091761Y1137873I-70J-187D01*
G02X1092245Y1136909I-718J-964D01*
G02X1089841I-1202J0D01*
G02X1090325Y1137873I1202J0D01*
G03X1090136Y1138221I-119J161D01*
G02X1089698Y1138142I-440J1187D01*
G01X1088647D01*
G02X1088209Y1138221I2J1266D01*
G03X1088020Y1137873I-70J-187D01*
G02X1088504Y1136909I-718J-964D01*
G02X1086100I-1202J0D01*
G02X1086584Y1137873I1202J0D01*
G03X1086395Y1138221I-119J161D01*
G02X1085957Y1138142I-440J1187D01*
G01X1084930D01*
G03X1084756Y1138040I0J-200D01*
G01X1084585Y1137736D01*
G03X1084589Y1137534I175J-98D01*
G02X1084764Y1136909I-1029J-625D01*
G02X1082360I-1202J0D01*
G02X1083498Y1138109I1202J0D01*
G03X1083640Y1138439I-10J200D01*
G03X1083619Y1138459I-148J-134D01*
G02X1083561Y1138514I841J945D01*
G01X1083541Y1138534D01*
G02X1083172Y1139384I896J894D01*
G03X1083056Y1139558I-200J-7D01*
G02X1082360Y1140649I507J1091D01*
G02X1082821Y1141595I1201J0D01*
G03X1082898Y1141752I-123J158D01*
G01Y1142265D01*
G03X1082882Y1142343I-200J0D01*
G01X1082854Y1142411D01*
G02X1082838Y1142489I184J78D01*
G01Y1142988D01*
G02X1082868Y1143261I1266J-1D01*
G03X1082800Y1143459I-195J44D01*
G02Y1145319I762J930D01*
G03X1082868Y1145517I-127J154D01*
G02X1082838Y1145790I1236J274D01*
G01Y1146728D01*
G02X1082868Y1147001I1266J-1D01*
G03X1082800Y1147199I-195J44D01*
G02Y1149059I762J930D01*
G03X1082868Y1149257I-127J154D01*
G02X1082838Y1149530I1236J274D01*
G01Y1150469D01*
G02X1082868Y1150742I1266J-1D01*
G03X1082800Y1150940I-195J44D01*
G02Y1152800I762J930D01*
G03X1082868Y1152998I-127J154D01*
G02X1082838Y1153271I1236J274D01*
G01Y1154300D01*
G03X1082753Y1154463I-200J-1D01*
G02Y1156757I809J1147D01*
G03X1082838Y1156920I-115J164D01*
G01Y1157949D01*
G02X1082868Y1158222I1266J-1D01*
G03X1082800Y1158420I-195J44D01*
G02Y1160280I762J930D01*
G03X1082868Y1160478I-127J154D01*
G02X1082838Y1160751I1236J274D01*
G01Y1169097D01*
G02X1083205Y1169987I1266J-1D01*
G01X1084712Y1171494D01*
G02X1085310Y1171830I896J-894D01*
G01X1085571Y1171892D01*
G02X1085666Y1171891I45J-195D01*
G01X1086172Y1171763D01*
G02X1086257Y1171718I-48J-194D01*
G01X1086397Y1171592D01*
G03X1086641Y1171574I134J149D01*
G02X1087302Y1171772I661J-1004D01*
G02X1087964Y1171573I0J-1202D01*
G03X1088200Y1171584I110J167D01*
G02X1088994Y1171866I796J-984D01*
G01X1089550D01*
G02X1089623Y1171852I0J-200D01*
G01X1089990Y1171708D01*
G02X1090050Y1171671I-73J-186D01*
G01X1090140Y1171592D01*
G03X1090382Y1171574I133J149D01*
G02X1091042Y1171772I661J-1004D01*
G01X1091043D01*
G02X1091705Y1171573I0J-1202D01*
G03X1091941Y1171584I110J167D01*
G02X1092735Y1171866I796J-984D01*
G01X1093290D01*
G02X1093363Y1171852I-1J-200D01*
G01X1093569Y1171771D01*
G03X1093756Y1171792I74J186D01*
G01X1093797Y1171820D01*
X1093842Y1171906D01*
Y1173218D01*
G02X1093886Y1173343I200J0D01*
G01X1093895Y1173354D01*
X1093894Y1173496D01*
X1093850Y1173550D01*
G02X1093581Y1174309I934J758D01*
G01Y1174311D01*
G02X1093850Y1175069I1202J0D01*
G01X1093895Y1175125D01*
X1093896Y1175266D01*
X1093887Y1175277D01*
G02X1093842Y1175403I155J126D01*
G01Y1176959D01*
G02X1093886Y1177084I200J0D01*
G01X1093895Y1177095D01*
X1093894Y1177237D01*
X1093850Y1177291D01*
G02X1093581Y1178050I934J758D01*
G01Y1178052D01*
G02X1093850Y1178810I1202J0D01*
G01X1093895Y1178866D01*
X1093896Y1179007D01*
X1093887Y1179018D01*
G02X1093842Y1179144I155J126D01*
G01Y1180699D01*
G02X1093886Y1180824I200J0D01*
G01X1093895Y1180835D01*
X1093894Y1180977D01*
X1093850Y1181031D01*
G02X1093581Y1181790I934J758D01*
G01Y1181792D01*
G02X1093850Y1182550I1202J0D01*
G01X1093895Y1182606D01*
X1093896Y1182747D01*
X1093887Y1182758D01*
G02X1093842Y1182884I155J126D01*
G01Y1184439D01*
G02X1093886Y1184564I200J0D01*
G01X1094356Y1185151D01*
G02X1094469Y1185221I156J-125D01*
G01X1094834Y1185301D01*
G03X1094840Y1185302I-30J198D01*
G03Y1185760I-57J229D01*
G03X1094834Y1185761I-36J-197D01*
G01X1094469Y1185841D01*
G02X1094356Y1185911I43J195D01*
G01X1094019Y1186332D01*
G03X1093893Y1186405I-156J-125D01*
G01X1093684Y1186438D01*
X1093611Y1186422D01*
X1093579Y1186400D01*
G02X1092914Y1186199I-665J1001D01*
G01X1092913D01*
G02X1092693Y1186220I4J1202D01*
G01X1092691D01*
G03X1092514Y1186165I-36J-197D01*
G01X1092279Y1185930D01*
G03X1092224Y1185753I142J-141D01*
G01Y1185751D01*
G02X1092245Y1185531I-1181J-224D01*
G02X1089841I-1202J0D01*
G02X1089862Y1185752I1202J-3D01*
G01Y1185754D01*
G03X1089807Y1185931I-197J36D01*
G01X1089572Y1186165D01*
G03X1089395Y1186220I-141J-142D01*
G01X1089394D01*
G02X1089172Y1186199I-224J1181D01*
G02X1090374Y1187401I0J1202D01*
G02X1090353Y1187180I-1202J3D01*
G01Y1187178D01*
G03X1090408Y1187001I197J-36D01*
G01X1090643Y1186767D01*
G03X1090820Y1186712I141J142D01*
G01X1090821D01*
G02X1091043Y1186733I224J-1181D01*
G02X1091263Y1186712I-4J-1202D01*
G01X1091265D01*
G03X1091442Y1186767I36J197D01*
G01X1091677Y1187002D01*
G03X1091732Y1187179I-142J141D01*
G01Y1187181D01*
G02X1091711Y1187401I1181J224D01*
G02X1092913Y1188603I1202J0D01*
G01X1092914D01*
G02X1093579Y1188402I0J-1202D01*
G01X1093611Y1188380D01*
X1093684Y1188364D01*
X1093893Y1188397D01*
G03X1094019Y1188470I-30J198D01*
G01X1094356Y1188891D01*
G02X1094469Y1188961I156J-125D01*
G01X1094835Y1189041D01*
G03X1094839Y1189042I-46J194D01*
G03X1095019Y1189253I-56J230D01*
G03X1095020Y1189265I-198J23D01*
G02X1095389Y1190138I1265J-20D01*
G01X1096320Y1191069D01*
G02X1096328Y1191076I837J-949D01*
G03X1096334Y1191082I-138J144D01*
G02X1097216Y1191442I884J-906D01*
G01X1097428D01*
G03X1097614Y1191569I0J200D01*
G01X1097750Y1191915D01*
G03X1097701Y1192134I-186J73D01*
G02X1097321Y1193011I822J877D01*
G02X1099725I1202J0D01*
G02X1099345Y1192134I-1202J0D01*
G03X1099296Y1191915I137J-146D01*
G01X1099432Y1191569D01*
G03X1099618Y1191442I186J73D01*
G01X1101168D01*
G03X1101354Y1191569I0J200D01*
G01X1101490Y1191915D01*
G03X1101441Y1192134I-186J73D01*
G02X1101061Y1193011I822J877D01*
G02X1103465I1202J0D01*
G02X1103085Y1192134I-1202J0D01*
G03X1103036Y1191915I137J-146D01*
G01X1103172Y1191569D01*
G03X1103358Y1191442I186J73D01*
G01X1106931D01*
G03X1107073Y1191500I1J200D01*
G01X1107660Y1192087D01*
G03X1107690Y1192125I-141J142D01*
G01X1107960Y1192569D01*
G02X1108039Y1192643I171J-103D01*
G01X1108406Y1192833D01*
G02X1108430Y1192845I578J-1126D01*
G03X1108541Y1193022I-89J179D01*
G02X1108550Y1193152I1202J-18D01*
G01Y1193154D01*
G03X1108462Y1193344I-199J23D01*
G01X1108184Y1193528D01*
G02X1107620Y1194581I702J1053D01*
G01Y1195181D01*
G02X1108184Y1196234I1266J0D01*
G01X1108462Y1196418D01*
G03X1108550Y1196608I-111J167D01*
G01Y1196609D01*
G02X1108541Y1196748I1193J147D01*
G01Y1196751D01*
G02X1109743Y1197953I1202J0D01*
G01X1109758D01*
G03X1109932Y1198051I2J200D01*
G01X1110148Y1198414D01*
G02X1111236Y1199034I1089J-646D01*
G01X1111991D01*
G02X1113079Y1198414I-1J-1266D01*
G01X1113295Y1198051D01*
G03X1113469Y1197953I172J102D01*
G01X1113499D01*
G03X1113673Y1198051I2J200D01*
G01X1113889Y1198414D01*
G02X1114977Y1199034I1089J-646D01*
G01X1115731D01*
G02X1116819Y1198414I-1J-1266D01*
G01X1117035Y1198051D01*
G03X1117209Y1197953I172J102D01*
G01X1117239D01*
G03X1117413Y1198051I2J200D01*
G01X1117629Y1198414D01*
G02X1118717Y1199034I1089J-646D01*
G01X1119471D01*
G02X1120559Y1198414I-1J-1266D01*
G01X1120775Y1198051D01*
G03X1120949Y1197953I172J102D01*
G01X1120979D01*
G03X1121153Y1198051I2J200D01*
G01X1121369Y1198414D01*
G02X1122457Y1199034I1089J-646D01*
G01X1123211D01*
G02X1124299Y1198414I-1J-1266D01*
G01X1124515Y1198051D01*
G03X1124689Y1197953I172J102D01*
G01X1124719D01*
G03X1124893Y1198051I2J200D01*
G01X1125109Y1198414D01*
G02X1126197Y1199034I1089J-646D01*
G01X1126951D01*
G02X1128039Y1198414I-1J-1266D01*
G01X1128255Y1198051D01*
G03X1128429Y1197953I172J102D01*
G01X1128459D01*
G03X1128633Y1198051I2J200D01*
G01X1128849Y1198414D01*
G02X1129937Y1199034I1089J-646D01*
G01X1130691D01*
G02X1131779Y1198414I-1J-1266D01*
G01X1131995Y1198051D01*
G03X1132169Y1197953I172J102D01*
G01X1132199D01*
G03X1132373Y1198051I2J200D01*
G01X1132589Y1198414D01*
G02X1133677Y1199034I1089J-646D01*
G01X1134431D01*
G02X1135519Y1198414I-1J-1266D01*
G01X1135735Y1198051D01*
G03X1135909Y1197953I172J102D01*
G01X1135939D01*
G03X1136113Y1198051I2J200D01*
G01X1136329Y1198414D01*
G02X1137417Y1199034I1089J-646D01*
G01X1138172D01*
G02X1139260Y1198414I-1J-1266D01*
G01X1139476Y1198051D01*
G03X1139650Y1197953I172J102D01*
G01X1139680D01*
G03X1139854Y1198051I2J200D01*
G01X1140070Y1198414D01*
G02X1141158Y1199034I1089J-646D01*
G01X1141912D01*
G02X1143000Y1198414I-1J-1266D01*
G01X1143216Y1198051D01*
G03X1143390Y1197953I172J102D01*
G01X1143420D01*
G03X1143594Y1198051I2J200D01*
G01X1143810Y1198414D01*
G02X1144898Y1199034I1089J-646D01*
G01X1149392D01*
G02X1150480Y1198414I-1J-1266D01*
G01X1150696Y1198051D01*
G03X1150870Y1197953I172J102D01*
G01X1150900D01*
G03X1151074Y1198051I2J200D01*
G01X1151290Y1198414D01*
G02X1152378Y1199034I1089J-646D01*
G01X1153132D01*
G02X1154220Y1198414I-1J-1266D01*
G01X1154436Y1198051D01*
G03X1154610Y1197953I172J102D01*
G01X1154640D01*
G03X1154814Y1198051I2J200D01*
G01X1155030Y1198414D01*
G02X1156118Y1199034I1089J-646D01*
G01X1156872D01*
G02X1157960Y1198414I-1J-1266D01*
G01X1158176Y1198051D01*
G03X1158350Y1197953I172J102D01*
G01X1158380D01*
G03X1158554Y1198051I2J200D01*
G01X1158770Y1198414D01*
G02X1159858Y1199034I1089J-646D01*
G01X1160613D01*
G02X1161701Y1198414I-1J-1266D01*
G01X1161917Y1198051D01*
G03X1162091Y1197953I172J102D01*
G01X1162121D01*
G03X1162295Y1198051I2J200D01*
G01X1162511Y1198414D01*
G02X1163599Y1199034I1089J-646D01*
G01X1164353D01*
G02X1165441Y1198414I-1J-1266D01*
G01X1165657Y1198051D01*
G03X1165831Y1197953I172J102D01*
G01X1165861D01*
G03X1166035Y1198051I2J200D01*
G01X1166251Y1198414D01*
G02X1167339Y1199034I1089J-646D01*
G01X1168093D01*
G02X1169181Y1198414I-1J-1266D01*
G01X1169397Y1198051D01*
G03X1169571Y1197953I172J102D01*
G01X1169601D01*
G03X1169775Y1198051I2J200D01*
G01X1169991Y1198414D01*
G02X1171079Y1199034I1089J-646D01*
G01X1171833D01*
G02X1172921Y1198414I-1J-1266D01*
G01X1173137Y1198051D01*
G03X1173311Y1197953I172J102D01*
G01X1173341D01*
G03X1173515Y1198051I2J200D01*
G01X1173731Y1198414D01*
G02X1174819Y1199034I1089J-646D01*
G01X1175573D01*
G02X1176661Y1198414I-1J-1266D01*
G01X1176877Y1198051D01*
G03X1177051Y1197953I172J102D01*
G01X1177081D01*
G03X1177255Y1198051I2J200D01*
G01X1177471Y1198414D01*
G02X1178559Y1199034I1089J-646D01*
G01X1179313D01*
G02X1180401Y1198414I-1J-1266D01*
G01X1180617Y1198051D01*
G03X1180791Y1197953I172J102D01*
G01X1180821D01*
G03X1180995Y1198051I2J200D01*
G01X1181211Y1198414D01*
G02X1182299Y1199034I1089J-646D01*
G01X1183085D01*
G02X1184176Y1198407I-2J-1266D01*
G01X1184394Y1198035D01*
G03X1184567Y1197936I173J101D01*
G01X1184619D01*
X1184711Y1197989D01*
X1184956Y1198407D01*
G02X1186047Y1199034I1093J-639D01*
G01X1186794D01*
G02X1187882Y1198414I-1J-1266D01*
G01X1188098Y1198051D01*
G03X1188272Y1197953I172J102D01*
G01X1188287D01*
G02X1189465Y1196994I0J-1203D01*
G01X1189475Y1196947D01*
X1189533Y1196873D01*
X1190119Y1196602D01*
G02X1190278Y1196515I-527J-1151D01*
G01X1190323Y1196485D01*
X1190432Y1196481D01*
X1190720Y1196633D01*
G03X1190826Y1196801I-94J177D01*
G01Y1196802D01*
G02X1192027Y1197953I1201J-51D01*
G02Y1195549I0J-1202D01*
G02X1191161Y1195917I0J1203D01*
G03X1190817Y1195785I-144J-139D01*
G03X1190822Y1195733I200J-7D01*
G02X1190854Y1195454I-1234J-283D01*
G01Y1194341D01*
G03X1190956Y1194167I200J0D01*
G01X1191196Y1194032D01*
G03X1191399Y1194036I98J174D01*
G02X1192027Y1194213I628J-1026D01*
G02Y1191809I0J-1202D01*
G02X1191399Y1191986I0J1203D01*
G03X1191196Y1191990I-105J-170D01*
G01X1190956Y1191855D01*
G03X1190854Y1191681I98J-174D01*
G01Y1190601D01*
G03X1190956Y1190427I200J0D01*
G01X1191196Y1190292D01*
G03X1191399Y1190296I98J174D01*
G02X1192027Y1190473I628J-1026D01*
G02Y1188069I0J-1202D01*
G02X1191399Y1188246I0J1203D01*
G03X1191196Y1188250I-105J-170D01*
G01X1190956Y1188115D01*
G03X1190854Y1187941I98J-174D01*
G01Y1186861D01*
G03X1190956Y1186687I200J0D01*
G01X1191196Y1186552D01*
G03X1191399Y1186556I98J174D01*
G02X1192027Y1186733I628J-1026D01*
G02Y1184329I0J-1202D01*
G02X1191285Y1184586I1J1202D01*
G01X1191284D01*
G03X1191116Y1184623I-123J-158D01*
G01X1190889Y1184570D01*
G03X1190751Y1184454I46J-195D01*
G02X1190482Y1184057I-1163J499D01*
G01X1189249Y1182824D01*
G03X1189190Y1182689I141J-142D01*
G01X1189188Y1182627D01*
X1189210Y1182561D01*
X1189232Y1182533D01*
G02X1189489Y1181791I-945J-743D01*
G02X1187085I-1202J0D01*
G01Y1181793D01*
G02X1187104Y1182005I1202J-1D01*
G01X1187112Y1182049D01*
X1187089Y1182134D01*
X1186916Y1182341D01*
G03X1186763Y1182412I-153J-129D01*
G01X1184100D01*
G03X1183900Y1182212I0J-200D01*
G01Y1179571D01*
G03X1183972Y1179417I200J0D01*
G01X1184147Y1179272D01*
G03X1184313Y1179230I127J154D01*
G01X1184314D01*
G02X1184546Y1179253I234J-1179D01*
G02Y1176849I0J-1202D01*
G02X1184315Y1176872I3J1202D01*
G01X1184313D01*
G03X1184147Y1176830I-39J-196D01*
G01X1183972Y1176685D01*
G03X1183900Y1176531I128J-154D01*
G01Y1175830D01*
G03X1183972Y1175676I200J0D01*
G01X1184147Y1175531D01*
G03X1184313Y1175489I127J154D01*
G01X1184314D01*
G02X1184546Y1175512I234J-1179D01*
G02Y1173108I0J-1202D01*
G02X1184315Y1173131I3J1202D01*
G01X1184313D01*
G03X1184147Y1173089I-39J-196D01*
G01X1183972Y1172944D01*
G03X1183900Y1172790I128J-154D01*
G01Y1172090D01*
G03X1183972Y1171936I200J0D01*
G01X1184147Y1171791D01*
G03X1184313Y1171749I127J154D01*
G01X1184314D01*
G02X1184546Y1171772I234J-1179D01*
G02X1185318Y1171491I0J-1201D01*
G03X1185447Y1171444I129J153D01*
G01X1187198D01*
G02X1187320Y1171403I1J-200D01*
G01X1187419Y1171407D01*
X1187494Y1171472D01*
G02X1188287Y1171772I794J-902D01*
G02X1189059Y1171491I0J-1201D01*
G03X1189188Y1171444I129J153D01*
G01X1190938D01*
G02X1191060Y1171403I1J-200D01*
G01X1191159Y1171407D01*
X1191234Y1171472D01*
G02X1192027Y1171772I794J-902D01*
G02X1193229Y1170570I0J-1202D01*
G02X1193018Y1169891I-1203J1D01*
G03X1193033Y1169645I165J-113D01*
G01X1193060Y1169616D01*
G02X1193110Y1169483I-150J-132D01*
G01Y1167917D01*
G02X1193060Y1167784I-200J-1D01*
G01X1193033Y1167755D01*
G03X1193018Y1167509I150J-133D01*
G02Y1166151I-992J-679D01*
G03X1193033Y1165905I165J-113D01*
G01X1193060Y1165876D01*
G02X1193110Y1165743I-150J-132D01*
G01Y1160437D01*
G02X1193060Y1160304I-200J-1D01*
G01X1193033Y1160275D01*
G03X1193018Y1160029I150J-133D01*
G02Y1158671I-992J-679D01*
G03X1193033Y1158425I165J-113D01*
G01X1193060Y1158396D01*
G02X1193110Y1158263I-150J-132D01*
G01Y1156697D01*
G02X1193060Y1156564I-200J-1D01*
G01X1193033Y1156535D01*
G03X1193018Y1156289I150J-133D01*
G02Y1154931I-992J-679D01*
G03X1193033Y1154685I165J-113D01*
G01X1193060Y1154656D01*
G02X1193110Y1154523I-150J-132D01*
G01Y1152957D01*
G02X1193060Y1152824I-200J-1D01*
G01X1193033Y1152795D01*
G03X1193018Y1152549I150J-133D01*
G02Y1151191I-992J-679D01*
G03X1193033Y1150945I165J-113D01*
G01X1193060Y1150916D01*
G02X1193110Y1150783I-150J-132D01*
G01Y1149216D01*
G02X1193060Y1149083I-200J-1D01*
G01X1193033Y1149054D01*
G03X1193018Y1148808I150J-133D01*
G02Y1147450I-992J-679D01*
G03X1193033Y1147204I165J-113D01*
G01X1193060Y1147175D01*
G02X1193110Y1147042I-150J-132D01*
G01Y1145476D01*
G02X1193060Y1145343I-200J-1D01*
G01X1193033Y1145314D01*
G03X1193018Y1145068I150J-133D01*
G02Y1143710I-992J-679D01*
G03X1193033Y1143464I165J-113D01*
G01X1193060Y1143435D01*
G02X1193110Y1143302I-150J-132D01*
G01Y1141736D01*
G02X1193060Y1141603I-200J-1D01*
G01X1193033Y1141574D01*
G03X1193018Y1141328I150J-133D01*
G02Y1139970I-992J-679D01*
G03X1193033Y1139724I165J-113D01*
G01X1193060Y1139695D01*
G02X1193110Y1139562I-150J-132D01*
G01Y1137996D01*
G02X1193060Y1137863I-200J-1D01*
G01X1193033Y1137834D01*
G03X1193018Y1137588I150J-133D01*
G02X1193229Y1136909I-992J-680D01*
G02X1192027Y1135707I-1202J0D01*
G01X1192026D01*
G02X1191758Y1135737I-1J1202D01*
G03X1191560Y1135670I-44J-195D01*
G02X1191483Y1135586I-971J812D01*
G01X1190637Y1134740D01*
G03X1190635Y1134738I140J-142D01*
G01X1190488Y1134585D01*
G02X1190418Y1134538I-144J139D01*
G01X1190018Y1134377D01*
G02X1189943Y1134362I-76J185D01*
G01X1185859D01*
G02X1185536Y1134404I0J1265D01*
G03X1185351Y1134062I-51J-193D01*
G02X1185748Y1133169I-806J-893D01*
G02X1183344I-1202J0D01*
G02X1183741Y1134062I1203J0D01*
G03X1183556Y1134404I-134J149D01*
G02X1183233Y1134362I-323J1223D01*
G37*
G36*
G01X1072342Y1176748D02*
X1068602D01*
G02Y1179354I0J1303D01*
G01X1072342D01*
G02Y1176748I0J-1303D01*
G37*
G36*
G01X1057380Y1171872D02*
X1061120D01*
G02Y1169268I0J-1302D01*
G01X1057380D01*
G02X1056373Y1169744I0J1303D01*
G01X1056345Y1169778D01*
X1056268Y1169815D01*
X1055877Y1169826D01*
X1055798Y1169792D01*
X1055769Y1169760D01*
G02X1054881Y1169368I-888J810D01*
G02Y1171772I0J1202D01*
G02X1055769Y1171380I0J-1202D01*
G01X1055798Y1171348D01*
X1055877Y1171314D01*
X1056224Y1171324D01*
G03X1056373Y1171396I-5J200D01*
G02X1057380Y1171872I1007J-827D01*
G37*
G36*
G01X1093581Y1110728D02*
G02X1095985I1202J0D01*
G02X1095964Y1110506I-1202J2D01*
G01X1095955Y1110457D01*
X1095984Y1110364D01*
X1096289Y1110059D01*
X1096382Y1110030D01*
X1096431Y1110039D01*
G02X1096653Y1110060I224J-1181D01*
G02X1095451Y1108858I0J-1202D01*
G02X1095472Y1109080I1202J-2D01*
G01X1095481Y1109129D01*
X1095452Y1109222D01*
X1095147Y1109527D01*
X1095054Y1109556D01*
X1095005Y1109547D01*
G02X1094783Y1109526I-224J1181D01*
G02X1094561Y1109547I2J1202D01*
G01X1094512Y1109556D01*
X1094419Y1109527D01*
X1094114Y1109222D01*
X1094085Y1109129D01*
X1094094Y1109080D01*
G02X1094115Y1108858I-1181J-224D01*
G02X1091711I-1202J0D01*
G02X1091732Y1109080I1202J-2D01*
G01X1091741Y1109129D01*
X1091712Y1109222D01*
X1091407Y1109527D01*
X1091314Y1109556D01*
X1091265Y1109547D01*
G02X1091043Y1109526I-224J1181D01*
G02X1090820Y1109547I1J1202D01*
G01X1090771Y1109556D01*
X1090678Y1109527D01*
X1090408Y1109258D01*
G03X1090353Y1109081I142J-141D01*
G01Y1109080D01*
G02X1090374Y1108858I-1181J-224D01*
G02X1089172Y1107656I-1202J0D01*
G02X1088950Y1107677I2J1202D01*
G01X1088901Y1107686D01*
X1088808Y1107657D01*
X1088503Y1107352D01*
X1088474Y1107259D01*
X1088483Y1107210D01*
G02X1088504Y1106988I-1181J-224D01*
G02X1088483Y1106765I-1202J1D01*
G01X1088474Y1106716D01*
X1088503Y1106623D01*
X1088772Y1106353D01*
G03X1088949Y1106298I141J142D01*
G01X1088950D01*
G02X1089172Y1106319I224J-1181D01*
G02X1087970Y1105117I0J-1202D01*
G02X1087991Y1105340I1202J-1D01*
G01X1088000Y1105389D01*
X1087971Y1105482D01*
X1087702Y1105752D01*
G03X1087525Y1105807I-141J-142D01*
G01X1087524D01*
G02X1087302Y1105786I-224J1181D01*
G02Y1108190I0J1202D01*
G02X1087524Y1108169I-2J-1202D01*
G01X1087573Y1108160D01*
X1087666Y1108189D01*
X1087971Y1108494D01*
X1088000Y1108587D01*
X1087991Y1108636D01*
G02X1087970Y1108858I1181J224D01*
G02X1087991Y1109080I1202J-2D01*
G01X1088000Y1109129D01*
X1087971Y1109222D01*
X1087666Y1109527D01*
X1087573Y1109556D01*
X1087524Y1109547D01*
G02X1087302Y1109526I-224J1181D01*
G02X1088504Y1110728I0J1202D01*
G02X1088483Y1110506I-1202J2D01*
G01X1088474Y1110457D01*
X1088503Y1110364D01*
X1088808Y1110059D01*
X1088901Y1110030D01*
X1088950Y1110039D01*
G02X1089172Y1110060I224J-1181D01*
G02X1089395Y1110039I-1J-1202D01*
G01X1089444Y1110030D01*
X1089537Y1110059D01*
X1089807Y1110328D01*
G03X1089862Y1110505I-142J141D01*
G01Y1110506D01*
G02X1089841Y1110728I1181J224D01*
G02X1092245I1202J0D01*
G02X1092224Y1110506I-1202J2D01*
G01X1092215Y1110457D01*
X1092244Y1110364D01*
X1092549Y1110059D01*
X1092642Y1110030D01*
X1092691Y1110039D01*
G02X1092913Y1110060I224J-1181D01*
G02X1093135Y1110039I-2J-1202D01*
G01X1093184Y1110030D01*
X1093277Y1110059D01*
X1093582Y1110364D01*
X1093611Y1110457D01*
X1093602Y1110506D01*
G02X1093581Y1110728I1181J224D01*
G37*
G36*
G01X1130982Y1114468D02*
G02X1132184Y1113266I1202J0D01*
G02X1131962Y1113287I2J1202D01*
G01X1131913Y1113296D01*
X1131820Y1113267D01*
X1131515Y1112962D01*
X1131486Y1112869D01*
X1131495Y1112820D01*
G02X1131516Y1112598I-1181J-224D01*
G02X1129112I-1202J0D01*
G02X1129133Y1112820I1202J-2D01*
G01X1129142Y1112869D01*
X1129113Y1112962D01*
X1128808Y1113267D01*
X1128715Y1113296D01*
X1128666Y1113287D01*
G02X1128444Y1113266I-224J1181D01*
G02X1129646Y1114468I0J1202D01*
G02X1129625Y1114246I-1202J2D01*
G01X1129616Y1114197D01*
X1129645Y1114104D01*
X1129950Y1113799D01*
X1130043Y1113770D01*
X1130092Y1113779D01*
G02X1130314Y1113800I224J-1181D01*
G02X1130536Y1113779I-2J-1202D01*
G01X1130585Y1113770D01*
X1130678Y1113799D01*
X1130983Y1114104D01*
X1131012Y1114197D01*
X1131003Y1114246D01*
G02X1130982Y1114468I1181J224D01*
G37*
G36*
G01X1205785Y1136909D02*
G02X1208189I1202J0D01*
G02X1208168Y1136688I-1202J3D01*
G01Y1136686D01*
G03X1208223Y1136509I197J-36D01*
G01X1208493Y1136240D01*
X1208586Y1136211D01*
X1208635Y1136220D01*
G02X1208858Y1136241I224J-1181D01*
G02X1207656Y1135039I0J-1202D01*
G02X1207677Y1135260I1202J-3D01*
G01Y1135262D01*
G03X1207622Y1135439I-197J36D01*
G01X1207352Y1135708D01*
X1207259Y1135737D01*
X1207210Y1135728D01*
G02X1206987Y1135707I-224J1181D01*
G02X1206765Y1135728I2J1202D01*
G01X1206716Y1135737D01*
X1206623Y1135708D01*
X1206318Y1135403D01*
X1206289Y1135310D01*
X1206298Y1135261D01*
G02X1206319Y1135039I-1181J-224D01*
G02X1205117Y1136241I-1202J0D01*
G02X1205339Y1136220I-2J-1202D01*
G01X1205388Y1136211D01*
X1205481Y1136240D01*
X1205786Y1136545D01*
X1205815Y1136638D01*
X1205806Y1136687D01*
G02X1205785Y1136909I1181J224D01*
G37*
G36*
G01X1110432Y1217100D02*
G02X1110411Y1217322I1181J224D01*
G02X1111613Y1216120I1202J0D01*
G02X1111391Y1216141I2J1202D01*
G03X1110924Y1215674I-74J-393D01*
G02X1110945Y1215452I-1181J-224D01*
G02X1109743Y1216654I-1202J0D01*
G02X1109965Y1216633I-2J-1202D01*
G03X1110432Y1217100I74J393D01*
G37*
G36*
G01X1115576Y1216141D02*
G02X1115354Y1216120I-224J1181D01*
G02X1116556Y1217322I0J1202D01*
G02X1116535Y1217100I-1202J2D01*
G03X1117002Y1216633I393J-74D01*
G02X1117224Y1216654I224J-1181D01*
G02X1116022Y1215452I0J-1202D01*
G02X1116043Y1215674I1202J-2D01*
G03X1115576Y1216141I-393J74D01*
G37*
G36*
G01X1132852Y1217322D02*
G02X1135256I1202J0D01*
G02X1135235Y1217101I-1202J3D01*
G01Y1217099D01*
G03X1135290Y1216922I197J-36D01*
G01X1135560Y1216653D01*
X1135653Y1216624D01*
X1135702Y1216633D01*
G02X1135925Y1216654I224J-1181D01*
G02X1134723Y1215452I0J-1202D01*
G02X1134744Y1215673I1202J-3D01*
G01Y1215675D01*
G03X1134689Y1215852I-197J36D01*
G01X1134419Y1216121D01*
X1134326Y1216150D01*
X1134277Y1216141D01*
G02X1134054Y1216120I-224J1181D01*
G02X1133832Y1216141I2J1202D01*
G01X1133783Y1216150D01*
X1133690Y1216121D01*
X1133385Y1215816D01*
X1133356Y1215723D01*
X1133365Y1215674D01*
G02X1133386Y1215452I-1181J-224D01*
G02X1132184Y1216654I-1202J0D01*
G02X1132406Y1216633I-2J-1202D01*
G01X1132455Y1216624D01*
X1132548Y1216653D01*
X1132853Y1216958D01*
X1132882Y1217051D01*
X1132873Y1217100D01*
G02X1132852Y1217322I1181J224D01*
G37*
G36*
G01X1155293D02*
G02X1157697I1202J0D01*
G02X1157676Y1217100I-1202J2D01*
G01X1157667Y1217051D01*
X1157696Y1216958D01*
X1158001Y1216653D01*
X1158094Y1216624D01*
X1158143Y1216633D01*
G02X1158365Y1216654I224J-1181D01*
G02X1157163Y1215452I0J-1202D01*
G02X1157184Y1215674I1202J-2D01*
G01X1157193Y1215723D01*
X1157164Y1215816D01*
X1156859Y1216121D01*
X1156766Y1216150D01*
X1156717Y1216141D01*
G02X1156495Y1216120I-224J1181D01*
G02X1156273Y1216141I2J1202D01*
G01X1156224Y1216150D01*
X1156131Y1216121D01*
X1155826Y1215816D01*
X1155797Y1215723D01*
X1155806Y1215674D01*
G02X1155827Y1215452I-1181J-224D01*
G02X1153423I-1202J0D01*
G02X1153444Y1215674I1202J-2D01*
G01X1153453Y1215723D01*
X1153424Y1215816D01*
X1153119Y1216121D01*
X1153026Y1216150D01*
X1152977Y1216141D01*
G02X1152755Y1216120I-224J1181D01*
G02X1152533Y1216141I2J1202D01*
G01X1152484Y1216150D01*
X1152391Y1216121D01*
X1152086Y1215816D01*
X1152057Y1215723D01*
X1152066Y1215674D01*
G02X1152087Y1215452I-1181J-224D01*
G02X1150885Y1216654I-1202J0D01*
G02X1151107Y1216633I-2J-1202D01*
G01X1151156Y1216624D01*
X1151249Y1216653D01*
X1151554Y1216958D01*
X1151583Y1217051D01*
X1151574Y1217100D01*
G02X1151553Y1217322I1181J224D01*
G02X1153957I1202J0D01*
G02X1153936Y1217100I-1202J2D01*
G01X1153927Y1217051D01*
X1153956Y1216958D01*
X1154261Y1216653D01*
X1154354Y1216624D01*
X1154403Y1216633D01*
G02X1154625Y1216654I224J-1181D01*
G02X1154847Y1216633I-2J-1202D01*
G01X1154896Y1216624D01*
X1154989Y1216653D01*
X1155294Y1216958D01*
X1155323Y1217051D01*
X1155314Y1217100D01*
G02X1155293Y1217322I1181J224D01*
G37*
G36*
G01X1099191Y1221062D02*
G02X1100393Y1219860I1202J0D01*
G02X1100171Y1219881I2J1202D01*
G01X1100122Y1219890D01*
X1100029Y1219861D01*
X1099724Y1219556D01*
X1099695Y1219463D01*
X1099704Y1219414D01*
G02X1099725Y1219192I-1181J-224D01*
G02X1097321I-1202J0D01*
G02X1097342Y1219414I1202J-2D01*
G01X1097351Y1219463D01*
X1097322Y1219556D01*
X1097017Y1219861D01*
X1096924Y1219890D01*
X1096875Y1219881D01*
G02X1096653Y1219860I-224J1181D01*
G02X1097855Y1221062I0J1202D01*
G02X1097834Y1220840I-1202J2D01*
G01X1097825Y1220791D01*
X1097854Y1220698D01*
X1098159Y1220393D01*
X1098252Y1220364D01*
X1098301Y1220373D01*
G02X1098523Y1220394I224J-1181D01*
G02X1098745Y1220373I-2J-1202D01*
G01X1098794Y1220364D01*
X1098887Y1220393D01*
X1099192Y1220698D01*
X1099221Y1220791D01*
X1099212Y1220840D01*
G02X1099191Y1221062I1181J224D01*
G37*
G36*
G01X1106671D02*
G02X1107873Y1219860I1202J0D01*
G02X1107651Y1219881I2J1202D01*
G01X1107602Y1219890D01*
X1107509Y1219861D01*
X1107204Y1219556D01*
X1107175Y1219463D01*
X1107184Y1219414D01*
G02X1107205Y1219192I-1181J-224D01*
G02X1104801I-1202J0D01*
G02X1104822Y1219414I1202J-2D01*
G01X1104831Y1219463D01*
X1104802Y1219556D01*
X1104497Y1219861D01*
X1104404Y1219890D01*
X1104355Y1219881D01*
G02X1104133Y1219860I-224J1181D01*
G02X1105335Y1221062I0J1202D01*
G02X1105314Y1220840I-1202J2D01*
G01X1105305Y1220791D01*
X1105334Y1220698D01*
X1105639Y1220393D01*
X1105732Y1220364D01*
X1105781Y1220373D01*
G02X1106003Y1220394I224J-1181D01*
G02X1106225Y1220373I-2J-1202D01*
G01X1106274Y1220364D01*
X1106367Y1220393D01*
X1106672Y1220698D01*
X1106701Y1220791D01*
X1106692Y1220840D01*
G02X1106671Y1221062I1181J224D01*
G37*
G36*
G01X1294313Y1124943D02*
G02X1297317I1502J0D01*
G02X1296878Y1123882I-1502J0D01*
G03X1296819Y1123735I141J-142D01*
G01X1296828Y1123445D01*
G03X1296894Y1123302I200J5D01*
G01X1296895Y1123301D01*
G02X1297395Y1122182I-1002J-1119D01*
G02X1294391I-1502J0D01*
G02X1294830Y1123243I1502J0D01*
G03X1294889Y1123390I-141J142D01*
G01X1294880Y1123680D01*
G03X1294814Y1123823I-200J-5D01*
G01X1294813Y1123824D01*
G02X1294313Y1124943I1002J1119D01*
G37*
G36*
G01X1253056Y1193415D02*
G02Y1196419I0J1502D01*
G02X1253429Y1196372I0J-1502D01*
G01X1253464Y1196363D01*
X1253537Y1196371D01*
X1253838Y1196523D01*
X1253887Y1196577D01*
X1253900Y1196611D01*
G02X1255296Y1197558I1396J-555D01*
G02Y1194554I0J-1502D01*
G02X1254923Y1194601I0J1502D01*
G01X1254888Y1194610D01*
X1254815Y1194602D01*
X1254514Y1194450D01*
X1254465Y1194396D01*
X1254452Y1194362D01*
G02X1253056Y1193415I-1396J555D01*
G37*
G36*
G01X1272968Y1227959D02*
G02X1272944Y1228226I1478J267D01*
G02X1274446Y1226724I1502J0D01*
G01X1274445D01*
G02X1274178Y1226748I0J1502D01*
G03X1273713Y1226283I-71J-394D01*
G02X1273737Y1226016I-1478J-267D01*
G02X1272235Y1227518I-1502J0D01*
G01X1272236D01*
G02X1272503Y1227494I0J-1502D01*
G03X1272968Y1227959I71J394D01*
G37*
G36*
G01X1263090Y1201265D02*
G02X1264575Y1202545I1485J-221D01*
G02Y1199541I0J-1502D01*
G02X1263662Y1199850I0J1503D01*
G03X1263023Y1199592I-243J-317D01*
G02X1261538Y1198312I-1485J221D01*
G02Y1201316I0J1502D01*
G02X1262451Y1201007I0J-1503D01*
G03X1263090Y1201265I243J317D01*
G37*
G36*
G01X1476694Y1582541D02*
Y1583667D01*
G02X1476897Y1583870I203J0D01*
G01X1479717D01*
G02X1479920Y1583667I0J-203D01*
G01Y1582541D01*
G03X1479948Y1582438I200J-1D01*
G02Y1580476I-1640J-981D01*
G03X1479920Y1580373I172J-102D01*
G01Y1577423D01*
G03X1479948Y1577320I200J-1D01*
G02Y1575358I-1640J-981D01*
G03X1479920Y1575255I172J-102D01*
G01Y1574129D01*
G02X1479717Y1573926I-203J0D01*
G01X1476897D01*
G02X1476694Y1574129I0J203D01*
G01Y1575255D01*
G03X1476666Y1575358I-200J1D01*
G02Y1577320I1640J981D01*
G03X1476694Y1577423I-172J102D01*
G01Y1580373D01*
G03X1476666Y1580476I-200J1D01*
G02Y1582438I1640J981D01*
G03X1476694Y1582541I-172J102D01*
G37*
G36*
G01X1494018D02*
Y1583667D01*
G02X1494220Y1583870I202J1D01*
G01X1497040D01*
G02X1497242Y1583667I-1J-203D01*
G01Y1582541D01*
G03X1497271Y1582438I200J1D01*
G02Y1580476I-1640J-981D01*
G03X1497242Y1580373I171J-104D01*
G01Y1577423D01*
G03X1497271Y1577320I200J1D01*
G02Y1575358I-1640J-981D01*
G03X1497242Y1575255I171J-104D01*
G01Y1574129D01*
G02X1497040Y1573926I-202J-1D01*
G01X1494220D01*
G02X1494018Y1574129I1J203D01*
G01Y1575255D01*
G03X1493989Y1575358I-200J-1D01*
G02Y1577320I1640J981D01*
G03X1494018Y1577423I-171J104D01*
G01Y1580373D01*
G03X1493989Y1580476I-200J-1D01*
G02Y1582438I1640J981D01*
G03X1494018Y1582541I-171J104D01*
G37*
G36*
G01X1511340D02*
Y1583667D01*
G02X1511543Y1583870I203J0D01*
G01X1514363D01*
G02X1514566Y1583667I0J-203D01*
G01Y1582541D01*
G03X1514594Y1582438I200J-1D01*
G02Y1580476I-1640J-981D01*
G03X1514566Y1580373I172J-102D01*
G01Y1577423D01*
G03X1514594Y1577320I200J-1D01*
G02Y1575358I-1640J-981D01*
G03X1514566Y1575255I172J-102D01*
G01Y1574129D01*
G02X1514363Y1573926I-203J0D01*
G01X1511543D01*
G02X1511340Y1574129I0J203D01*
G01Y1575255D01*
G03X1511312Y1575358I-200J1D01*
G02Y1577320I1640J981D01*
G03X1511340Y1577423I-172J102D01*
G01Y1580373D01*
G03X1511312Y1580476I-200J1D01*
G02Y1582438I1640J981D01*
G03X1511340Y1582541I-172J102D01*
G37*
G36*
G01X1528662D02*
Y1583667D01*
G02X1528865Y1583870I203J0D01*
G01X1531685D01*
G02X1531888Y1583667I0J-203D01*
G01Y1582541D01*
G03X1531916Y1582438I200J-1D01*
G02Y1580476I-1640J-981D01*
G03X1531888Y1580373I172J-102D01*
G01Y1577423D01*
G03X1531916Y1577320I200J-1D01*
G02Y1575358I-1640J-981D01*
G03X1531888Y1575255I172J-102D01*
G01Y1574129D01*
G02X1531685Y1573926I-203J0D01*
G01X1528865D01*
G02X1528662Y1574129I0J203D01*
G01Y1575255D01*
G03X1528634Y1575358I-200J1D01*
G02Y1577320I1640J981D01*
G03X1528662Y1577423I-172J102D01*
G01Y1580373D01*
G03X1528634Y1580476I-200J1D01*
G02Y1582438I1640J981D01*
G03X1528662Y1582541I-172J102D01*
G37*
G36*
G01X1485356Y1586872D02*
Y1587998D01*
G02X1485558Y1588200I202J0D01*
G01X1488378D01*
G02X1488580Y1587998I0J-202D01*
G01Y1586872D01*
G03X1488609Y1586769I200J1D01*
G02Y1584807I-1640J-981D01*
G03X1488580Y1584704I171J-104D01*
G01Y1581754D01*
G03X1488609Y1581651I200J1D01*
G02Y1579689I-1640J-981D01*
G03X1488580Y1579586I171J-104D01*
G01Y1578460D01*
G02X1488378Y1578258I-202J0D01*
G01X1485558D01*
G02X1485356Y1578460I0J202D01*
G01Y1579586D01*
G03X1485327Y1579689I-200J-1D01*
G02Y1581651I1640J981D01*
G03X1485356Y1581754I-171J104D01*
G01Y1584704D01*
G03X1485327Y1584807I-200J-1D01*
G02Y1586769I1640J981D01*
G03X1485356Y1586872I-171J104D01*
G37*
G36*
G01X1502678D02*
Y1587998D01*
G02X1502881Y1588200I203J-1D01*
G01X1505701D01*
G02X1505904Y1587998I1J-202D01*
G01Y1586872D01*
G03X1505932Y1586769I200J-1D01*
G02Y1584807I-1640J-981D01*
G03X1505904Y1584704I172J-102D01*
G01Y1581754D01*
G03X1505932Y1581651I200J-1D01*
G02Y1579689I-1640J-981D01*
G03X1505904Y1579586I172J-102D01*
G01Y1578460D01*
G02X1505701Y1578258I-203J1D01*
G01X1502881D01*
G02X1502678Y1578460I-1J202D01*
G01Y1579586D01*
G03X1502650Y1579689I-200J1D01*
G02Y1581651I1640J981D01*
G03X1502678Y1581754I-172J102D01*
G01Y1584704D01*
G03X1502650Y1584807I-200J1D01*
G02Y1586769I1640J981D01*
G03X1502678Y1586872I-172J102D01*
G37*
G36*
G01X1520002D02*
Y1587998D01*
G02X1520204Y1588200I202J0D01*
G01X1523024D01*
G02X1523226Y1587998I0J-202D01*
G01Y1586872D01*
G03X1523255Y1586769I200J1D01*
G02Y1584807I-1640J-981D01*
G03X1523226Y1584704I171J-104D01*
G01Y1581754D01*
G03X1523255Y1581651I200J1D01*
G02Y1579689I-1640J-981D01*
G03X1523226Y1579586I171J-104D01*
G01Y1578460D01*
G02X1523024Y1578258I-202J0D01*
G01X1520204D01*
G02X1520002Y1578460I0J202D01*
G01Y1579586D01*
G03X1519973Y1579689I-200J-1D01*
G02Y1581651I1640J981D01*
G03X1520002Y1581754I-171J104D01*
G01Y1584704D01*
G03X1519973Y1584807I-200J-1D01*
G02Y1586769I1640J981D01*
G03X1520002Y1586872I-171J104D01*
G37*
G36*
G01X1537324D02*
Y1587998D01*
G02X1537527Y1588200I203J-1D01*
G01X1540347D01*
G02X1540550Y1587998I1J-202D01*
G01Y1586872D01*
G03X1540578Y1586769I200J-1D01*
G02Y1584807I-1640J-981D01*
G03X1540550Y1584704I172J-102D01*
G01Y1581754D01*
G03X1540578Y1581651I200J-1D01*
G02Y1579689I-1640J-981D01*
G03X1540550Y1579586I172J-102D01*
G01Y1578460D01*
G02X1540347Y1578258I-203J1D01*
G01X1537527D01*
G02X1537324Y1578460I-1J202D01*
G01Y1579586D01*
G03X1537296Y1579689I-200J1D01*
G02Y1581651I1640J981D01*
G03X1537324Y1581754I-172J102D01*
G01Y1584704D01*
G03X1537296Y1584807I-200J1D01*
G02Y1586769I1640J981D01*
G03X1537324Y1586872I-172J102D01*
G37*
G36*
G01X1303466Y1597895D02*
Y1599021D01*
G02X1303669Y1599224I203J0D01*
G01X1306489D01*
G02X1306692Y1599021I0J-203D01*
G01Y1597895D01*
G03X1306720Y1597792I200J-1D01*
G02Y1595830I-1640J-981D01*
G03X1306692Y1595727I172J-102D01*
G01Y1592777D01*
G03X1306720Y1592674I200J-1D01*
G02Y1590712I-1640J-981D01*
G03X1306692Y1590609I172J-102D01*
G01Y1589483D01*
G02X1306489Y1589280I-203J0D01*
G01X1303669D01*
G02X1303466Y1589483I0J203D01*
G01Y1590609D01*
G03X1303438Y1590712I-200J1D01*
G02Y1592674I1640J981D01*
G03X1303466Y1592777I-172J102D01*
G01Y1595727D01*
G03X1303438Y1595830I-200J1D01*
G02Y1597792I1640J981D01*
G03X1303466Y1597895I-172J102D01*
G37*
G36*
G01X1320790D02*
Y1599021D01*
G02X1320992Y1599224I202J1D01*
G01X1323812D01*
G02X1324014Y1599021I-1J-203D01*
G01Y1597895D01*
G03X1324043Y1597792I200J1D01*
G02Y1595830I-1640J-981D01*
G03X1324014Y1595727I171J-104D01*
G01Y1592777D01*
G03X1324043Y1592674I200J1D01*
G02Y1590712I-1640J-981D01*
G03X1324014Y1590609I171J-104D01*
G01Y1589483D01*
G02X1323812Y1589280I-202J-1D01*
G01X1320992D01*
G02X1320790Y1589483I1J203D01*
G01Y1590609D01*
G03X1320761Y1590712I-200J-1D01*
G02Y1592674I1640J981D01*
G03X1320790Y1592777I-171J104D01*
G01Y1595727D01*
G03X1320761Y1595830I-200J-1D01*
G02Y1597792I1640J981D01*
G03X1320790Y1597895I-171J104D01*
G37*
G36*
G01X1338112D02*
Y1599021D01*
G02X1338315Y1599224I203J0D01*
G01X1341135D01*
G02X1341338Y1599021I0J-203D01*
G01Y1597895D01*
G03X1341366Y1597792I200J-1D01*
G02Y1595830I-1640J-981D01*
G03X1341338Y1595727I172J-102D01*
G01Y1592777D01*
G03X1341366Y1592674I200J-1D01*
G02Y1590712I-1640J-981D01*
G03X1341338Y1590609I172J-102D01*
G01Y1589483D01*
G02X1341135Y1589280I-203J0D01*
G01X1338315D01*
G02X1338112Y1589483I0J203D01*
G01Y1590609D01*
G03X1338084Y1590712I-200J1D01*
G02Y1592674I1640J981D01*
G03X1338112Y1592777I-172J102D01*
G01Y1595727D01*
G03X1338084Y1595830I-200J1D01*
G02Y1597792I1640J981D01*
G03X1338112Y1597895I-172J102D01*
G37*
G36*
G01X1355434D02*
Y1599021D01*
G02X1355637Y1599224I203J0D01*
G01X1358457D01*
G02X1358660Y1599021I0J-203D01*
G01Y1597895D01*
G03X1358688Y1597792I200J-1D01*
G02Y1595830I-1640J-981D01*
G03X1358660Y1595727I172J-102D01*
G01Y1592777D01*
G03X1358688Y1592674I200J-1D01*
G02Y1590712I-1640J-981D01*
G03X1358660Y1590609I172J-102D01*
G01Y1589483D01*
G02X1358457Y1589280I-203J0D01*
G01X1355637D01*
G02X1355434Y1589483I0J203D01*
G01Y1590609D01*
G03X1355406Y1590712I-200J1D01*
G02Y1592674I1640J981D01*
G03X1355434Y1592777I-172J102D01*
G01Y1595727D01*
G03X1355406Y1595830I-200J1D01*
G02Y1597792I1640J981D01*
G03X1355434Y1597895I-172J102D01*
G37*
G36*
G01X1476694D02*
Y1599021D01*
G02X1476897Y1599224I203J0D01*
G01X1479717D01*
G02X1479920Y1599021I0J-203D01*
G01Y1597895D01*
G03X1479948Y1597792I200J-1D01*
G02Y1595830I-1640J-981D01*
G03X1479920Y1595727I172J-102D01*
G01Y1592777D01*
G03X1479948Y1592674I200J-1D01*
G02Y1590712I-1640J-981D01*
G03X1479920Y1590609I172J-102D01*
G01Y1589483D01*
G02X1479717Y1589280I-203J0D01*
G01X1476897D01*
G02X1476694Y1589483I0J203D01*
G01Y1590609D01*
G03X1476666Y1590712I-200J1D01*
G02Y1592674I1640J981D01*
G03X1476694Y1592777I-172J102D01*
G01Y1595727D01*
G03X1476666Y1595830I-200J1D01*
G02Y1597792I1640J981D01*
G03X1476694Y1597895I-172J102D01*
G37*
G36*
G01X1494018D02*
Y1599021D01*
G02X1494220Y1599224I202J1D01*
G01X1497040D01*
G02X1497242Y1599021I-1J-203D01*
G01Y1597895D01*
G03X1497271Y1597792I200J1D01*
G02Y1595830I-1640J-981D01*
G03X1497242Y1595727I171J-104D01*
G01Y1592777D01*
G03X1497271Y1592674I200J1D01*
G02Y1590712I-1640J-981D01*
G03X1497242Y1590609I171J-104D01*
G01Y1589483D01*
G02X1497040Y1589280I-202J-1D01*
G01X1494220D01*
G02X1494018Y1589483I1J203D01*
G01Y1590609D01*
G03X1493989Y1590712I-200J-1D01*
G02Y1592674I1640J981D01*
G03X1494018Y1592777I-171J104D01*
G01Y1595727D01*
G03X1493989Y1595830I-200J-1D01*
G02Y1597792I1640J981D01*
G03X1494018Y1597895I-171J104D01*
G37*
G36*
G01X1511340D02*
Y1599021D01*
G02X1511543Y1599224I203J0D01*
G01X1514363D01*
G02X1514566Y1599021I0J-203D01*
G01Y1597895D01*
G03X1514594Y1597792I200J-1D01*
G02Y1595830I-1640J-981D01*
G03X1514566Y1595727I172J-102D01*
G01Y1592777D01*
G03X1514594Y1592674I200J-1D01*
G02Y1590712I-1640J-981D01*
G03X1514566Y1590609I172J-102D01*
G01Y1589483D01*
G02X1514363Y1589280I-203J0D01*
G01X1511543D01*
G02X1511340Y1589483I0J203D01*
G01Y1590609D01*
G03X1511312Y1590712I-200J1D01*
G02Y1592674I1640J981D01*
G03X1511340Y1592777I-172J102D01*
G01Y1595727D01*
G03X1511312Y1595830I-200J1D01*
G02Y1597792I1640J981D01*
G03X1511340Y1597895I-172J102D01*
G37*
G36*
G01X1528662D02*
Y1599021D01*
G02X1528865Y1599224I203J0D01*
G01X1531685D01*
G02X1531888Y1599021I0J-203D01*
G01Y1597895D01*
G03X1531916Y1597792I200J-1D01*
G02Y1595830I-1640J-981D01*
G03X1531888Y1595727I172J-102D01*
G01Y1592777D01*
G03X1531916Y1592674I200J-1D01*
G02Y1590712I-1640J-981D01*
G03X1531888Y1590609I172J-102D01*
G01Y1589483D01*
G02X1531685Y1589280I-203J0D01*
G01X1528865D01*
G02X1528662Y1589483I0J203D01*
G01Y1590609D01*
G03X1528634Y1590712I-200J1D01*
G02Y1592674I1640J981D01*
G03X1528662Y1592777I-172J102D01*
G01Y1595727D01*
G03X1528634Y1595830I-200J1D01*
G02Y1597792I1640J981D01*
G03X1528662Y1597895I-172J102D01*
G37*
G36*
G01X1312128Y1602226D02*
Y1603352D01*
G02X1312330Y1603554I202J0D01*
G01X1315150D01*
G02X1315352Y1603352I0J-202D01*
G01Y1602226D01*
G03X1315381Y1602123I200J1D01*
G02Y1600161I-1640J-981D01*
G03X1315352Y1600058I171J-104D01*
G01Y1597108D01*
G03X1315381Y1597005I200J1D01*
G02Y1595043I-1640J-981D01*
G03X1315352Y1594940I171J-104D01*
G01Y1593814D01*
G02X1315150Y1593612I-202J0D01*
G01X1312330D01*
G02X1312128Y1593814I0J202D01*
G01Y1594940D01*
G03X1312099Y1595043I-200J-1D01*
G02Y1597005I1640J981D01*
G03X1312128Y1597108I-171J104D01*
G01Y1600058D01*
G03X1312099Y1600161I-200J-1D01*
G02Y1602123I1640J981D01*
G03X1312128Y1602226I-171J104D01*
G37*
G36*
G01X1329450D02*
Y1603352D01*
G02X1329653Y1603554I203J-1D01*
G01X1332473D01*
G02X1332676Y1603352I1J-202D01*
G01Y1602226D01*
G03X1332704Y1602123I200J-1D01*
G02Y1600161I-1640J-981D01*
G03X1332676Y1600058I172J-102D01*
G01Y1597108D01*
G03X1332704Y1597005I200J-1D01*
G02Y1595043I-1640J-981D01*
G03X1332676Y1594940I172J-102D01*
G01Y1593814D01*
G02X1332473Y1593612I-203J1D01*
G01X1329653D01*
G02X1329450Y1593814I-1J202D01*
G01Y1594940D01*
G03X1329422Y1595043I-200J1D01*
G02Y1597005I1640J981D01*
G03X1329450Y1597108I-172J102D01*
G01Y1600058D01*
G03X1329422Y1600161I-200J1D01*
G02Y1602123I1640J981D01*
G03X1329450Y1602226I-172J102D01*
G37*
G36*
G01X1346774D02*
Y1603352D01*
G02X1346976Y1603554I202J0D01*
G01X1349796D01*
G02X1349998Y1603352I0J-202D01*
G01Y1602226D01*
G03X1350027Y1602123I200J1D01*
G02Y1600161I-1640J-981D01*
G03X1349998Y1600058I171J-104D01*
G01Y1597108D01*
G03X1350027Y1597005I200J1D01*
G02Y1595043I-1640J-981D01*
G03X1349998Y1594940I171J-104D01*
G01Y1593814D01*
G02X1349796Y1593612I-202J0D01*
G01X1346976D01*
G02X1346774Y1593814I0J202D01*
G01Y1594940D01*
G03X1346745Y1595043I-200J-1D01*
G02Y1597005I1640J981D01*
G03X1346774Y1597108I-171J104D01*
G01Y1600058D01*
G03X1346745Y1600161I-200J-1D01*
G02Y1602123I1640J981D01*
G03X1346774Y1602226I-171J104D01*
G37*
G36*
G01X1364096D02*
Y1603352D01*
G02X1364299Y1603554I203J-1D01*
G01X1367119D01*
G02X1367322Y1603352I1J-202D01*
G01Y1602226D01*
G03X1367350Y1602123I200J-1D01*
G02Y1600161I-1640J-981D01*
G03X1367322Y1600058I172J-102D01*
G01Y1597108D01*
G03X1367350Y1597005I200J-1D01*
G02Y1595043I-1640J-981D01*
G03X1367322Y1594940I172J-102D01*
G01Y1593814D01*
G02X1367119Y1593612I-203J1D01*
G01X1364299D01*
G02X1364096Y1593814I-1J202D01*
G01Y1594940D01*
G03X1364068Y1595043I-200J1D01*
G02Y1597005I1640J981D01*
G03X1364096Y1597108I-172J102D01*
G01Y1600058D01*
G03X1364068Y1600161I-200J1D01*
G02Y1602123I1640J981D01*
G03X1364096Y1602226I-172J102D01*
G37*
G36*
G01X1485356D02*
Y1603352D01*
G02X1485558Y1603554I202J0D01*
G01X1488378D01*
G02X1488580Y1603352I0J-202D01*
G01Y1602226D01*
G03X1488609Y1602123I200J1D01*
G02Y1600161I-1640J-981D01*
G03X1488580Y1600058I171J-104D01*
G01Y1597108D01*
G03X1488609Y1597005I200J1D01*
G02Y1595043I-1640J-981D01*
G03X1488580Y1594940I171J-104D01*
G01Y1593814D01*
G02X1488378Y1593612I-202J0D01*
G01X1485558D01*
G02X1485356Y1593814I0J202D01*
G01Y1594940D01*
G03X1485327Y1595043I-200J-1D01*
G02Y1597005I1640J981D01*
G03X1485356Y1597108I-171J104D01*
G01Y1600058D01*
G03X1485327Y1600161I-200J-1D01*
G02Y1602123I1640J981D01*
G03X1485356Y1602226I-171J104D01*
G37*
G36*
G01X1502678D02*
Y1603352D01*
G02X1502881Y1603554I203J-1D01*
G01X1505701D01*
G02X1505904Y1603352I1J-202D01*
G01Y1602226D01*
G03X1505932Y1602123I200J-1D01*
G02Y1600161I-1640J-981D01*
G03X1505904Y1600058I172J-102D01*
G01Y1597108D01*
G03X1505932Y1597005I200J-1D01*
G02Y1595043I-1640J-981D01*
G03X1505904Y1594940I172J-102D01*
G01Y1593814D01*
G02X1505701Y1593612I-203J1D01*
G01X1502881D01*
G02X1502678Y1593814I-1J202D01*
G01Y1594940D01*
G03X1502650Y1595043I-200J1D01*
G02Y1597005I1640J981D01*
G03X1502678Y1597108I-172J102D01*
G01Y1600058D01*
G03X1502650Y1600161I-200J1D01*
G02Y1602123I1640J981D01*
G03X1502678Y1602226I-172J102D01*
G37*
G36*
G01X1520002D02*
Y1603352D01*
G02X1520204Y1603554I202J0D01*
G01X1523024D01*
G02X1523226Y1603352I0J-202D01*
G01Y1602226D01*
G03X1523255Y1602123I200J1D01*
G02Y1600161I-1640J-981D01*
G03X1523226Y1600058I171J-104D01*
G01Y1597108D01*
G03X1523255Y1597005I200J1D01*
G02Y1595043I-1640J-981D01*
G03X1523226Y1594940I171J-104D01*
G01Y1593814D01*
G02X1523024Y1593612I-202J0D01*
G01X1520204D01*
G02X1520002Y1593814I0J202D01*
G01Y1594940D01*
G03X1519973Y1595043I-200J-1D01*
G02Y1597005I1640J981D01*
G03X1520002Y1597108I-171J104D01*
G01Y1600058D01*
G03X1519973Y1600161I-200J-1D01*
G02Y1602123I1640J981D01*
G03X1520002Y1602226I-171J104D01*
G37*
G36*
G01X1537324D02*
Y1603352D01*
G02X1537527Y1603554I203J-1D01*
G01X1540347D01*
G02X1540550Y1603352I1J-202D01*
G01Y1602226D01*
G03X1540578Y1602123I200J-1D01*
G02Y1600161I-1640J-981D01*
G03X1540550Y1600058I172J-102D01*
G01Y1597108D01*
G03X1540578Y1597005I200J-1D01*
G02Y1595043I-1640J-981D01*
G03X1540550Y1594940I172J-102D01*
G01Y1593814D01*
G02X1540347Y1593612I-203J1D01*
G01X1537527D01*
G02X1537324Y1593814I-1J202D01*
G01Y1594940D01*
G03X1537296Y1595043I-200J1D01*
G02Y1597005I1640J981D01*
G03X1537324Y1597108I-172J102D01*
G01Y1600058D01*
G03X1537296Y1600161I-200J1D01*
G02Y1602123I1640J981D01*
G03X1537324Y1602226I-172J102D01*
G37*
G36*
G01X1303466Y1613250D02*
Y1614376D01*
G02X1303669Y1614578I203J-1D01*
G01X1306489D01*
G02X1306692Y1614376I1J-202D01*
G01Y1613250D01*
G03X1306720Y1613147I200J-1D01*
G02Y1611185I-1640J-981D01*
G03X1306692Y1611082I172J-102D01*
G01Y1608132D01*
G03X1306720Y1608029I200J-1D01*
G02Y1606067I-1640J-981D01*
G03X1306692Y1605964I172J-102D01*
G01Y1604838D01*
G02X1306489Y1604636I-203J1D01*
G01X1303669D01*
G02X1303466Y1604838I-1J202D01*
G01Y1605964D01*
G03X1303438Y1606067I-200J1D01*
G02Y1608029I1640J981D01*
G03X1303466Y1608132I-172J102D01*
G01Y1611082D01*
G03X1303438Y1611185I-200J1D01*
G02Y1613147I1640J981D01*
G03X1303466Y1613250I-172J102D01*
G37*
G36*
G01X1320790D02*
Y1614376D01*
G02X1320992Y1614578I202J0D01*
G01X1323812D01*
G02X1324014Y1614376I0J-202D01*
G01Y1613250D01*
G03X1324043Y1613147I200J1D01*
G02Y1611185I-1640J-981D01*
G03X1324014Y1611082I171J-104D01*
G01Y1608132D01*
G03X1324043Y1608029I200J1D01*
G02Y1606067I-1640J-981D01*
G03X1324014Y1605964I171J-104D01*
G01Y1604838D01*
G02X1323812Y1604636I-202J0D01*
G01X1320992D01*
G02X1320790Y1604838I0J202D01*
G01Y1605964D01*
G03X1320761Y1606067I-200J-1D01*
G02Y1608029I1640J981D01*
G03X1320790Y1608132I-171J104D01*
G01Y1611082D01*
G03X1320761Y1611185I-200J-1D01*
G02Y1613147I1640J981D01*
G03X1320790Y1613250I-171J104D01*
G37*
G36*
G01X1338112D02*
Y1614376D01*
G02X1338315Y1614578I203J-1D01*
G01X1341135D01*
G02X1341338Y1614376I1J-202D01*
G01Y1613250D01*
G03X1341366Y1613147I200J-1D01*
G02Y1611185I-1640J-981D01*
G03X1341338Y1611082I172J-102D01*
G01Y1608132D01*
G03X1341366Y1608029I200J-1D01*
G02Y1606067I-1640J-981D01*
G03X1341338Y1605964I172J-102D01*
G01Y1604838D01*
G02X1341135Y1604636I-203J1D01*
G01X1338315D01*
G02X1338112Y1604838I-1J202D01*
G01Y1605964D01*
G03X1338084Y1606067I-200J1D01*
G02Y1608029I1640J981D01*
G03X1338112Y1608132I-172J102D01*
G01Y1611082D01*
G03X1338084Y1611185I-200J1D01*
G02Y1613147I1640J981D01*
G03X1338112Y1613250I-172J102D01*
G37*
G36*
G01X1355434D02*
Y1614376D01*
G02X1355637Y1614578I203J-1D01*
G01X1358457D01*
G02X1358660Y1614376I1J-202D01*
G01Y1613250D01*
G03X1358688Y1613147I200J-1D01*
G02Y1611185I-1640J-981D01*
G03X1358660Y1611082I172J-102D01*
G01Y1608132D01*
G03X1358688Y1608029I200J-1D01*
G02Y1606067I-1640J-981D01*
G03X1358660Y1605964I172J-102D01*
G01Y1604838D01*
G02X1358457Y1604636I-203J1D01*
G01X1355637D01*
G02X1355434Y1604838I-1J202D01*
G01Y1605964D01*
G03X1355406Y1606067I-200J1D01*
G02Y1608029I1640J981D01*
G03X1355434Y1608132I-172J102D01*
G01Y1611082D01*
G03X1355406Y1611185I-200J1D01*
G02Y1613147I1640J981D01*
G03X1355434Y1613250I-172J102D01*
G37*
G36*
G01X1476694D02*
Y1614376D01*
G02X1476897Y1614578I203J-1D01*
G01X1479717D01*
G02X1479920Y1614376I1J-202D01*
G01Y1613250D01*
G03X1479948Y1613147I200J-1D01*
G02Y1611185I-1640J-981D01*
G03X1479920Y1611082I172J-102D01*
G01Y1608132D01*
G03X1479948Y1608029I200J-1D01*
G02Y1606067I-1640J-981D01*
G03X1479920Y1605964I172J-102D01*
G01Y1604838D01*
G02X1479717Y1604636I-203J1D01*
G01X1476897D01*
G02X1476694Y1604838I-1J202D01*
G01Y1605964D01*
G03X1476666Y1606067I-200J1D01*
G02Y1608029I1640J981D01*
G03X1476694Y1608132I-172J102D01*
G01Y1611082D01*
G03X1476666Y1611185I-200J1D01*
G02Y1613147I1640J981D01*
G03X1476694Y1613250I-172J102D01*
G37*
G36*
G01X1494018D02*
Y1614376D01*
G02X1494220Y1614578I202J0D01*
G01X1497040D01*
G02X1497242Y1614376I0J-202D01*
G01Y1613250D01*
G03X1497271Y1613147I200J1D01*
G02Y1611185I-1640J-981D01*
G03X1497242Y1611082I171J-104D01*
G01Y1608132D01*
G03X1497271Y1608029I200J1D01*
G02Y1606067I-1640J-981D01*
G03X1497242Y1605964I171J-104D01*
G01Y1604838D01*
G02X1497040Y1604636I-202J0D01*
G01X1494220D01*
G02X1494018Y1604838I0J202D01*
G01Y1605964D01*
G03X1493989Y1606067I-200J-1D01*
G02Y1608029I1640J981D01*
G03X1494018Y1608132I-171J104D01*
G01Y1611082D01*
G03X1493989Y1611185I-200J-1D01*
G02Y1613147I1640J981D01*
G03X1494018Y1613250I-171J104D01*
G37*
G36*
G01X1511340D02*
Y1614376D01*
G02X1511543Y1614578I203J-1D01*
G01X1514363D01*
G02X1514566Y1614376I1J-202D01*
G01Y1613250D01*
G03X1514594Y1613147I200J-1D01*
G02Y1611185I-1640J-981D01*
G03X1514566Y1611082I172J-102D01*
G01Y1608132D01*
G03X1514594Y1608029I200J-1D01*
G02Y1606067I-1640J-981D01*
G03X1514566Y1605964I172J-102D01*
G01Y1604838D01*
G02X1514363Y1604636I-203J1D01*
G01X1511543D01*
G02X1511340Y1604838I-1J202D01*
G01Y1605964D01*
G03X1511312Y1606067I-200J1D01*
G02Y1608029I1640J981D01*
G03X1511340Y1608132I-172J102D01*
G01Y1611082D01*
G03X1511312Y1611185I-200J1D01*
G02Y1613147I1640J981D01*
G03X1511340Y1613250I-172J102D01*
G37*
G36*
G01X1528662D02*
Y1614376D01*
G02X1528865Y1614578I203J-1D01*
G01X1531685D01*
G02X1531888Y1614376I1J-202D01*
G01Y1613250D01*
G03X1531916Y1613147I200J-1D01*
G02Y1611185I-1640J-981D01*
G03X1531888Y1611082I172J-102D01*
G01Y1608132D01*
G03X1531916Y1608029I200J-1D01*
G02Y1606067I-1640J-981D01*
G03X1531888Y1605964I172J-102D01*
G01Y1604838D01*
G02X1531685Y1604636I-203J1D01*
G01X1528865D01*
G02X1528662Y1604838I-1J202D01*
G01Y1605964D01*
G03X1528634Y1606067I-200J1D01*
G02Y1608029I1640J981D01*
G03X1528662Y1608132I-172J102D01*
G01Y1611082D01*
G03X1528634Y1611185I-200J1D01*
G02Y1613147I1640J981D01*
G03X1528662Y1613250I-172J102D01*
G37*
G36*
G01X1649922D02*
Y1614376D01*
G02X1650125Y1614578I203J-1D01*
G01X1652945D01*
G02X1653148Y1614376I1J-202D01*
G01Y1613250D01*
G03X1653176Y1613147I200J-1D01*
G02Y1611185I-1640J-981D01*
G03X1653148Y1611082I172J-102D01*
G01Y1608132D01*
G03X1653176Y1608029I200J-1D01*
G02Y1606067I-1640J-981D01*
G03X1653148Y1605964I172J-102D01*
G01Y1604838D01*
G02X1652945Y1604636I-203J1D01*
G01X1650125D01*
G02X1649922Y1604838I-1J202D01*
G01Y1605964D01*
G03X1649894Y1606067I-200J1D01*
G02Y1608029I1640J981D01*
G03X1649922Y1608132I-172J102D01*
G01Y1611082D01*
G03X1649894Y1611185I-200J1D01*
G02Y1613147I1640J981D01*
G03X1649922Y1613250I-172J102D01*
G37*
G36*
G01X1667246D02*
Y1614376D01*
G02X1667448Y1614578I202J0D01*
G01X1670268D01*
G02X1670470Y1614376I0J-202D01*
G01Y1613250D01*
G03X1670499Y1613147I200J1D01*
G02Y1611185I-1640J-981D01*
G03X1670470Y1611082I171J-104D01*
G01Y1608132D01*
G03X1670499Y1608029I200J1D01*
G02Y1606067I-1640J-981D01*
G03X1670470Y1605964I171J-104D01*
G01Y1604838D01*
G02X1670268Y1604636I-202J0D01*
G01X1667448D01*
G02X1667246Y1604838I0J202D01*
G01Y1605964D01*
G03X1667217Y1606067I-200J-1D01*
G02Y1608029I1640J981D01*
G03X1667246Y1608132I-171J104D01*
G01Y1611082D01*
G03X1667217Y1611185I-200J-1D01*
G02Y1613147I1640J981D01*
G03X1667246Y1613250I-171J104D01*
G37*
G36*
G01X1684568D02*
Y1614376D01*
G02X1684771Y1614578I203J-1D01*
G01X1687591D01*
G02X1687794Y1614376I1J-202D01*
G01Y1613250D01*
G03X1687822Y1613147I200J-1D01*
G02Y1611185I-1640J-981D01*
G03X1687794Y1611082I172J-102D01*
G01Y1608132D01*
G03X1687822Y1608029I200J-1D01*
G02Y1606067I-1640J-981D01*
G03X1687794Y1605964I172J-102D01*
G01Y1604838D01*
G02X1687591Y1604636I-203J1D01*
G01X1684771D01*
G02X1684568Y1604838I-1J202D01*
G01Y1605964D01*
G03X1684540Y1606067I-200J1D01*
G02Y1608029I1640J981D01*
G03X1684568Y1608132I-172J102D01*
G01Y1611082D01*
G03X1684540Y1611185I-200J1D01*
G02Y1613147I1640J981D01*
G03X1684568Y1613250I-172J102D01*
G37*
G36*
G01X1701890D02*
Y1614376D01*
G02X1702093Y1614578I203J-1D01*
G01X1704913D01*
G02X1705116Y1614376I1J-202D01*
G01Y1613250D01*
G03X1705144Y1613147I200J-1D01*
G02Y1611185I-1640J-981D01*
G03X1705116Y1611082I172J-102D01*
G01Y1608132D01*
G03X1705144Y1608029I200J-1D01*
G02Y1606067I-1640J-981D01*
G03X1705116Y1605964I172J-102D01*
G01Y1604838D01*
G02X1704913Y1604636I-203J1D01*
G01X1702093D01*
G02X1701890Y1604838I-1J202D01*
G01Y1605964D01*
G03X1701862Y1606067I-200J1D01*
G02Y1608029I1640J981D01*
G03X1701890Y1608132I-172J102D01*
G01Y1611082D01*
G03X1701862Y1611185I-200J1D01*
G02Y1613147I1640J981D01*
G03X1701890Y1613250I-172J102D01*
G37*
G36*
G01X1312128Y1617580D02*
Y1618706D01*
G02X1312330Y1618908I202J0D01*
G01X1315150D01*
G02X1315352Y1618706I0J-202D01*
G01Y1617580D01*
G03X1315381Y1617477I200J1D01*
G02Y1615515I-1640J-981D01*
G03X1315352Y1615412I171J-104D01*
G01Y1612462D01*
G03X1315381Y1612359I200J1D01*
G02Y1610397I-1640J-981D01*
G03X1315352Y1610294I171J-104D01*
G01Y1609168D01*
G02X1315150Y1608966I-202J0D01*
G01X1312330D01*
G02X1312128Y1609168I0J202D01*
G01Y1610294D01*
G03X1312099Y1610397I-200J-1D01*
G02Y1612359I1640J981D01*
G03X1312128Y1612462I-171J104D01*
G01Y1615412D01*
G03X1312099Y1615515I-200J-1D01*
G02Y1617477I1640J981D01*
G03X1312128Y1617580I-171J104D01*
G37*
G36*
G01X1329450D02*
Y1618706D01*
G02X1329653Y1618908I203J-1D01*
G01X1332473D01*
G02X1332676Y1618706I1J-202D01*
G01Y1617580D01*
G03X1332704Y1617477I200J-1D01*
G02Y1615515I-1640J-981D01*
G03X1332676Y1615412I172J-102D01*
G01Y1612462D01*
G03X1332704Y1612359I200J-1D01*
G02Y1610397I-1640J-981D01*
G03X1332676Y1610294I172J-102D01*
G01Y1609168D01*
G02X1332473Y1608966I-203J1D01*
G01X1329653D01*
G02X1329450Y1609168I-1J202D01*
G01Y1610294D01*
G03X1329422Y1610397I-200J1D01*
G02Y1612359I1640J981D01*
G03X1329450Y1612462I-172J102D01*
G01Y1615412D01*
G03X1329422Y1615515I-200J1D01*
G02Y1617477I1640J981D01*
G03X1329450Y1617580I-172J102D01*
G37*
G36*
G01X1346774D02*
Y1618706D01*
G02X1346976Y1618908I202J0D01*
G01X1349796D01*
G02X1349998Y1618706I0J-202D01*
G01Y1617580D01*
G03X1350027Y1617477I200J1D01*
G02Y1615515I-1640J-981D01*
G03X1349998Y1615412I171J-104D01*
G01Y1612462D01*
G03X1350027Y1612359I200J1D01*
G02Y1610397I-1640J-981D01*
G03X1349998Y1610294I171J-104D01*
G01Y1609168D01*
G02X1349796Y1608966I-202J0D01*
G01X1346976D01*
G02X1346774Y1609168I0J202D01*
G01Y1610294D01*
G03X1346745Y1610397I-200J-1D01*
G02Y1612359I1640J981D01*
G03X1346774Y1612462I-171J104D01*
G01Y1615412D01*
G03X1346745Y1615515I-200J-1D01*
G02Y1617477I1640J981D01*
G03X1346774Y1617580I-171J104D01*
G37*
G36*
G01X1364096D02*
Y1618706D01*
G02X1364299Y1618908I203J-1D01*
G01X1367119D01*
G02X1367322Y1618706I1J-202D01*
G01Y1617580D01*
G03X1367350Y1617477I200J-1D01*
G02Y1615515I-1640J-981D01*
G03X1367322Y1615412I172J-102D01*
G01Y1612462D01*
G03X1367350Y1612359I200J-1D01*
G02Y1610397I-1640J-981D01*
G03X1367322Y1610294I172J-102D01*
G01Y1609168D01*
G02X1367119Y1608966I-203J1D01*
G01X1364299D01*
G02X1364096Y1609168I-1J202D01*
G01Y1610294D01*
G03X1364068Y1610397I-200J1D01*
G02Y1612359I1640J981D01*
G03X1364096Y1612462I-172J102D01*
G01Y1615412D01*
G03X1364068Y1615515I-200J1D01*
G02Y1617477I1640J981D01*
G03X1364096Y1617580I-172J102D01*
G37*
G36*
G01X1485356D02*
Y1618706D01*
G02X1485558Y1618908I202J0D01*
G01X1488378D01*
G02X1488580Y1618706I0J-202D01*
G01Y1617580D01*
G03X1488609Y1617477I200J1D01*
G02Y1615515I-1640J-981D01*
G03X1488580Y1615412I171J-104D01*
G01Y1612462D01*
G03X1488609Y1612359I200J1D01*
G02Y1610397I-1640J-981D01*
G03X1488580Y1610294I171J-104D01*
G01Y1609168D01*
G02X1488378Y1608966I-202J0D01*
G01X1485558D01*
G02X1485356Y1609168I0J202D01*
G01Y1610294D01*
G03X1485327Y1610397I-200J-1D01*
G02Y1612359I1640J981D01*
G03X1485356Y1612462I-171J104D01*
G01Y1615412D01*
G03X1485327Y1615515I-200J-1D01*
G02Y1617477I1640J981D01*
G03X1485356Y1617580I-171J104D01*
G37*
G36*
G01X1502678D02*
Y1618706D01*
G02X1502881Y1618908I203J-1D01*
G01X1505701D01*
G02X1505904Y1618706I1J-202D01*
G01Y1617580D01*
G03X1505932Y1617477I200J-1D01*
G02Y1615515I-1640J-981D01*
G03X1505904Y1615412I172J-102D01*
G01Y1612462D01*
G03X1505932Y1612359I200J-1D01*
G02Y1610397I-1640J-981D01*
G03X1505904Y1610294I172J-102D01*
G01Y1609168D01*
G02X1505701Y1608966I-203J1D01*
G01X1502881D01*
G02X1502678Y1609168I-1J202D01*
G01Y1610294D01*
G03X1502650Y1610397I-200J1D01*
G02Y1612359I1640J981D01*
G03X1502678Y1612462I-172J102D01*
G01Y1615412D01*
G03X1502650Y1615515I-200J1D01*
G02Y1617477I1640J981D01*
G03X1502678Y1617580I-172J102D01*
G37*
G36*
G01X1520002D02*
Y1618706D01*
G02X1520204Y1618908I202J0D01*
G01X1523024D01*
G02X1523226Y1618706I0J-202D01*
G01Y1617580D01*
G03X1523255Y1617477I200J1D01*
G02Y1615515I-1640J-981D01*
G03X1523226Y1615412I171J-104D01*
G01Y1612462D01*
G03X1523255Y1612359I200J1D01*
G02Y1610397I-1640J-981D01*
G03X1523226Y1610294I171J-104D01*
G01Y1609168D01*
G02X1523024Y1608966I-202J0D01*
G01X1520204D01*
G02X1520002Y1609168I0J202D01*
G01Y1610294D01*
G03X1519973Y1610397I-200J-1D01*
G02Y1612359I1640J981D01*
G03X1520002Y1612462I-171J104D01*
G01Y1615412D01*
G03X1519973Y1615515I-200J-1D01*
G02Y1617477I1640J981D01*
G03X1520002Y1617580I-171J104D01*
G37*
G36*
G01X1537324D02*
Y1618706D01*
G02X1537527Y1618908I203J-1D01*
G01X1540347D01*
G02X1540550Y1618706I1J-202D01*
G01Y1617580D01*
G03X1540578Y1617477I200J-1D01*
G02Y1615515I-1640J-981D01*
G03X1540550Y1615412I172J-102D01*
G01Y1612462D01*
G03X1540578Y1612359I200J-1D01*
G02Y1610397I-1640J-981D01*
G03X1540550Y1610294I172J-102D01*
G01Y1609168D01*
G02X1540347Y1608966I-203J1D01*
G01X1537527D01*
G02X1537324Y1609168I-1J202D01*
G01Y1610294D01*
G03X1537296Y1610397I-200J1D01*
G02Y1612359I1640J981D01*
G03X1537324Y1612462I-172J102D01*
G01Y1615412D01*
G03X1537296Y1615515I-200J1D01*
G02Y1617477I1640J981D01*
G03X1537324Y1617580I-172J102D01*
G37*
G36*
G01X1658584D02*
Y1618706D01*
G02X1658786Y1618908I202J0D01*
G01X1661606D01*
G02X1661808Y1618706I0J-202D01*
G01Y1617580D01*
G03X1661837Y1617477I200J1D01*
G02Y1615515I-1640J-981D01*
G03X1661808Y1615412I171J-104D01*
G01Y1612462D01*
G03X1661837Y1612359I200J1D01*
G02Y1610397I-1640J-981D01*
G03X1661808Y1610294I171J-104D01*
G01Y1609168D01*
G02X1661606Y1608966I-202J0D01*
G01X1658786D01*
G02X1658584Y1609168I0J202D01*
G01Y1610294D01*
G03X1658555Y1610397I-200J-1D01*
G02Y1612359I1640J981D01*
G03X1658584Y1612462I-171J104D01*
G01Y1615412D01*
G03X1658555Y1615515I-200J-1D01*
G02Y1617477I1640J981D01*
G03X1658584Y1617580I-171J104D01*
G37*
G36*
G01X1675906D02*
Y1618706D01*
G02X1676109Y1618908I203J-1D01*
G01X1678929D01*
G02X1679132Y1618706I1J-202D01*
G01Y1617580D01*
G03X1679160Y1617477I200J-1D01*
G02Y1615515I-1640J-981D01*
G03X1679132Y1615412I172J-102D01*
G01Y1612462D01*
G03X1679160Y1612359I200J-1D01*
G02Y1610397I-1640J-981D01*
G03X1679132Y1610294I172J-102D01*
G01Y1609168D01*
G02X1678929Y1608966I-203J1D01*
G01X1676109D01*
G02X1675906Y1609168I-1J202D01*
G01Y1610294D01*
G03X1675878Y1610397I-200J1D01*
G02Y1612359I1640J981D01*
G03X1675906Y1612462I-172J102D01*
G01Y1615412D01*
G03X1675878Y1615515I-200J1D01*
G02Y1617477I1640J981D01*
G03X1675906Y1617580I-172J102D01*
G37*
G36*
G01X1693230D02*
Y1618706D01*
G02X1693432Y1618908I202J0D01*
G01X1696252D01*
G02X1696454Y1618706I0J-202D01*
G01Y1617580D01*
G03X1696483Y1617477I200J1D01*
G02Y1615515I-1640J-981D01*
G03X1696454Y1615412I171J-104D01*
G01Y1612462D01*
G03X1696483Y1612359I200J1D01*
G02Y1610397I-1640J-981D01*
G03X1696454Y1610294I171J-104D01*
G01Y1609168D01*
G02X1696252Y1608966I-202J0D01*
G01X1693432D01*
G02X1693230Y1609168I0J202D01*
G01Y1610294D01*
G03X1693201Y1610397I-200J-1D01*
G02Y1612359I1640J981D01*
G03X1693230Y1612462I-171J104D01*
G01Y1615412D01*
G03X1693201Y1615515I-200J-1D01*
G02Y1617477I1640J981D01*
G03X1693230Y1617580I-171J104D01*
G37*
G36*
G01X1710552D02*
Y1618706D01*
G02X1710755Y1618908I203J-1D01*
G01X1713575D01*
G02X1713778Y1618706I1J-202D01*
G01Y1617580D01*
G03X1713806Y1617477I200J-1D01*
G02Y1615515I-1640J-981D01*
G03X1713778Y1615412I172J-102D01*
G01Y1612462D01*
G03X1713806Y1612359I200J-1D01*
G02Y1610397I-1640J-981D01*
G03X1713778Y1610294I172J-102D01*
G01Y1609168D01*
G02X1713575Y1608966I-203J1D01*
G01X1710755D01*
G02X1710552Y1609168I-1J202D01*
G01Y1610294D01*
G03X1710524Y1610397I-200J1D01*
G02Y1612359I1640J981D01*
G03X1710552Y1612462I-172J102D01*
G01Y1615412D01*
G03X1710524Y1615515I-200J1D01*
G02Y1617477I1640J981D01*
G03X1710552Y1617580I-172J102D01*
G37*
G36*
G01X1332500Y959998D02*
G02Y963002I0J1502D01*
G02X1333543Y962580I-1J-1502D01*
G01X1333575Y962550D01*
X1333654Y962522D01*
X1334040Y962552D01*
X1334115Y962594D01*
X1334141Y962628D01*
G02X1335343Y963229I1202J-902D01*
G02Y960225I0J-1502D01*
G02X1334300Y960647I1J1502D01*
G01X1334268Y960677D01*
X1334189Y960705D01*
X1333803Y960675D01*
X1333728Y960633D01*
X1333702Y960599D01*
G02X1332500Y959998I-1202J901D01*
G37*
G36*
G01X1387813Y1032454D02*
G02Y1029450I0J-1502D01*
G02X1387635Y1029461I3J1502D01*
G01X1387634D01*
G03X1387495Y1029426I-24J-199D01*
G01X1387276Y1029270D01*
G03X1387197Y1029151I116J-163D01*
G02X1385732Y1027980I-1465J331D01*
G02Y1030984I0J1502D01*
G02X1385910Y1030973I-3J-1502D01*
G01X1385911D01*
G03X1386050Y1031008I24J199D01*
G01X1386269Y1031164D01*
G03X1386348Y1031283I-116J163D01*
G02X1387813Y1032454I1465J-331D01*
G37*
G36*
G01X1327708Y1061829D02*
X1327709Y1061828D01*
G03X1327839Y1061780I130J152D01*
G01X1328103D01*
G03X1328233Y1061828I0J200D01*
G01X1328234Y1061829D01*
G02X1329221Y1062199I987J-1131D01*
G02X1330723Y1060697I0J-1502D01*
G02X1330317Y1059670I-1502J0D01*
G01X1330291Y1059643D01*
X1330263Y1059572D01*
Y1059222D01*
X1330291Y1059151D01*
X1330317Y1059124D01*
G02X1330723Y1058097I-1096J-1027D01*
G02X1329221Y1056595I-1502J0D01*
G02X1328234Y1056965I0J1501D01*
G01X1328233D01*
Y1056966D01*
G03X1328103Y1057014I-130J-152D01*
G01X1327839D01*
G03X1327709Y1056966I0J-200D01*
G01X1327708Y1056965D01*
G02X1325734I-987J1131D01*
G01X1325733D01*
Y1056966D01*
G03X1325603Y1057014I-130J-152D01*
G01X1325339D01*
G03X1325209Y1056966I0J-200D01*
G01X1325208Y1056965D01*
G02X1323234I-987J1131D01*
G01X1323233D01*
Y1056966D01*
G03X1323103Y1057014I-130J-152D01*
G01X1322839D01*
G03X1322709Y1056966I0J-200D01*
G01X1322708Y1056965D01*
G02X1320734I-987J1131D01*
G01X1320733D01*
Y1056966D01*
G03X1320603Y1057014I-130J-152D01*
G01X1320339D01*
G03X1320209Y1056966I0J-200D01*
G01X1320208Y1056965D01*
G02X1319221Y1056595I-987J1131D01*
G02X1317719Y1058097I0J1502D01*
G02X1318125Y1059124I1502J0D01*
G01X1318151Y1059151D01*
X1318179Y1059222D01*
Y1059572D01*
X1318151Y1059643D01*
X1318125Y1059670D01*
G02X1317719Y1060697I1096J1027D01*
G02X1319221Y1062199I1502J0D01*
G02X1320208Y1061829I0J-1501D01*
G01X1320209D01*
Y1061828D01*
G03X1320339Y1061780I130J152D01*
G01X1320603D01*
G03X1320733Y1061828I0J200D01*
G01X1320734Y1061829D01*
G02X1322708I987J-1131D01*
G01X1322709D01*
Y1061828D01*
G03X1322839Y1061780I130J152D01*
G01X1323103D01*
G03X1323233Y1061828I0J200D01*
G01X1323234Y1061829D01*
G02X1325208I987J-1131D01*
G01X1325209D01*
Y1061828D01*
G03X1325339Y1061780I130J152D01*
G01X1325603D01*
G03X1325733Y1061828I0J200D01*
G01X1325734Y1061829D01*
G02X1327708I987J-1131D01*
G37*
G36*
G01X1415838D02*
X1415839Y1061828D01*
G03X1415969Y1061780I130J152D01*
G01X1416233D01*
G03X1416363Y1061828I0J200D01*
G01X1416364Y1061829D01*
G02X1417351Y1062199I987J-1131D01*
G02X1418853Y1060697I0J-1502D01*
G02X1418447Y1059670I-1502J0D01*
G01X1418421Y1059643D01*
X1418393Y1059572D01*
Y1059222D01*
X1418421Y1059151D01*
X1418447Y1059124D01*
G02X1418853Y1058097I-1096J-1027D01*
G02X1417351Y1056595I-1502J0D01*
G02X1416364Y1056965I0J1501D01*
G01X1416363D01*
Y1056966D01*
G03X1416233Y1057014I-130J-152D01*
G01X1415969D01*
G03X1415839Y1056966I0J-200D01*
G01X1415838Y1056965D01*
G02X1413864I-987J1131D01*
G01X1413863D01*
Y1056966D01*
G03X1413733Y1057014I-130J-152D01*
G01X1413469D01*
G03X1413339Y1056966I0J-200D01*
G01X1413338Y1056965D01*
G02X1411364I-987J1131D01*
G01X1411363D01*
Y1056966D01*
G03X1411233Y1057014I-130J-152D01*
G01X1410969D01*
G03X1410839Y1056966I0J-200D01*
G01X1410838Y1056965D01*
G02X1408864I-987J1131D01*
G01X1408863D01*
Y1056966D01*
G03X1408733Y1057014I-130J-152D01*
G01X1408469D01*
G03X1408339Y1056966I0J-200D01*
G01X1408338Y1056965D01*
G02X1407351Y1056595I-987J1131D01*
G02X1405849Y1058097I0J1502D01*
G02X1406255Y1059124I1502J0D01*
G01X1406281Y1059151D01*
X1406309Y1059222D01*
Y1059572D01*
X1406281Y1059643D01*
X1406255Y1059670D01*
G02X1405849Y1060697I1096J1027D01*
G02X1407351Y1062199I1502J0D01*
G02X1408338Y1061829I0J-1501D01*
G01X1408339D01*
Y1061828D01*
G03X1408469Y1061780I130J152D01*
G01X1408733D01*
G03X1408863Y1061828I0J200D01*
G01X1408864Y1061829D01*
G02X1410838I987J-1131D01*
G01X1410839D01*
Y1061828D01*
G03X1410969Y1061780I130J152D01*
G01X1411233D01*
G03X1411363Y1061828I0J200D01*
G01X1411364Y1061829D01*
G02X1413338I987J-1131D01*
G01X1413339D01*
Y1061828D01*
G03X1413469Y1061780I130J152D01*
G01X1413733D01*
G03X1413863Y1061828I0J200D01*
G01X1413864Y1061829D01*
G02X1415838I987J-1131D01*
G37*
G36*
G01X1414164Y1087928D02*
X1414165Y1087927D01*
G03X1414295Y1087879I130J152D01*
G01X1414559D01*
G03X1414689Y1087927I0J200D01*
G01X1414690Y1087928D01*
G02X1415677Y1088298I987J-1131D01*
G02X1417179Y1086796I0J-1502D01*
G02X1416809Y1085809I-1501J0D01*
G01Y1085808D01*
X1416808D01*
G03X1416760Y1085678I152J-130D01*
G01Y1085414D01*
G03X1416808Y1085284I200J0D01*
G01X1416809Y1085283D01*
G02X1417179Y1084296I-1131J-987D01*
G02X1415677Y1082794I-1502J0D01*
G02X1414690Y1083164I0J1501D01*
G01X1414689D01*
Y1083165D01*
G03X1414559Y1083213I-130J-152D01*
G01X1414295D01*
G03X1414165Y1083165I0J-200D01*
G01X1414164Y1083164D01*
G02X1412190I-987J1131D01*
G01X1412189D01*
Y1083165D01*
G03X1412059Y1083213I-130J-152D01*
G01X1411795D01*
G03X1411665Y1083165I0J-200D01*
G01X1411664Y1083164D01*
G02X1409690I-987J1131D01*
G01X1409689D01*
Y1083165D01*
G03X1409559Y1083213I-130J-152D01*
G01X1409295D01*
G03X1409165Y1083165I0J-200D01*
G01X1409164Y1083164D01*
G02X1407190I-987J1131D01*
G01X1407189D01*
Y1083165D01*
G03X1407059Y1083213I-130J-152D01*
G01X1406795D01*
G03X1406665Y1083165I0J-200D01*
G01X1406664Y1083164D01*
G02X1405677Y1082794I-987J1131D01*
G02X1404175Y1084296I0J1502D01*
G02X1404545Y1085283I1501J0D01*
G01Y1085284D01*
X1404546D01*
G03X1404594Y1085414I-152J130D01*
G01Y1085678D01*
G03X1404546Y1085808I-200J0D01*
G01X1404545Y1085809D01*
G02X1404175Y1086796I1131J987D01*
G02X1405677Y1088298I1502J0D01*
G02X1406664Y1087928I0J-1501D01*
G01X1406665D01*
Y1087927D01*
G03X1406795Y1087879I130J152D01*
G01X1407059D01*
G03X1407189Y1087927I0J200D01*
G01X1407190Y1087928D01*
G02X1409164I987J-1131D01*
G01X1409165D01*
Y1087927D01*
G03X1409295Y1087879I130J152D01*
G01X1409559D01*
G03X1409689Y1087927I0J200D01*
G01X1409690Y1087928D01*
G02X1411664I987J-1131D01*
G01X1411665D01*
Y1087927D01*
G03X1411795Y1087879I130J152D01*
G01X1412059D01*
G03X1412189Y1087927I0J200D01*
G01X1412190Y1087928D01*
G02X1414164I987J-1131D01*
G37*
G36*
G01X1391672Y1087827D02*
Y1088037D01*
G03X1391615Y1088176I-200J-1D01*
G02X1391189Y1089224I1076J1048D01*
G02X1394193I1502J0D01*
G02X1393823Y1088237I-1501J0D01*
G01Y1088236D01*
X1393822D01*
G03X1393774Y1088106I152J-130D01*
G01Y1087842D01*
G03X1393822Y1087712I200J0D01*
G01X1393823Y1087711D01*
G02Y1085737I-1131J-987D01*
G01Y1085736D01*
X1393822D01*
G03X1393774Y1085606I152J-130D01*
G01Y1085342D01*
G03X1393822Y1085212I200J0D01*
G01X1393823Y1085211D01*
G02Y1083237I-1131J-987D01*
G01Y1083236D01*
X1393822D01*
G03X1393774Y1083106I152J-130D01*
G01Y1082842D01*
G03X1393822Y1082712I200J0D01*
G01X1393823Y1082711D01*
G02X1394193Y1081724I-1131J-987D01*
G02X1392691Y1080222I-1502J0D01*
G02X1391704Y1080592I0J1501D01*
G01X1391703D01*
Y1080593D01*
G03X1391573Y1080641I-130J-152D01*
G01X1391309D01*
G03X1391179Y1080593I0J-200D01*
G01X1391178Y1080592D01*
G02X1390191Y1080222I-987J1131D01*
G02X1388689Y1081724I0J1502D01*
G02X1389059Y1082711I1501J0D01*
G01Y1082712D01*
X1389060D01*
G03X1389108Y1082842I-152J130D01*
G01Y1083106D01*
G03X1389060Y1083236I-200J0D01*
G01X1389059Y1083237D01*
G02Y1085211I1131J987D01*
G01Y1085212D01*
X1389060D01*
G03X1389108Y1085342I-152J130D01*
G01Y1085606D01*
G03X1389060Y1085736I-200J0D01*
G01X1389059Y1085737D01*
G02X1388689Y1086724I1131J987D01*
G02X1390191Y1088226I1502J0D01*
G02X1391239Y1087800I0J-1502D01*
G03X1391378Y1087743I140J143D01*
G01X1391504D01*
G03X1391643Y1087800I-1J200D01*
G02X1391672Y1087827I1038J-1086D01*
G37*
G36*
G01X1386949Y1093048D02*
G02X1389953I1502J0D01*
G02X1389423Y1091903I-1502J0D01*
G03X1389352Y1091746I129J-153D01*
G01X1389361Y1091389D01*
X1389402Y1091309D01*
X1389438Y1091281D01*
G02X1390025Y1090090I-915J-1191D01*
G02X1387021I-1502J0D01*
G02X1387551Y1091235I1502J0D01*
G03X1387622Y1091392I-129J153D01*
G01X1387613Y1091749D01*
X1387572Y1091829D01*
X1387536Y1091857D01*
G02X1386949Y1093048I915J1191D01*
G37*
G36*
G01X1415053Y1091541D02*
Y1091835D01*
G03X1414988Y1091982I-200J-1D01*
G02X1414503Y1093088I1019J1106D01*
G02X1417507I1502J0D01*
G02X1417022Y1091982I-1504J0D01*
G03X1416957Y1091835I135J-148D01*
G01Y1091541D01*
G03X1417022Y1091394I200J1D01*
G02X1417507Y1090288I-1019J-1106D01*
G02X1414503I-1502J0D01*
G02X1414988Y1091394I1504J0D01*
G03X1415053Y1091541I-135J148D01*
G37*
G36*
G01X1358382Y1112146D02*
G02Y1115150I0J1502D01*
G02X1359369Y1114780I0J-1501D01*
G01X1359370D01*
Y1114779D01*
G03X1359500Y1114731I130J152D01*
G01X1359764D01*
G03X1359894Y1114779I0J200D01*
G01X1359895Y1114780D01*
G02X1360882Y1115150I987J-1131D01*
G02Y1112146I0J-1502D01*
G02X1359895Y1112516I0J1501D01*
G01X1359894D01*
Y1112517D01*
G03X1359764Y1112565I-130J-152D01*
G01X1359500D01*
G03X1359370Y1112517I0J-200D01*
G01X1359369Y1112516D01*
G02X1358382Y1112146I-987J1131D01*
G37*
G36*
G01X1391841D02*
G02Y1115150I0J1502D01*
G02X1392828Y1114780I0J-1501D01*
G01X1392829D01*
Y1114779D01*
G03X1392959Y1114731I130J152D01*
G01X1393223D01*
G03X1393353Y1114779I0J200D01*
G01X1393354Y1114780D01*
G02X1394341Y1115150I987J-1131D01*
G02Y1112146I0J-1502D01*
G02X1393354Y1112516I0J1501D01*
G01X1393353D01*
Y1112517D01*
G03X1393223Y1112565I-130J-152D01*
G01X1392959D01*
G03X1392829Y1112517I0J-200D01*
G01X1392828Y1112516D01*
G02X1391841Y1112146I-987J1131D01*
G37*
G36*
G01X1321633Y1174884D02*
G02X1323135Y1176386I1502J0D01*
G02X1324122Y1176016I0J-1501D01*
G01X1324123D01*
Y1176015D01*
G03X1324253Y1175967I130J152D01*
G01X1324517D01*
G03X1324647Y1176015I0J200D01*
G01X1324648Y1176016D01*
G02X1325635Y1176386I987J-1131D01*
G02X1327137Y1174884I0J-1502D01*
G02X1326767Y1173897I-1501J0D01*
G01Y1173896D01*
X1326766D01*
G03X1326718Y1173766I152J-130D01*
G01Y1173502D01*
G03X1326766Y1173372I200J0D01*
G01X1326767Y1173371D01*
G02Y1171397I-1131J-987D01*
G01Y1171396D01*
X1326766D01*
G03X1326718Y1171266I152J-130D01*
G01Y1171002D01*
G03X1326766Y1170872I200J0D01*
G01X1326767Y1170871D01*
G02Y1168897I-1131J-987D01*
G01Y1168896D01*
X1326766D01*
G03X1326718Y1168766I152J-130D01*
G01Y1168502D01*
G03X1326766Y1168372I200J0D01*
G01X1326767Y1168371D01*
G02Y1166397I-1131J-987D01*
G01Y1166396D01*
X1326766D01*
G03X1326718Y1166266I152J-130D01*
G01Y1166002D01*
G03X1326766Y1165872I200J0D01*
G01X1326767Y1165871D01*
G02Y1163897I-1131J-987D01*
G01Y1163896D01*
X1326766D01*
G03X1326718Y1163766I152J-130D01*
G01Y1163502D01*
G03X1326766Y1163372I200J0D01*
G01X1326767Y1163371D01*
G02X1327137Y1162384I-1131J-987D01*
G02X1325635Y1160882I-1502J0D01*
G02X1324648Y1161252I0J1501D01*
G01X1324647D01*
Y1161253D01*
G03X1324517Y1161301I-130J-152D01*
G01X1324253D01*
G03X1324123Y1161253I0J-200D01*
G01X1324122Y1161252D01*
G02X1323135Y1160882I-987J1131D01*
G02X1321633Y1162384I0J1502D01*
G02X1322003Y1163371I1501J0D01*
G01Y1163372D01*
X1322004D01*
G03X1322052Y1163502I-152J130D01*
G01Y1163766D01*
G03X1322004Y1163896I-200J0D01*
G01X1322003Y1163897D01*
G02Y1165871I1131J987D01*
G01Y1165872D01*
X1322004D01*
G03X1322052Y1166002I-152J130D01*
G01Y1166266D01*
G03X1322004Y1166396I-200J0D01*
G01X1322003Y1166397D01*
G02Y1168371I1131J987D01*
G01Y1168372D01*
X1322004D01*
G03X1322052Y1168502I-152J130D01*
G01Y1168766D01*
G03X1322004Y1168896I-200J0D01*
G01X1322003Y1168897D01*
G02Y1170871I1131J987D01*
G01Y1170872D01*
X1322004D01*
G03X1322052Y1171002I-152J130D01*
G01Y1171266D01*
G03X1322004Y1171396I-200J0D01*
G01X1322003Y1171397D01*
G02Y1173371I1131J987D01*
G01Y1173372D01*
X1322004D01*
G03X1322052Y1173502I-152J130D01*
G01Y1173766D01*
G03X1322004Y1173896I-200J0D01*
G01X1322003Y1173897D01*
G02X1321633Y1174884I1131J987D01*
G37*
G36*
G01X1349461D02*
G02X1350963Y1176386I1502J0D01*
G02X1351950Y1176016I0J-1501D01*
G01X1351951D01*
Y1176015D01*
G03X1352081Y1175967I130J152D01*
G01X1352345D01*
G03X1352475Y1176015I0J200D01*
G01X1352476Y1176016D01*
G02X1353463Y1176386I987J-1131D01*
G02X1354965Y1174884I0J-1502D01*
G02X1354595Y1173897I-1501J0D01*
G01Y1173896D01*
X1354594D01*
G03X1354546Y1173766I152J-130D01*
G01Y1173502D01*
G03X1354594Y1173372I200J0D01*
G01X1354595Y1173371D01*
G02Y1171397I-1131J-987D01*
G01Y1171396D01*
X1354594D01*
G03X1354546Y1171266I152J-130D01*
G01Y1171002D01*
G03X1354594Y1170872I200J0D01*
G01X1354595Y1170871D01*
G02Y1168897I-1131J-987D01*
G01Y1168896D01*
X1354594D01*
G03X1354546Y1168766I152J-130D01*
G01Y1168502D01*
G03X1354594Y1168372I200J0D01*
G01X1354595Y1168371D01*
G02Y1166397I-1131J-987D01*
G01Y1166396D01*
X1354594D01*
G03X1354546Y1166266I152J-130D01*
G01Y1166002D01*
G03X1354594Y1165872I200J0D01*
G01X1354595Y1165871D01*
G02Y1163897I-1131J-987D01*
G01Y1163896D01*
X1354594D01*
G03X1354546Y1163766I152J-130D01*
G01Y1163502D01*
G03X1354594Y1163372I200J0D01*
G01X1354595Y1163371D01*
G02X1354965Y1162384I-1131J-987D01*
G02X1353463Y1160882I-1502J0D01*
G02X1352476Y1161252I0J1501D01*
G01X1352475D01*
Y1161253D01*
G03X1352345Y1161301I-130J-152D01*
G01X1352081D01*
G03X1351951Y1161253I0J-200D01*
G01X1351950Y1161252D01*
G02X1350963Y1160882I-987J1131D01*
G02X1349461Y1162384I0J1502D01*
G02X1349831Y1163371I1501J0D01*
G01Y1163372D01*
X1349832D01*
G03X1349880Y1163502I-152J130D01*
G01Y1163766D01*
G03X1349832Y1163896I-200J0D01*
G01X1349831Y1163897D01*
G02Y1165871I1131J987D01*
G01Y1165872D01*
X1349832D01*
G03X1349880Y1166002I-152J130D01*
G01Y1166266D01*
G03X1349832Y1166396I-200J0D01*
G01X1349831Y1166397D01*
G02Y1168371I1131J987D01*
G01Y1168372D01*
X1349832D01*
G03X1349880Y1168502I-152J130D01*
G01Y1168766D01*
G03X1349832Y1168896I-200J0D01*
G01X1349831Y1168897D01*
G02Y1170871I1131J987D01*
G01Y1170872D01*
X1349832D01*
G03X1349880Y1171002I-152J130D01*
G01Y1171266D01*
G03X1349832Y1171396I-200J0D01*
G01X1349831Y1171397D01*
G02Y1173371I1131J987D01*
G01Y1173372D01*
X1349832D01*
G03X1349880Y1173502I-152J130D01*
G01Y1173766D01*
G03X1349832Y1173896I-200J0D01*
G01X1349831Y1173897D01*
G02X1349461Y1174884I1131J987D01*
G37*
G36*
G01X1387220D02*
G02X1388722Y1176386I1502J0D01*
G02X1389709Y1176016I0J-1501D01*
G01X1389710D01*
Y1176015D01*
G03X1389840Y1175967I130J152D01*
G01X1390104D01*
G03X1390234Y1176015I0J200D01*
G01X1390235Y1176016D01*
G02X1391222Y1176386I987J-1131D01*
G02X1392724Y1174884I0J-1502D01*
G02X1392354Y1173897I-1501J0D01*
G01Y1173896D01*
X1392353D01*
G03X1392305Y1173766I152J-130D01*
G01Y1173502D01*
G03X1392353Y1173372I200J0D01*
G01X1392354Y1173371D01*
G02Y1171397I-1131J-987D01*
G01Y1171396D01*
X1392353D01*
G03X1392305Y1171266I152J-130D01*
G01Y1171002D01*
G03X1392353Y1170872I200J0D01*
G01X1392354Y1170871D01*
G02Y1168897I-1131J-987D01*
G01Y1168896D01*
X1392353D01*
G03X1392305Y1168766I152J-130D01*
G01Y1168502D01*
G03X1392353Y1168372I200J0D01*
G01X1392354Y1168371D01*
G02Y1166397I-1131J-987D01*
G01Y1166396D01*
X1392353D01*
G03X1392305Y1166266I152J-130D01*
G01Y1166002D01*
G03X1392353Y1165872I200J0D01*
G01X1392354Y1165871D01*
G02Y1163897I-1131J-987D01*
G01Y1163896D01*
X1392353D01*
G03X1392305Y1163766I152J-130D01*
G01Y1163502D01*
G03X1392353Y1163372I200J0D01*
G01X1392354Y1163371D01*
G02X1392724Y1162384I-1131J-987D01*
G02X1391222Y1160882I-1502J0D01*
G02X1390235Y1161252I0J1501D01*
G01X1390234D01*
Y1161253D01*
G03X1390104Y1161301I-130J-152D01*
G01X1389840D01*
G03X1389710Y1161253I0J-200D01*
G01X1389709Y1161252D01*
G02X1388722Y1160882I-987J1131D01*
G02X1387220Y1162384I0J1502D01*
G02X1387590Y1163371I1501J0D01*
G01Y1163372D01*
X1387591D01*
G03X1387639Y1163502I-152J130D01*
G01Y1163766D01*
G03X1387591Y1163896I-200J0D01*
G01X1387590Y1163897D01*
G02Y1165871I1131J987D01*
G01Y1165872D01*
X1387591D01*
G03X1387639Y1166002I-152J130D01*
G01Y1166266D01*
G03X1387591Y1166396I-200J0D01*
G01X1387590Y1166397D01*
G02Y1168371I1131J987D01*
G01Y1168372D01*
X1387591D01*
G03X1387639Y1168502I-152J130D01*
G01Y1168766D01*
G03X1387591Y1168896I-200J0D01*
G01X1387590Y1168897D01*
G02Y1170871I1131J987D01*
G01Y1170872D01*
X1387591D01*
G03X1387639Y1171002I-152J130D01*
G01Y1171266D01*
G03X1387591Y1171396I-200J0D01*
G01X1387590Y1171397D01*
G02Y1173371I1131J987D01*
G01Y1173372D01*
X1387591D01*
G03X1387639Y1173502I-152J130D01*
G01Y1173766D01*
G03X1387591Y1173896I-200J0D01*
G01X1387590Y1173897D01*
G02X1387220Y1174884I1131J987D01*
G37*
G36*
G01X1415048D02*
G02X1416550Y1176386I1502J0D01*
G02X1417537Y1176016I0J-1501D01*
G01X1417538D01*
Y1176015D01*
G03X1417668Y1175967I130J152D01*
G01X1417932D01*
G03X1418062Y1176015I0J200D01*
G01X1418063Y1176016D01*
G02X1419050Y1176386I987J-1131D01*
G02X1420552Y1174884I0J-1502D01*
G02X1420182Y1173897I-1501J0D01*
G01Y1173896D01*
X1420181D01*
G03X1420133Y1173766I152J-130D01*
G01Y1173502D01*
G03X1420181Y1173372I200J0D01*
G01X1420182Y1173371D01*
G02Y1171397I-1131J-987D01*
G01Y1171396D01*
X1420181D01*
G03X1420133Y1171266I152J-130D01*
G01Y1171002D01*
G03X1420181Y1170872I200J0D01*
G01X1420182Y1170871D01*
G02Y1168897I-1131J-987D01*
G01Y1168896D01*
X1420181D01*
G03X1420133Y1168766I152J-130D01*
G01Y1168502D01*
G03X1420181Y1168372I200J0D01*
G01X1420182Y1168371D01*
G02Y1166397I-1131J-987D01*
G01Y1166396D01*
X1420181D01*
G03X1420133Y1166266I152J-130D01*
G01Y1166002D01*
G03X1420181Y1165872I200J0D01*
G01X1420182Y1165871D01*
G02Y1163897I-1131J-987D01*
G01Y1163896D01*
X1420181D01*
G03X1420133Y1163766I152J-130D01*
G01Y1163502D01*
G03X1420181Y1163372I200J0D01*
G01X1420182Y1163371D01*
G02X1420552Y1162384I-1131J-987D01*
G02X1419050Y1160882I-1502J0D01*
G02X1418063Y1161252I0J1501D01*
G01X1418062D01*
Y1161253D01*
G03X1417932Y1161301I-130J-152D01*
G01X1417668D01*
G03X1417538Y1161253I0J-200D01*
G01X1417537Y1161252D01*
G02X1416550Y1160882I-987J1131D01*
G02X1415048Y1162384I0J1502D01*
G02X1415418Y1163371I1501J0D01*
G01Y1163372D01*
X1415419D01*
G03X1415467Y1163502I-152J130D01*
G01Y1163766D01*
G03X1415419Y1163896I-200J0D01*
G01X1415418Y1163897D01*
G02Y1165871I1131J987D01*
G01Y1165872D01*
X1415419D01*
G03X1415467Y1166002I-152J130D01*
G01Y1166266D01*
G03X1415419Y1166396I-200J0D01*
G01X1415418Y1166397D01*
G02Y1168371I1131J987D01*
G01Y1168372D01*
X1415419D01*
G03X1415467Y1168502I-152J130D01*
G01Y1168766D01*
G03X1415419Y1168896I-200J0D01*
G01X1415418Y1168897D01*
G02Y1170871I1131J987D01*
G01Y1170872D01*
X1415419D01*
G03X1415467Y1171002I-152J130D01*
G01Y1171266D01*
G03X1415419Y1171396I-200J0D01*
G01X1415418Y1171397D01*
G02Y1173371I1131J987D01*
G01Y1173372D01*
X1415419D01*
G03X1415467Y1173502I-152J130D01*
G01Y1173766D01*
G03X1415419Y1173896I-200J0D01*
G01X1415418Y1173897D01*
G02X1415048Y1174884I1131J987D01*
G37*
G36*
G01X1318991Y1186709D02*
G02X1321995I1502J0D01*
G02X1321625Y1185722I-1501J0D01*
G01Y1185721D01*
X1321624D01*
G03X1321576Y1185591I152J-130D01*
G01Y1185327D01*
G03X1321624Y1185197I200J0D01*
G01X1321625Y1185196D01*
G02Y1183222I-1131J-987D01*
G01Y1183221D01*
X1321624D01*
G03X1321576Y1183091I152J-130D01*
G01Y1182827D01*
G03X1321624Y1182697I200J0D01*
G01X1321625Y1182696D01*
G02Y1180722I-1131J-987D01*
G01Y1180721D01*
X1321624D01*
G03X1321576Y1180591I152J-130D01*
G01Y1180327D01*
G03X1321624Y1180197I200J0D01*
G01X1321625Y1180196D01*
G02X1321995Y1179209I-1131J-987D01*
G02X1318991I-1502J0D01*
G02X1319361Y1180196I1501J0D01*
G01Y1180197D01*
X1319362D01*
G03X1319410Y1180327I-152J130D01*
G01Y1180591D01*
G03X1319362Y1180721I-200J0D01*
G01X1319361Y1180722D01*
G02Y1182696I1131J987D01*
G01Y1182697D01*
X1319362D01*
G03X1319410Y1182827I-152J130D01*
G01Y1183091D01*
G03X1319362Y1183221I-200J0D01*
G01X1319361Y1183222D01*
G02Y1185196I1131J987D01*
G01Y1185197D01*
X1319362D01*
G03X1319410Y1185327I-152J130D01*
G01Y1185591D01*
G03X1319362Y1185721I-200J0D01*
G01X1319361Y1185722D01*
G02X1318991Y1186709I1131J987D01*
G37*
G36*
G01X1345921D02*
G02X1348925I1502J0D01*
G02X1348555Y1185722I-1501J0D01*
G01Y1185721D01*
X1348554D01*
G03X1348506Y1185591I152J-130D01*
G01Y1185327D01*
G03X1348554Y1185197I200J0D01*
G01X1348555Y1185196D01*
G02Y1183222I-1131J-987D01*
G01Y1183221D01*
X1348554D01*
G03X1348506Y1183091I152J-130D01*
G01Y1182827D01*
G03X1348554Y1182697I200J0D01*
G01X1348555Y1182696D01*
G02Y1180722I-1131J-987D01*
G01Y1180721D01*
X1348554D01*
G03X1348506Y1180591I152J-130D01*
G01Y1180327D01*
G03X1348554Y1180197I200J0D01*
G01X1348555Y1180196D01*
G02X1348925Y1179209I-1131J-987D01*
G02X1345921I-1502J0D01*
G02X1346291Y1180196I1501J0D01*
G01Y1180197D01*
X1346292D01*
G03X1346340Y1180327I-152J130D01*
G01Y1180591D01*
G03X1346292Y1180721I-200J0D01*
G01X1346291Y1180722D01*
G02Y1182696I1131J987D01*
G01Y1182697D01*
X1346292D01*
G03X1346340Y1182827I-152J130D01*
G01Y1183091D01*
G03X1346292Y1183221I-200J0D01*
G01X1346291Y1183222D01*
G02Y1185196I1131J987D01*
G01Y1185197D01*
X1346292D01*
G03X1346340Y1185327I-152J130D01*
G01Y1185591D01*
G03X1346292Y1185721I-200J0D01*
G01X1346291Y1185722D01*
G02X1345921Y1186709I1131J987D01*
G37*
G36*
G01X1392193D02*
G02X1395197I1502J0D01*
G02X1394827Y1185722I-1501J0D01*
G01Y1185721D01*
X1394826D01*
G03X1394778Y1185591I152J-130D01*
G01Y1185327D01*
G03X1394826Y1185197I200J0D01*
G01X1394827Y1185196D01*
G02Y1183222I-1131J-987D01*
G01Y1183221D01*
X1394826D01*
G03X1394778Y1183091I152J-130D01*
G01Y1182827D01*
G03X1394826Y1182697I200J0D01*
G01X1394827Y1182696D01*
G02Y1180722I-1131J-987D01*
G01Y1180721D01*
X1394826D01*
G03X1394778Y1180591I152J-130D01*
G01Y1180327D01*
G03X1394826Y1180197I200J0D01*
G01X1394827Y1180196D01*
G02X1395197Y1179209I-1131J-987D01*
G02X1392193I-1502J0D01*
G02X1392563Y1180196I1501J0D01*
G01Y1180197D01*
X1392564D01*
G03X1392612Y1180327I-152J130D01*
G01Y1180591D01*
G03X1392564Y1180721I-200J0D01*
G01X1392563Y1180722D01*
G02Y1182696I1131J987D01*
G01Y1182697D01*
X1392564D01*
G03X1392612Y1182827I-152J130D01*
G01Y1183091D01*
G03X1392564Y1183221I-200J0D01*
G01X1392563Y1183222D01*
G02Y1185196I1131J987D01*
G01Y1185197D01*
X1392564D01*
G03X1392612Y1185327I-152J130D01*
G01Y1185591D01*
G03X1392564Y1185721I-200J0D01*
G01X1392563Y1185722D01*
G02X1392193Y1186709I1131J987D01*
G37*
G36*
G01X1419123D02*
G02X1422127I1502J0D01*
G02X1421757Y1185722I-1501J0D01*
G01Y1185721D01*
X1421756D01*
G03X1421708Y1185591I152J-130D01*
G01Y1185327D01*
G03X1421756Y1185197I200J0D01*
G01X1421757Y1185196D01*
G02Y1183222I-1131J-987D01*
G01Y1183221D01*
X1421756D01*
G03X1421708Y1183091I152J-130D01*
G01Y1182827D01*
G03X1421756Y1182697I200J0D01*
G01X1421757Y1182696D01*
G02Y1180722I-1131J-987D01*
G01Y1180721D01*
X1421756D01*
G03X1421708Y1180591I152J-130D01*
G01Y1180327D01*
G03X1421756Y1180197I200J0D01*
G01X1421757Y1180196D01*
G02X1422127Y1179209I-1131J-987D01*
G02X1419123I-1502J0D01*
G02X1419493Y1180196I1501J0D01*
G01Y1180197D01*
X1419494D01*
G03X1419542Y1180327I-152J130D01*
G01Y1180591D01*
G03X1419494Y1180721I-200J0D01*
G01X1419493Y1180722D01*
G02Y1182696I1131J987D01*
G01Y1182697D01*
X1419494D01*
G03X1419542Y1182827I-152J130D01*
G01Y1183091D01*
G03X1419494Y1183221I-200J0D01*
G01X1419493Y1183222D01*
G02Y1185196I1131J987D01*
G01Y1185197D01*
X1419494D01*
G03X1419542Y1185327I-152J130D01*
G01Y1185591D01*
G03X1419494Y1185721I-200J0D01*
G01X1419493Y1185722D01*
G02X1419123Y1186709I1131J987D01*
G37*
G36*
G01X1333291Y1186921D02*
G02X1336295I1502J0D01*
G02X1335925Y1185934I-1501J0D01*
G01Y1185933D01*
X1335924D01*
G03X1335876Y1185803I152J-130D01*
G01Y1185539D01*
G03X1335924Y1185409I200J0D01*
G01X1335925Y1185408D01*
G02Y1183434I-1131J-987D01*
G01Y1183433D01*
X1335924D01*
G03X1335876Y1183303I152J-130D01*
G01Y1183039D01*
G03X1335924Y1182909I200J0D01*
G01X1335925Y1182908D01*
G02Y1180934I-1131J-987D01*
G01Y1180933D01*
X1335924D01*
G03X1335876Y1180803I152J-130D01*
G01Y1180539D01*
G03X1335924Y1180409I200J0D01*
G01X1335925Y1180408D01*
G02X1336295Y1179421I-1131J-987D01*
G02X1333291I-1502J0D01*
G02X1333661Y1180408I1501J0D01*
G01Y1180409D01*
X1333662D01*
G03X1333710Y1180539I-152J130D01*
G01Y1180803D01*
G03X1333662Y1180933I-200J0D01*
G01X1333661Y1180934D01*
G02Y1182908I1131J987D01*
G01Y1182909D01*
X1333662D01*
G03X1333710Y1183039I-152J130D01*
G01Y1183303D01*
G03X1333662Y1183433I-200J0D01*
G01X1333661Y1183434D01*
G02Y1185408I1131J987D01*
G01Y1185409D01*
X1333662D01*
G03X1333710Y1185539I-152J130D01*
G01Y1185803D01*
G03X1333662Y1185933I-200J0D01*
G01X1333661Y1185934D01*
G02X1333291Y1186921I1131J987D01*
G37*
G36*
G01X1360221D02*
G02X1363225I1502J0D01*
G02X1362855Y1185934I-1501J0D01*
G01Y1185933D01*
X1362854D01*
G03X1362806Y1185803I152J-130D01*
G01Y1185539D01*
G03X1362854Y1185409I200J0D01*
G01X1362855Y1185408D01*
G02Y1183434I-1131J-987D01*
G01Y1183433D01*
X1362854D01*
G03X1362806Y1183303I152J-130D01*
G01Y1183039D01*
G03X1362854Y1182909I200J0D01*
G01X1362855Y1182908D01*
G02Y1180934I-1131J-987D01*
G01Y1180933D01*
X1362854D01*
G03X1362806Y1180803I152J-130D01*
G01Y1180539D01*
G03X1362854Y1180409I200J0D01*
G01X1362855Y1180408D01*
G02X1363225Y1179421I-1131J-987D01*
G02X1360221I-1502J0D01*
G02X1360591Y1180408I1501J0D01*
G01Y1180409D01*
X1360592D01*
G03X1360640Y1180539I-152J130D01*
G01Y1180803D01*
G03X1360592Y1180933I-200J0D01*
G01X1360591Y1180934D01*
G02Y1182908I1131J987D01*
G01Y1182909D01*
X1360592D01*
G03X1360640Y1183039I-152J130D01*
G01Y1183303D01*
G03X1360592Y1183433I-200J0D01*
G01X1360591Y1183434D01*
G02Y1185408I1131J987D01*
G01Y1185409D01*
X1360592D01*
G03X1360640Y1185539I-152J130D01*
G01Y1185803D01*
G03X1360592Y1185933I-200J0D01*
G01X1360591Y1185934D01*
G02X1360221Y1186921I1131J987D01*
G37*
G36*
G01X1406493D02*
G02X1409497I1502J0D01*
G02X1409127Y1185934I-1501J0D01*
G01Y1185933D01*
X1409126D01*
G03X1409078Y1185803I152J-130D01*
G01Y1185539D01*
G03X1409126Y1185409I200J0D01*
G01X1409127Y1185408D01*
G02Y1183434I-1131J-987D01*
G01Y1183433D01*
X1409126D01*
G03X1409078Y1183303I152J-130D01*
G01Y1183039D01*
G03X1409126Y1182909I200J0D01*
G01X1409127Y1182908D01*
G02Y1180934I-1131J-987D01*
G01Y1180933D01*
X1409126D01*
G03X1409078Y1180803I152J-130D01*
G01Y1180539D01*
G03X1409126Y1180409I200J0D01*
G01X1409127Y1180408D01*
G02X1409497Y1179421I-1131J-987D01*
G02X1406493I-1502J0D01*
G02X1406863Y1180408I1501J0D01*
G01Y1180409D01*
X1406864D01*
G03X1406912Y1180539I-152J130D01*
G01Y1180803D01*
G03X1406864Y1180933I-200J0D01*
G01X1406863Y1180934D01*
G02Y1182908I1131J987D01*
G01Y1182909D01*
X1406864D01*
G03X1406912Y1183039I-152J130D01*
G01Y1183303D01*
G03X1406864Y1183433I-200J0D01*
G01X1406863Y1183434D01*
G02Y1185408I1131J987D01*
G01Y1185409D01*
X1406864D01*
G03X1406912Y1185539I-152J130D01*
G01Y1185803D01*
G03X1406864Y1185933I-200J0D01*
G01X1406863Y1185934D01*
G02X1406493Y1186921I1131J987D01*
G37*
G36*
G01X1433423D02*
G02X1436427I1502J0D01*
G02X1436057Y1185934I-1501J0D01*
G01Y1185933D01*
X1436056D01*
G03X1436008Y1185803I152J-130D01*
G01Y1185539D01*
G03X1436056Y1185409I200J0D01*
G01X1436057Y1185408D01*
G02Y1183434I-1131J-987D01*
G01Y1183433D01*
X1436056D01*
G03X1436008Y1183303I152J-130D01*
G01Y1183039D01*
G03X1436056Y1182909I200J0D01*
G01X1436057Y1182908D01*
G02Y1180934I-1131J-987D01*
G01Y1180933D01*
X1436056D01*
G03X1436008Y1180803I152J-130D01*
G01Y1180539D01*
G03X1436056Y1180409I200J0D01*
G01X1436057Y1180408D01*
G02X1436427Y1179421I-1131J-987D01*
G02X1433423I-1502J0D01*
G02X1433793Y1180408I1501J0D01*
G01Y1180409D01*
X1433794D01*
G03X1433842Y1180539I-152J130D01*
G01Y1180803D01*
G03X1433794Y1180933I-200J0D01*
G01X1433793Y1180934D01*
G02Y1182908I1131J987D01*
G01Y1182909D01*
X1433794D01*
G03X1433842Y1183039I-152J130D01*
G01Y1183303D01*
G03X1433794Y1183433I-200J0D01*
G01X1433793Y1183434D01*
G02Y1185408I1131J987D01*
G01Y1185409D01*
X1433794D01*
G03X1433842Y1185539I-152J130D01*
G01Y1185803D01*
G03X1433794Y1185933I-200J0D01*
G01X1433793Y1185934D01*
G02X1433423Y1186921I1131J987D01*
G37*
G36*
G01X1316676Y1192621D02*
G02X1319680I1502J0D01*
G02X1319310Y1191634I-1501J0D01*
G01Y1191633D01*
X1319309D01*
G03X1319261Y1191503I152J-130D01*
G01Y1191239D01*
G03X1319309Y1191109I200J0D01*
G01X1319310Y1191108D01*
G02X1319680Y1190121I-1131J-987D01*
G02X1316676I-1502J0D01*
G02X1317046Y1191108I1501J0D01*
G01Y1191109D01*
X1317047D01*
G03X1317095Y1191239I-152J130D01*
G01Y1191503D01*
G03X1317047Y1191633I-200J0D01*
G01X1317046Y1191634D01*
G02X1316676Y1192621I1131J987D01*
G37*
G36*
G01X1330141D02*
G02X1333145I1502J0D01*
G02X1332775Y1191634I-1501J0D01*
G01Y1191633D01*
X1332774D01*
G03X1332726Y1191503I152J-130D01*
G01Y1191239D01*
G03X1332774Y1191109I200J0D01*
G01X1332775Y1191108D01*
G02X1333145Y1190121I-1131J-987D01*
G02X1330141I-1502J0D01*
G02X1330511Y1191108I1501J0D01*
G01Y1191109D01*
X1330512D01*
G03X1330560Y1191239I-152J130D01*
G01Y1191503D01*
G03X1330512Y1191633I-200J0D01*
G01X1330511Y1191634D01*
G02X1330141Y1192621I1131J987D01*
G37*
G36*
G01X1335606D02*
G02X1338610I1502J0D01*
G02X1338240Y1191634I-1501J0D01*
G01Y1191633D01*
X1338239D01*
G03X1338191Y1191503I152J-130D01*
G01Y1191239D01*
G03X1338239Y1191109I200J0D01*
G01X1338240Y1191108D01*
G02X1338610Y1190121I-1131J-987D01*
G02X1335606I-1502J0D01*
G02X1335976Y1191108I1501J0D01*
G01Y1191109D01*
X1335977D01*
G03X1336025Y1191239I-152J130D01*
G01Y1191503D01*
G03X1335977Y1191633I-200J0D01*
G01X1335976Y1191634D01*
G02X1335606Y1192621I1131J987D01*
G37*
G36*
G01X1343606D02*
G02X1346610I1502J0D01*
G02X1346240Y1191634I-1501J0D01*
G01Y1191633D01*
X1346239D01*
G03X1346191Y1191503I152J-130D01*
G01Y1191239D01*
G03X1346239Y1191109I200J0D01*
G01X1346240Y1191108D01*
G02X1346610Y1190121I-1131J-987D01*
G02X1343606I-1502J0D01*
G02X1343976Y1191108I1501J0D01*
G01Y1191109D01*
X1343977D01*
G03X1344025Y1191239I-152J130D01*
G01Y1191503D01*
G03X1343977Y1191633I-200J0D01*
G01X1343976Y1191634D01*
G02X1343606Y1192621I1131J987D01*
G37*
G36*
G01X1362536D02*
G02X1365540I1502J0D01*
G02X1365170Y1191634I-1501J0D01*
G01Y1191633D01*
X1365169D01*
G03X1365121Y1191503I152J-130D01*
G01Y1191239D01*
G03X1365169Y1191109I200J0D01*
G01X1365170Y1191108D01*
G02X1365540Y1190121I-1131J-987D01*
G02X1362536I-1502J0D01*
G02X1362906Y1191108I1501J0D01*
G01Y1191109D01*
X1362907D01*
G03X1362955Y1191239I-152J130D01*
G01Y1191503D01*
G03X1362907Y1191633I-200J0D01*
G01X1362906Y1191634D01*
G02X1362536Y1192621I1131J987D01*
G37*
G36*
G01X1389878D02*
G02X1392882I1502J0D01*
G02X1392512Y1191634I-1501J0D01*
G01Y1191633D01*
X1392511D01*
G03X1392463Y1191503I152J-130D01*
G01Y1191239D01*
G03X1392511Y1191109I200J0D01*
G01X1392512Y1191108D01*
G02X1392882Y1190121I-1131J-987D01*
G02X1389878I-1502J0D01*
G02X1390248Y1191108I1501J0D01*
G01Y1191109D01*
X1390249D01*
G03X1390297Y1191239I-152J130D01*
G01Y1191503D01*
G03X1390249Y1191633I-200J0D01*
G01X1390248Y1191634D01*
G02X1389878Y1192621I1131J987D01*
G37*
G36*
G01X1403343D02*
G02X1406347I1502J0D01*
G02X1405977Y1191634I-1501J0D01*
G01Y1191633D01*
X1405976D01*
G03X1405928Y1191503I152J-130D01*
G01Y1191239D01*
G03X1405976Y1191109I200J0D01*
G01X1405977Y1191108D01*
G02X1406347Y1190121I-1131J-987D01*
G02X1403343I-1502J0D01*
G02X1403713Y1191108I1501J0D01*
G01Y1191109D01*
X1403714D01*
G03X1403762Y1191239I-152J130D01*
G01Y1191503D01*
G03X1403714Y1191633I-200J0D01*
G01X1403713Y1191634D01*
G02X1403343Y1192621I1131J987D01*
G37*
G36*
G01X1408808D02*
G02X1411812I1502J0D01*
G02X1411442Y1191634I-1501J0D01*
G01Y1191633D01*
X1411441D01*
G03X1411393Y1191503I152J-130D01*
G01Y1191239D01*
G03X1411441Y1191109I200J0D01*
G01X1411442Y1191108D01*
G02X1411812Y1190121I-1131J-987D01*
G02X1408808I-1502J0D01*
G02X1409178Y1191108I1501J0D01*
G01Y1191109D01*
X1409179D01*
G03X1409227Y1191239I-152J130D01*
G01Y1191503D01*
G03X1409179Y1191633I-200J0D01*
G01X1409178Y1191634D01*
G02X1408808Y1192621I1131J987D01*
G37*
G36*
G01X1416808D02*
G02X1419812I1502J0D01*
G02X1419442Y1191634I-1501J0D01*
G01Y1191633D01*
X1419441D01*
G03X1419393Y1191503I152J-130D01*
G01Y1191239D01*
G03X1419441Y1191109I200J0D01*
G01X1419442Y1191108D01*
G02X1419812Y1190121I-1131J-987D01*
G02X1416808I-1502J0D01*
G02X1417178Y1191108I1501J0D01*
G01Y1191109D01*
X1417179D01*
G03X1417227Y1191239I-152J130D01*
G01Y1191503D01*
G03X1417179Y1191633I-200J0D01*
G01X1417178Y1191634D01*
G02X1416808Y1192621I1131J987D01*
G37*
G36*
G01X1435738D02*
G02X1438742I1502J0D01*
G02X1438372Y1191634I-1501J0D01*
G01Y1191633D01*
X1438371D01*
G03X1438323Y1191503I152J-130D01*
G01Y1191239D01*
G03X1438371Y1191109I200J0D01*
G01X1438372Y1191108D01*
G02X1438742Y1190121I-1131J-987D01*
G02X1435738I-1502J0D01*
G02X1436108Y1191108I1501J0D01*
G01Y1191109D01*
X1436109D01*
G03X1436157Y1191239I-152J130D01*
G01Y1191503D01*
G03X1436109Y1191633I-200J0D01*
G01X1436108Y1191634D01*
G02X1435738Y1192621I1131J987D01*
G37*
G36*
G01X1362219Y1261006D02*
X1362533D01*
G03X1362691Y1261083I0J200D01*
G02X1365061I1185J-923D01*
G03X1365219Y1261006I158J123D01*
G01X1365533D01*
G03X1365691Y1261083I0J200D01*
G02X1366876Y1261662I1185J-923D01*
G02X1368378Y1260160I0J-1502D01*
G02X1367799Y1258975I-1502J0D01*
G03X1367722Y1258817I123J-158D01*
G01Y1258503D01*
G03X1367799Y1258345I200J0D01*
G02X1368378Y1257160I-923J-1185D01*
G02X1366876Y1255658I-1502J0D01*
G02X1365691Y1256237I0J1502D01*
G03X1365533Y1256314I-158J-123D01*
G01X1365219D01*
G03X1365061Y1256237I0J-200D01*
G02X1362691I-1185J923D01*
G03X1362533Y1256314I-158J-123D01*
G01X1362219D01*
G03X1362061Y1256237I0J-200D01*
G02X1359691I-1185J923D01*
G03X1359533Y1256314I-158J-123D01*
G01X1359219D01*
G03X1359061Y1256237I0J-200D01*
G02X1356691I-1185J923D01*
G03X1356533Y1256314I-158J-123D01*
G01X1356219D01*
G03X1356061Y1256237I0J-200D01*
G02X1353691I-1185J923D01*
G03X1353533Y1256314I-158J-123D01*
G01X1353219D01*
G03X1353061Y1256237I0J-200D01*
G02X1350691I-1185J923D01*
G03X1350533Y1256314I-158J-123D01*
G01X1350219D01*
G03X1350061Y1256237I0J-200D01*
G02X1347691I-1185J923D01*
G03X1347533Y1256314I-158J-123D01*
G01X1347219D01*
G03X1347061Y1256237I0J-200D01*
G02X1344691I-1185J923D01*
G03X1344533Y1256314I-158J-123D01*
G01X1344219D01*
G03X1344061Y1256237I0J-200D01*
G02X1341691I-1185J923D01*
G03X1341533Y1256314I-158J-123D01*
G01X1341219D01*
G03X1341061Y1256237I0J-200D01*
G02X1338691I-1185J923D01*
G03X1338533Y1256314I-158J-123D01*
G01X1338219D01*
G03X1338061Y1256237I0J-200D01*
G02X1335691I-1185J923D01*
G03X1335533Y1256314I-158J-123D01*
G01X1335219D01*
G03X1335061Y1256237I0J-200D01*
G02X1333876Y1255658I-1185J923D01*
G02X1332374Y1257160I0J1502D01*
G02X1332953Y1258345I1502J0D01*
G03X1333030Y1258503I-123J158D01*
G01Y1258817D01*
G03X1332953Y1258975I-200J0D01*
G02X1332374Y1260160I923J1185D01*
G02X1333876Y1261662I1502J0D01*
G02X1335061Y1261083I0J-1502D01*
G03X1335219Y1261006I158J123D01*
G01X1335533D01*
G03X1335691Y1261083I0J200D01*
G02X1338061I1185J-923D01*
G03X1338219Y1261006I158J123D01*
G01X1338533D01*
G03X1338691Y1261083I0J200D01*
G02X1341061I1185J-923D01*
G03X1341219Y1261006I158J123D01*
G01X1341533D01*
G03X1341691Y1261083I0J200D01*
G02X1344061I1185J-923D01*
G03X1344219Y1261006I158J123D01*
G01X1344533D01*
G03X1344691Y1261083I0J200D01*
G02X1347061I1185J-923D01*
G03X1347219Y1261006I158J123D01*
G01X1347533D01*
G03X1347691Y1261083I0J200D01*
G02X1350061I1185J-923D01*
G03X1350219Y1261006I158J123D01*
G01X1350533D01*
G03X1350691Y1261083I0J200D01*
G02X1353061I1185J-923D01*
G03X1353219Y1261006I158J123D01*
G01X1353533D01*
G03X1353691Y1261083I0J200D01*
G02X1356061I1185J-923D01*
G03X1356219Y1261006I158J123D01*
G01X1356533D01*
G03X1356691Y1261083I0J200D01*
G02X1359061I1185J-923D01*
G03X1359219Y1261006I158J123D01*
G01X1359533D01*
G03X1359691Y1261083I0J200D01*
G02X1362061I1185J-923D01*
G03X1362219Y1261006I158J123D01*
G37*
G36*
G01X1376634Y1208292D02*
G02X1376195Y1207232I-1501J1D01*
G01X1373355Y1204392D01*
G03X1373296Y1204250I141J-142D01*
G01Y1197925D01*
G03X1373354Y1197785I200J1D01*
G01X1373357Y1197781D01*
G03X1373499Y1197722I142J141D01*
G01X1373504D01*
G03X1373646Y1197781I0J200D01*
G01X1374397Y1198533D01*
G02X1375457Y1198972I1061J-1062D01*
G01X1375459D01*
G02X1376960Y1197471I0J-1501D01*
G01Y1197469D01*
G02X1376521Y1196409I-1501J1D01*
G01X1375724Y1195612D01*
G03Y1195330I141J-141D01*
G01X1376521Y1194533D01*
G02X1376960Y1193473I-1062J-1061D01*
G01Y1193471D01*
G02X1375459Y1191970I-1501J0D01*
G01X1375457D01*
G02X1374397Y1192409I1J1501D01*
G01X1373646Y1193161D01*
G03X1373504Y1193220I-142J-141D01*
G01X1372170D01*
G02X1371110Y1193659I1J1501D01*
G01X1369232Y1195537D01*
G02X1368792Y1196599I1062J1062D01*
G01Y1205577D01*
G02X1369232Y1206639I1502J0D01*
G01X1372073Y1209479D01*
G03X1372132Y1209621I-141J142D01*
G01Y1281877D01*
G03X1372073Y1282019I-200J0D01*
G01X1363076Y1291015D01*
G03X1362934Y1291074I-142J-141D01*
G01X1320187D01*
G03X1320045Y1291015I0J-200D01*
G01X1319349Y1290319D01*
G02X1318289Y1289880I-1061J1062D01*
G01X1318287D01*
G02X1316786Y1291381I0J1501D01*
G01Y1291383D01*
G02X1317225Y1292443I1501J-1D01*
G01X1318022Y1293240D01*
G03Y1293522I-141J141D01*
G01X1317225Y1294319D01*
G02X1316786Y1295379I1062J1061D01*
G01Y1295381D01*
G02X1318287Y1296882I1501J0D01*
G01X1318289D01*
G02X1319349Y1296443I-1J-1501D01*
G01X1320155Y1295637D01*
G03X1320297Y1295578I142J141D01*
G01X1364261D01*
G02X1365323Y1295138I0J-1502D01*
G01X1376195Y1284266D01*
G02X1376634Y1283206I-1062J-1061D01*
G01Y1208292D01*
G37*
G36*
G01X1403109Y964834D02*
G02X1402064Y964411I-1045J1079D01*
G02Y967415I0J1502D01*
G02X1403507Y966330I0J-1502D01*
G03X1404169Y966153I384J111D01*
G02X1405214Y966576I1045J-1079D01*
G02Y963572I0J-1502D01*
G02X1403771Y964657I0J1502D01*
G03X1403109Y964834I-384J-111D01*
G37*
G36*
G01X1399791Y989176D02*
G02X1399763Y989464I1474J289D01*
G01Y989465D01*
G02X1401265Y987963I1502J0D01*
G02X1400835Y988026I0J1502D01*
G03X1400328Y987566I-114J-383D01*
G02X1400356Y987278I-1474J-289D01*
G01Y987277D01*
G02X1398854Y988779I-1502J0D01*
G02X1399284Y988716I0J-1502D01*
G03X1399791Y989176I114J383D01*
G37*
G36*
G01X1322427Y989723D02*
X1322428D01*
G02X1322750Y989688I0J-1502D01*
G01X1322793Y989678D01*
X1322878Y989697D01*
X1323157Y989908D01*
G03X1323236Y990054I-121J160D01*
G01Y990055D01*
G02X1324735Y991468I1499J-89D01*
G02X1326235Y990044I0J-1502D01*
G01X1326237Y989997D01*
X1326284Y989915D01*
X1326630Y989683D01*
X1326722Y989671D01*
X1326767Y989687D01*
G02X1327267Y989773I501J-1416D01*
G02X1328340Y989322I0J-1502D01*
G01X1328341Y989321D01*
G03X1328472Y989262I142J141D01*
G01X1328743Y989247D01*
G03X1328880Y989292I10J200D01*
G02X1328962Y989355I956J-1159D01*
G01X1328936Y989590D01*
G03X1328827Y989746I-199J-23D01*
G02X1328001Y991088I677J1342D01*
G02X1331005I1502J0D01*
G02X1330564Y990025I-1502J0D01*
G01X1330531Y989992D01*
X1330502Y989907D01*
X1330541Y989550D01*
G03X1330633Y989404I199J23D01*
G01X1330634Y989403D01*
G02X1330813Y989271I-799J-1271D01*
G01X1330842Y989246D01*
X1330912Y989221D01*
X1331258Y989233D01*
X1331326Y989262D01*
X1331353Y989289D01*
G02X1332404Y989717I1050J-1074D01*
G02X1332903Y989632I1J-1502D01*
G01X1332953Y989614D01*
X1333058Y989633D01*
X1333362Y989891D01*
G03X1333430Y990078I-129J153D01*
G01Y990079D01*
G02X1333407Y990340I1479J262D01*
G02X1336411I1502J0D01*
G01Y990338D01*
G02X1336389Y990083I-1502J1D01*
G01X1336380Y990029D01*
X1336418Y989928D01*
X1336734Y989674D01*
G03X1336937Y989646I125J156D01*
G02X1337513Y989761I576J-1387D01*
G01X1337514D01*
G02X1336012Y988259I0J-1502D01*
G01Y988261D01*
G02X1336034Y988516I1502J-1D01*
G01X1336043Y988570D01*
X1336005Y988671D01*
X1335689Y988925D01*
G03X1335486Y988953I-125J-156D01*
G02X1334909Y988838I-576J1387D01*
G02X1334410Y988923I-1J1502D01*
G01X1334360Y988941D01*
X1334255Y988922D01*
X1333951Y988664D01*
G03X1333883Y988477I129J-153D01*
G01Y988476D01*
G02X1333906Y988215I-1479J-262D01*
G02X1332404Y986713I-1502J0D01*
G02X1331425Y987076I0J1502D01*
G01X1331396Y987101D01*
X1331326Y987126D01*
X1330980Y987114D01*
X1330912Y987085D01*
X1330885Y987058D01*
G02X1329836Y986630I-1050J1074D01*
G01X1329834D01*
G02X1328761Y987081I0J1502D01*
G01X1328760Y987082D01*
G03X1328629Y987141I-142J-141D01*
G01X1328358Y987156D01*
G03X1328221Y987111I-10J-200D01*
G02X1327267Y986769I-954J1160D01*
G02X1325767Y988193I0J1502D01*
G01X1325765Y988240D01*
X1325718Y988322D01*
X1325372Y988554D01*
X1325280Y988566D01*
X1325235Y988550D01*
G02X1324735Y988464I-501J1416D01*
G01X1324734D01*
G02X1324412Y988499I0J1502D01*
G01X1324369Y988509D01*
X1324284Y988490D01*
X1324005Y988279D01*
G03X1323926Y988133I121J-160D01*
G01Y988132D01*
G02X1322427Y986719I-1499J89D01*
G02X1320930Y988103I0J1502D01*
G01X1320926Y988150D01*
X1320878Y988230D01*
X1320530Y988453D01*
X1320437Y988463D01*
X1320393Y988446D01*
G02X1319877Y988354I-518J1410D01*
G01X1319874D01*
G02X1319679Y988367I2J1502D01*
G03X1319521Y988319I-26J-198D01*
G01X1319294Y988121D01*
G03X1319226Y987970I132J-150D01*
G01Y987105D01*
G02X1319167Y986963I-200J0D01*
G01X1318349Y986145D01*
G02X1318207Y986086I-142J141D01*
G01X1313098D01*
G02X1312956Y986145I0J200D01*
G01X1311625Y987475D01*
G02X1311566Y987617I141J142D01*
G01Y996878D01*
G02X1311625Y997020I200J0D01*
G01X1337091Y1022485D01*
G03X1337150Y1022627I-141J142D01*
G01Y1030705D01*
G02X1337209Y1030847I200J0D01*
G01X1338916Y1032555D01*
G02X1339058Y1032614I142J-141D01*
G01X1347858D01*
G02X1348000Y1032555I0J-200D01*
G01X1349385Y1031170D01*
G02X1349444Y1031028I-141J-142D01*
G01Y1021602D01*
G03X1349503Y1021460I200J0D01*
G01X1351706Y1019257D01*
G03X1351848Y1019198I142J141D01*
G01X1355871D01*
G03X1356018Y1019263I-1J200D01*
G01X1356246Y1019511D01*
X1356273Y1019591D01*
X1356269Y1019633D01*
G02X1356263Y1019766I1496J134D01*
G02X1357765Y1021268I1502J0D01*
G02X1358550Y1021047I0J-1505D01*
G03X1358795Y1021076I104J171D01*
G01X1359659Y1021939D01*
G02X1359801Y1021998I142J-141D01*
G01X1362405D01*
G02X1362547Y1021940I1J-200D01*
G01X1363136Y1021351D01*
G03X1363362Y1021311I142J141D01*
G01X1363759Y1021496D01*
X1363822Y1021605D01*
X1363817Y1021667D01*
G02X1363812Y1021793I1497J123D01*
G02X1364009Y1022537I1503J0D01*
G01X1364036Y1022584D01*
X1364035Y1022690D01*
X1363835Y1023035D01*
G03X1363662Y1023134I-173J-101D01*
G01X1362200D01*
G02X1360855Y1023691I0J1902D01*
G01X1359944Y1024602D01*
G02X1359388Y1025944I1346J1344D01*
G01Y1031022D01*
G03X1359329Y1031164I-200J0D01*
G01X1358187Y1032305D01*
G03X1358045Y1032364I-142J-141D01*
G01X1357265D01*
G02Y1036168I0J1902D01*
G01X1358916D01*
G02X1360261Y1035611I0J-1902D01*
G01X1362634Y1033238D01*
G02X1363190Y1031896I-1346J-1344D01*
G01Y1029637D01*
G03X1363322Y1029449I200J0D01*
G01X1363676Y1029321D01*
G03X1363897Y1029380I68J188D01*
G02X1365049Y1029918I1152J-964D01*
G02X1366551Y1028416I0J-1502D01*
G02X1366286Y1027564I-1502J0D01*
G01X1366255Y1027519D01*
X1366248Y1027407D01*
X1366439Y1027045D01*
G03X1366616Y1026938I177J93D01*
G01X1367235D01*
G02X1368580Y1026381I0J-1902D01*
G01X1372177Y1022784D01*
G02X1372734Y1021439I-1345J-1345D01*
G01Y1020521D01*
G03X1372832Y1020349I200J0D01*
G01X1373175Y1020147D01*
X1373281Y1020146D01*
X1373328Y1020172D01*
G02X1374059Y1020362I731J-1311D01*
G02X1375561Y1018860I0J-1502D01*
G02X1375554Y1018721I-1502J6D01*
G01Y1018719D01*
X1375550Y1018672D01*
X1375585Y1018584D01*
X1375864Y1018338D01*
G03X1376037Y1018292I132J150D01*
G01X1376038D01*
G02X1376359Y1018327I322J-1467D01*
G02Y1015323I0J-1502D01*
G01X1376358D01*
G02X1375884Y1015400I1J1502D01*
G01X1375849Y1015412D01*
X1375776Y1015409D01*
X1375463Y1015274D01*
X1375411Y1015224D01*
X1375395Y1015190D01*
G02X1374034Y1014323I-1361J635D01*
G02X1373085Y1014662I1J1500D01*
G01X1373083D01*
X1373049Y1014690D01*
X1372965Y1014711D01*
X1372576Y1014640D01*
X1372505Y1014589D01*
X1372483Y1014550D01*
G02X1372177Y1014148I-1653J941D01*
G01X1369405Y1011376D01*
G03X1369346Y1011234I141J-142D01*
G01Y1004634D01*
G03X1369405Y1004492I200J0D01*
G01X1373615Y1000282D01*
G02X1374172Y998937I-1345J-1345D01*
G01Y993825D01*
G03X1374231Y993683I200J0D01*
G01X1382542Y985371D01*
G03X1382684Y985312I142J141D01*
G01X1404153D01*
G03X1404295Y985371I0J200D01*
G01X1406511Y987587D01*
G03X1406569Y987750I-141J142D01*
G01X1406536Y988059D01*
G03X1406446Y988206I-199J-21D01*
G02X1405763Y989465I819J1259D01*
G02X1407265Y990967I1502J0D01*
G02X1408524Y990284I0J-1502D01*
G03X1408671Y990194I168J109D01*
G01X1408980Y990161D01*
G03X1409143Y990219I21J199D01*
G01X1412575Y993652D01*
G02X1413917Y994208I1344J-1346D01*
G01X1416618D01*
G02Y990406I0J-1901D01*
G01X1414791D01*
G03X1414649Y990347I0J-200D01*
G01X1406369Y982066D01*
G02X1405027Y981510I-1344J1346D01*
G01X1381810D01*
G02X1380468Y982066I2J1902D01*
G01X1370925Y991609D01*
G02X1370368Y992954I1345J1345D01*
G01Y998066D01*
G03X1370309Y998208I-200J0D01*
G01X1366099Y1002418D01*
G02X1365668Y1003082I1345J1345D01*
G01X1365655Y1003117D01*
X1365604Y1003173D01*
X1365294Y1003327D01*
X1365220Y1003334D01*
X1365184Y1003323D01*
G02X1364765Y1003264I-417J1443D01*
G02Y1006268I0J1502D01*
G02X1365063Y1006238I-1J-1502D01*
G01X1365108Y1006229D01*
X1365194Y1006250D01*
X1365469Y1006475D01*
G03X1365542Y1006630I-127J155D01*
G01Y1012105D01*
G02X1366099Y1013450I1902J0D01*
G01X1368871Y1016222D01*
G03X1368930Y1016364I-141J142D01*
G01Y1020568D01*
G03X1368871Y1020710I-200J0D01*
G01X1367499Y1022083D01*
G03X1367280Y1022127I-142J-141D01*
G01X1366882Y1021961D01*
X1366816Y1021860D01*
Y1021793D01*
G02X1365314Y1020291I-1502J0D01*
G02X1364674Y1020434I-1J1501D01*
G03X1364431Y1020377I-86J-181D01*
G01X1364399Y1020336D01*
G03X1364416Y1020071I158J-123D01*
G01X1364561Y1019926D01*
G02X1364620Y1019784I-141J-142D01*
G01Y1013236D01*
G02X1364561Y1013094I-200J0D01*
G01X1362260Y1010793D01*
G02X1362118Y1010734I-142J141D01*
G01X1340516D01*
G03X1340374Y1010675I0J-200D01*
G01X1320977Y991278D01*
G03X1320919Y991135I142J-141D01*
G01Y991015D01*
G03X1320973Y990880I200J2D01*
G02X1321371Y989974I-1099J-1023D01*
G01X1321375Y989927D01*
X1321423Y989847D01*
X1321771Y989624D01*
X1321864Y989614D01*
X1321908Y989631D01*
G02X1322427Y989723I518J-1410D01*
G37*
G36*
G01X1350418Y1094590D02*
G02X1351920Y1093088I0J-1502D01*
G02X1351435Y1091982I-1504J0D01*
G03X1351370Y1091835I135J-148D01*
G01Y1091541D01*
G03X1351435Y1091394I200J1D01*
G02X1351920Y1090288I-1019J-1106D01*
G02X1350418Y1088786I-1502J0D01*
G02X1349579Y1089042I0J1503D01*
G01X1349578Y1089043D01*
G03X1349402Y1089066I-111J-166D01*
G01X1349056Y1088949D01*
X1348991Y1088883D01*
X1348976Y1088838D01*
G02X1348684Y1088330I-1423J480D01*
G01Y1088328D01*
X1348683D01*
G03X1348635Y1088198I152J-130D01*
G01Y1087934D01*
G03X1348683Y1087804I200J0D01*
G01X1348684Y1087803D01*
G02Y1085829I-1131J-987D01*
G01Y1085828D01*
X1348683D01*
G03X1348635Y1085698I152J-130D01*
G01Y1085434D01*
G03X1348683Y1085304I200J0D01*
G01X1348684Y1085303D01*
G02Y1083329I-1131J-987D01*
G01Y1083328D01*
X1348683D01*
G03X1348635Y1083198I152J-130D01*
G01Y1082934D01*
G03X1348683Y1082804I200J0D01*
G01X1348684Y1082803D01*
G02X1349054Y1081816I-1131J-987D01*
G02X1347552Y1080314I-1502J0D01*
G02X1346565Y1080684I0J1501D01*
G01X1346564D01*
Y1080685D01*
G03X1346434Y1080733I-130J-152D01*
G01X1346170D01*
G03X1346040Y1080685I0J-200D01*
G01X1346039Y1080684D01*
G02X1345052Y1080314I-987J1131D01*
G02X1343550Y1081816I0J1502D01*
G02X1343920Y1082803I1501J0D01*
G01Y1082804D01*
X1343921D01*
G03X1343969Y1082934I-152J130D01*
G01Y1083198D01*
G03X1343921Y1083328I-200J0D01*
G01X1343920Y1083329D01*
G02Y1085303I1131J987D01*
G01Y1085304D01*
X1343921D01*
G03X1343969Y1085434I-152J130D01*
G01Y1085698D01*
G03X1343921Y1085828I-200J0D01*
G01X1343920Y1085829D01*
G02X1343550Y1086816I1131J987D01*
G02X1345052Y1088318I1502J0D01*
G02X1346100Y1087892I0J-1502D01*
G03X1346239Y1087835I140J143D01*
G01X1346365D01*
G03X1346504Y1087892I-1J200D01*
G02X1346533Y1087919I1038J-1086D01*
G01Y1088129D01*
G03X1346476Y1088268I-200J-1D01*
G02X1346050Y1089316I1076J1048D01*
G02X1346420Y1090303I1501J0D01*
G01Y1090304D01*
X1346421D01*
G03X1346469Y1090434I-152J130D01*
G01Y1090698D01*
G03X1346421Y1090828I-200J0D01*
G01X1346420Y1090829D01*
G02X1346050Y1091816I1131J987D01*
G02X1347552Y1093318I1502J0D01*
G01X1347554D01*
G02X1348339Y1093096I-1J-1502D01*
G01X1348381Y1093070D01*
X1348479Y1093063D01*
X1348872Y1093238D01*
X1348932Y1093314D01*
X1348941Y1093363D01*
G02X1350418Y1094590I1477J-275D01*
G37*
G36*
G01X1321519Y1093956D02*
G02X1324523I1502J0D01*
G02X1323944Y1092771I-1502J0D01*
G03X1323867Y1092613I123J-158D01*
G01Y1092299D01*
G03X1323944Y1092141I200J0D01*
G02X1324523Y1090956I-923J-1185D01*
G02X1323863Y1089712I-1502J0D01*
G01X1323820Y1089683D01*
X1323773Y1089589D01*
X1323796Y1089142D01*
X1323852Y1089054D01*
X1323899Y1089029D01*
G02X1324225Y1088792I-712J-1322D01*
G01X1324226Y1088791D01*
G03X1324396Y1088739I137J146D01*
G01X1324759Y1088800D01*
X1324834Y1088855D01*
X1324856Y1088897D01*
G02X1325399Y1089482I1333J-692D01*
G01X1325400Y1089483D01*
G03X1325493Y1089634I-106J169D01*
G01X1325527Y1089999D01*
X1325493Y1090086D01*
X1325458Y1090118D01*
G02X1324969Y1091227I1013J1109D01*
G02X1327973I1502J0D01*
G02X1327261Y1089950I-1501J0D01*
G01X1327260Y1089949D01*
G03X1327167Y1089798I106J-169D01*
G01X1327133Y1089433D01*
X1327167Y1089346D01*
X1327202Y1089314D01*
G02X1327374Y1089128I-1013J-1109D01*
G03X1327532Y1089051I158J123D01*
G01X1327846D01*
G03X1328004Y1089128I0J200D01*
G02X1329189Y1089707I1185J-923D01*
G02X1330691Y1088205I0J-1502D01*
G02X1330112Y1087020I-1502J0D01*
G03X1330035Y1086862I123J-158D01*
G01Y1086548D01*
G03X1330112Y1086390I200J0D01*
G02X1330691Y1085205I-923J-1185D01*
G02X1330235Y1084127I-1502J0D01*
G01X1330206Y1084099D01*
X1330175Y1084026D01*
X1330171Y1083661D01*
X1330201Y1083588D01*
X1330230Y1083559D01*
G02X1330665Y1082502I-1067J-1057D01*
G01Y1082501D01*
G02X1329163Y1080999I-1502J0D01*
G02X1327978Y1081578I0J1502D01*
G03X1327820Y1081655I-158J-123D01*
G01X1327506D01*
G03X1327348Y1081578I0J-200D01*
G02X1324978I-1185J923D01*
G03X1324820Y1081655I-158J-123D01*
G01X1324506D01*
G03X1324348Y1081578I0J-200D01*
G02X1323163Y1080999I-1185J923D01*
G02X1321661Y1082501I0J1502D01*
G02X1322117Y1083579I1502J0D01*
G01X1322146Y1083607D01*
X1322177Y1083680D01*
X1322181Y1084045D01*
X1322151Y1084118D01*
X1322122Y1084147D01*
G02X1321687Y1085204I1067J1057D01*
G01Y1085205D01*
G02X1322057Y1086192I1501J0D01*
G01Y1086193D01*
X1322058D01*
G03X1322106Y1086323I-152J130D01*
G01Y1086587D01*
G03X1322058Y1086717I-200J0D01*
G01X1322057Y1086718D01*
G02X1321687Y1087705I1131J987D01*
G02X1322347Y1088949I1502J0D01*
G01X1322390Y1088978D01*
X1322437Y1089072D01*
X1322414Y1089519D01*
X1322358Y1089607D01*
X1322311Y1089632D01*
G02X1321519Y1090956I711J1324D01*
G02X1322098Y1092141I1502J0D01*
G03X1322175Y1092299I-123J158D01*
G01Y1092613D01*
G03X1322098Y1092771I-200J0D01*
G02X1321519Y1093956I923J1185D01*
G37*
G36*
G01X1369795Y1106897D02*
G02X1372799I1502J0D01*
G02X1371397Y1105398I-1502J0D01*
G01X1371350Y1105395D01*
X1371268Y1105347D01*
X1371042Y1104998D01*
X1371032Y1104905D01*
X1371049Y1104860D01*
G02X1371144Y1104335I-1407J-526D01*
G02X1371087Y1103925I-1503J0D01*
G01X1371075Y1103881D01*
X1371090Y1103792D01*
X1371298Y1103500D01*
G03X1371448Y1103416I163J115D01*
G01X1371449D01*
G02X1372864Y1101917I-86J-1499D01*
G02X1369860I-1502J0D01*
G02X1369917Y1102327I1503J0D01*
G01X1369929Y1102371D01*
X1369914Y1102460D01*
X1369706Y1102752D01*
G03X1369556Y1102836I-163J-115D01*
G01X1369555D01*
G02X1368201Y1103910I86J1499D01*
G01X1368189Y1103952D01*
X1368134Y1104016D01*
X1367827Y1104162D01*
G03X1367663Y1104166I-86J-180D01*
G02X1367084Y1104050I-579J1387D01*
G02X1365642Y1105133I0J1502D01*
G01Y1105134D01*
G03X1365549Y1105251I-192J-57D01*
G01X1365308Y1105389D01*
G03X1365161Y1105410I-100J-173D01*
G02X1365100Y1105396I-366J1457D01*
G01X1365099D01*
G03X1364979Y1105318I42J-196D01*
G01X1364798Y1105068D01*
X1364779Y1104996D01*
X1364783Y1104959D01*
G02X1364792Y1104792I-1493J-164D01*
G02X1364703Y1104284I-1502J1D01*
G01X1364692Y1104251D01*
Y1096829D01*
G02X1364281Y1095838I-1402J1D01*
G01X1360481Y1092037D01*
G03X1360422Y1091895I141J-142D01*
G01Y1065449D01*
G03X1360481Y1065307I200J0D01*
G01X1382975Y1042812D01*
G02X1383386Y1041821I-991J-992D01*
G01Y1036605D01*
G02X1382975Y1035614I-1402J1D01*
G01X1381635Y1034273D01*
G03X1381576Y1034131I141J-142D01*
G01Y1030519D01*
G03X1381635Y1030377I200J0D01*
G01X1387418Y1024593D01*
G02X1387828Y1023603I-991J-990D01*
G01Y1010643D01*
G03X1387887Y1010501I200J0D01*
G01X1392639Y1005749D01*
X1392671Y1005734D01*
G02X1393533Y1004375I-640J-1359D01*
G02X1392031Y1002873I-1502J0D01*
G02X1390672Y1003735I0J1502D01*
G01X1390657Y1003767D01*
X1385436Y1008988D01*
G02X1385026Y1009978I991J990D01*
G01Y1022938D01*
G03X1384967Y1023080I-200J0D01*
G01X1379183Y1028864D01*
G02X1378772Y1029855I991J992D01*
G01Y1034795D01*
G02X1379183Y1035786I1402J-1D01*
G01X1380523Y1037127D01*
G03X1380582Y1037269I-141J142D01*
G01Y1041157D01*
G03X1380523Y1041299I-200J0D01*
G01X1358029Y1063794D01*
G02X1357618Y1064785I991J992D01*
G01Y1092559D01*
G02X1358029Y1093550I1402J-1D01*
G01X1361829Y1097351D01*
G03X1361888Y1097493I-141J142D01*
G01Y1104251D01*
X1361877Y1104284D01*
G02X1361788Y1104792I1413J509D01*
G02X1362987Y1106263I1502J0D01*
G01X1362988D01*
G03X1363108Y1106341I-42J196D01*
G01X1363289Y1106591D01*
X1363308Y1106663D01*
X1363304Y1106700D01*
G02X1363295Y1106867I1493J164D01*
G02X1364797Y1108369I1502J0D01*
G02X1366239Y1107286I0J-1502D01*
G01Y1107285D01*
G03X1366332Y1107168I192J57D01*
G01X1366573Y1107030D01*
G03X1366720Y1107009I100J173D01*
G02X1367084Y1107054I365J-1457D01*
G02X1368525Y1105977I0J-1503D01*
G01X1368537Y1105935D01*
X1368592Y1105871D01*
X1368899Y1105725D01*
G03X1369063Y1105721I86J180D01*
G02X1369542Y1105834I580J-1386D01*
G01X1369589Y1105837D01*
X1369671Y1105885D01*
X1369897Y1106234D01*
X1369907Y1106327D01*
X1369890Y1106372D01*
G02X1369795Y1106897I1407J526D01*
G37*
G36*
G01X1405600Y1031220D02*
G02X1405190Y1030230I-1401J0D01*
G01X1401473Y1026513D01*
G03X1401414Y1026371I141J-142D01*
G01Y1022300D01*
G03X1401488Y1022144I200J-1D01*
G01X1401731Y1021948D01*
G03X1401898Y1021908I126J156D01*
G01X1401899D01*
G02X1402215Y1021942I318J-1468D01*
G02Y1018938I0J-1502D01*
G02X1401899Y1018972I2J1502D01*
G01X1401898D01*
G03X1401731Y1018932I-41J-196D01*
G01X1401488Y1018736D01*
G03X1401414Y1018580I126J-155D01*
G01Y999329D01*
G02X1401004Y998339I-1401J0D01*
G01X1397954Y995289D01*
G02X1396963Y994878I-992J991D01*
G01X1382060D01*
X1382027Y994867D01*
G02X1381519Y994778I-509J1413D01*
G02Y997782I0J1502D01*
G02X1382027Y997693I-1J-1502D01*
G01X1382060Y997682D01*
X1396299D01*
G03X1396441Y997741I0J200D01*
G01X1398553Y999852D01*
G03X1398612Y999994I-141J142D01*
G01Y1027036D01*
G02X1399022Y1028026I1401J0D01*
G01X1402739Y1031743D01*
G03X1402798Y1031885I-141J142D01*
G01Y1039708D01*
G03X1402739Y1039850I-200J0D01*
G01X1392280Y1050309D01*
G03X1392138Y1050368I-142J-141D01*
G01X1389165D01*
G02X1388175Y1050778I0J1401D01*
G01X1378703Y1060250D01*
G02X1378292Y1061241I991J992D01*
G01Y1096012D01*
G02X1378703Y1097003I1402J-1D01*
G01X1384505Y1102805D01*
G02X1385496Y1103216I992J-991D01*
G01X1393107D01*
G03X1393249Y1103275I0J200D01*
G01X1395375Y1105400D01*
X1395390Y1105432D01*
G02X1396446Y1106263I1359J-640D01*
G01X1396447D01*
G03X1396567Y1106341I-42J196D01*
G01X1396748Y1106591D01*
X1396767Y1106663D01*
X1396763Y1106700D01*
G02X1396754Y1106867I1493J164D01*
G02X1398256Y1108369I1502J0D01*
G02X1399698Y1107286I0J-1502D01*
G01Y1107285D01*
G03X1399791Y1107168I192J57D01*
G01X1400032Y1107030D01*
G03X1400179Y1107009I100J173D01*
G02X1400543Y1107054I365J-1457D01*
G02X1401984Y1105977I0J-1503D01*
G01X1401996Y1105935D01*
X1402051Y1105871D01*
X1402358Y1105725D01*
G03X1402522Y1105721I86J180D01*
G02X1403001Y1105834I580J-1386D01*
G01X1403048Y1105837D01*
X1403130Y1105885D01*
X1403356Y1106234D01*
X1403366Y1106327D01*
X1403349Y1106372D01*
G02X1403254Y1106897I1407J526D01*
G02X1406258I1502J0D01*
G02X1404856Y1105398I-1502J0D01*
G01X1404809Y1105395D01*
X1404727Y1105347D01*
X1404501Y1104998D01*
X1404491Y1104905D01*
X1404508Y1104860D01*
G02X1404603Y1104335I-1407J-526D01*
G02X1404546Y1103925I-1503J0D01*
G01X1404534Y1103881D01*
X1404549Y1103792D01*
X1404757Y1103500D01*
G03X1404907Y1103416I163J115D01*
G01X1404908D01*
G02X1406323Y1101917I-86J-1499D01*
G02X1403319I-1502J0D01*
G02X1403376Y1102327I1503J0D01*
G01X1403388Y1102371D01*
X1403373Y1102460D01*
X1403165Y1102752D01*
G03X1403015Y1102836I-163J-115D01*
G01X1403014D01*
G02X1401660Y1103910I86J1499D01*
G01X1401648Y1103952D01*
X1401593Y1104016D01*
X1401286Y1104162D01*
G03X1401122Y1104166I-86J-180D01*
G02X1400543Y1104050I-579J1387D01*
G02X1399101Y1105133I0J1502D01*
G01Y1105134D01*
G03X1399008Y1105251I-192J-57D01*
G01X1398767Y1105389D01*
G03X1398620Y1105410I-100J-173D01*
G02X1398559Y1105396I-366J1457D01*
G01X1398558D01*
G03X1398438Y1105318I42J-196D01*
G01X1398257Y1105068D01*
X1398238Y1104996D01*
X1398242Y1104959D01*
G02X1398251Y1104792I-1493J-164D01*
G02X1397389Y1103433I-1502J0D01*
G01X1397357Y1103418D01*
X1394762Y1100823D01*
G02X1393771Y1100412I-992J991D01*
G01X1386160D01*
G03X1386018Y1100353I0J-200D01*
G01X1381155Y1095490D01*
G03X1381096Y1095348I141J-142D01*
G01Y1061905D01*
G03X1381155Y1061763I200J0D01*
G01X1389688Y1053229D01*
G03X1389830Y1053170I142J141D01*
G01X1392803D01*
G02X1393793Y1052760I0J-1401D01*
G01X1405190Y1041363D01*
G02X1405600Y1040373I-991J-990D01*
G01Y1031220D01*
G37*
G36*
G01X1435382Y1106897D02*
G02X1438386I1502J0D01*
G02X1436984Y1105398I-1502J0D01*
G01X1436937Y1105395D01*
X1436855Y1105347D01*
X1436629Y1104998D01*
X1436619Y1104905D01*
X1436636Y1104860D01*
G02X1436731Y1104335I-1407J-526D01*
G02X1436674Y1103925I-1503J0D01*
G01X1436662Y1103881D01*
X1436677Y1103792D01*
X1436885Y1103500D01*
G03X1437035Y1103416I163J115D01*
G01X1437036D01*
G02X1438451Y1101917I-86J-1499D01*
G02X1435447I-1502J0D01*
G02X1435504Y1102327I1503J0D01*
G01X1435516Y1102371D01*
X1435501Y1102460D01*
X1435293Y1102752D01*
G03X1435143Y1102836I-163J-115D01*
G01X1435142D01*
G02X1433788Y1103910I86J1499D01*
G01X1433776Y1103952D01*
X1433721Y1104016D01*
X1433414Y1104162D01*
G03X1433250Y1104166I-86J-180D01*
G02X1432671Y1104050I-579J1387D01*
G02X1431229Y1105133I0J1502D01*
G01Y1105134D01*
G03X1431136Y1105251I-192J-57D01*
G01X1430895Y1105389D01*
G03X1430748Y1105410I-100J-173D01*
G02X1430687Y1105396I-366J1457D01*
G01X1430686D01*
G03X1430566Y1105318I42J-196D01*
G01X1430385Y1105068D01*
X1430366Y1104996D01*
X1430370Y1104959D01*
G02X1430379Y1104792I-1493J-164D01*
G02X1430290Y1104284I-1502J1D01*
G01X1430278Y1104251D01*
Y1098293D01*
G03X1430337Y1098151I200J0D01*
G01X1433689Y1094799D01*
G02X1434100Y1093808I-991J-992D01*
G01Y1050515D01*
G02X1433689Y1049524I-1402J1D01*
G01X1410597Y1026431D01*
G03X1410538Y1026289I141J-142D01*
G01Y1014670D01*
G02X1410127Y1013679I-1402J1D01*
G01X1406601Y1010152D01*
G03X1406542Y1010010I141J-142D01*
G01Y998407D01*
G02X1406131Y997416I-1402J1D01*
G01X1400292Y991577D01*
G02X1399301Y991166I-992J991D01*
G01X1389733D01*
X1389700Y991155D01*
G02X1389192Y991066I-509J1413D01*
G02Y994070I0J1502D01*
G02X1389700Y993981I-1J-1502D01*
G01X1389733Y993970D01*
X1398637D01*
G03X1398779Y994029I0J200D01*
G01X1403679Y998929D01*
G03X1403738Y999071I-141J142D01*
G01Y1010674D01*
G02X1404149Y1011665I1402J-1D01*
G01X1407675Y1015192D01*
G03X1407734Y1015334I-141J142D01*
G01Y1026953D01*
G02X1408145Y1027944I1402J-1D01*
G01X1431237Y1051037D01*
G03X1431296Y1051179I-141J142D01*
G01Y1093144D01*
G03X1431237Y1093286I-200J0D01*
G01X1427886Y1096638D01*
G02X1427476Y1097628I991J990D01*
G01Y1104251D01*
X1427464Y1104284D01*
G02X1427375Y1104792I1413J509D01*
G02X1428574Y1106263I1502J0D01*
G01X1428575D01*
G03X1428695Y1106341I-42J196D01*
G01X1428876Y1106591D01*
X1428895Y1106663D01*
X1428891Y1106700D01*
G02X1428882Y1106867I1493J164D01*
G02X1430384Y1108369I1502J0D01*
G02X1431826Y1107286I0J-1502D01*
G01Y1107285D01*
G03X1431919Y1107168I192J57D01*
G01X1432160Y1107030D01*
G03X1432307Y1107009I100J173D01*
G02X1432671Y1107054I365J-1457D01*
G02X1434112Y1105977I0J-1503D01*
G01X1434124Y1105935D01*
X1434179Y1105871D01*
X1434486Y1105725D01*
G03X1434650Y1105721I86J180D01*
G02X1435129Y1105834I580J-1386D01*
G01X1435176Y1105837D01*
X1435258Y1105885D01*
X1435484Y1106234D01*
X1435494Y1106327D01*
X1435477Y1106372D01*
G02X1435382Y1106897I1407J526D01*
G37*
G36*
G01X1438888Y461652D02*
G02X1440390Y463154I1502J0D01*
G02X1441377Y462784I0J-1501D01*
G01X1441378D01*
Y462783D01*
G03X1441508Y462735I130J152D01*
G01X1441772D01*
G03X1441902Y462783I0J200D01*
G01X1441903Y462784D01*
G02X1442890Y463154I987J-1131D01*
G02X1444392Y461652I0J-1502D01*
G02X1444022Y460665I-1501J0D01*
G01Y460664D01*
X1444021D01*
G03X1443973Y460534I152J-130D01*
G01Y460270D01*
G03X1444021Y460140I200J0D01*
G01X1444022Y460139D01*
G02Y458165I-1131J-987D01*
G01Y458164D01*
X1444021D01*
G03X1443973Y458034I152J-130D01*
G01Y457770D01*
G03X1444021Y457640I200J0D01*
G01X1444022Y457639D01*
G02X1444392Y456652I-1131J-987D01*
G02X1442890Y455150I-1502J0D01*
G02X1441903Y455520I0J1501D01*
G01X1441902D01*
Y455521D01*
G03X1441772Y455569I-130J-152D01*
G01X1441508D01*
G03X1441378Y455521I0J-200D01*
G01X1441377Y455520D01*
G02X1440390Y455150I-987J1131D01*
G02X1438888Y456652I0J1502D01*
G02X1439258Y457639I1501J0D01*
G01Y457640D01*
X1439259D01*
G03X1439307Y457770I-152J130D01*
G01Y458034D01*
G03X1439259Y458164I-200J0D01*
G01X1439258Y458165D01*
G02Y460139I1131J987D01*
G01Y460140D01*
X1439259D01*
G03X1439307Y460270I-152J130D01*
G01Y460534D01*
G03X1439259Y460664I-200J0D01*
G01X1439258Y460665D01*
G02X1438888Y461652I1131J987D01*
G37*
G36*
G01X1424882Y478625D02*
G02X1427886I1502J0D01*
G02X1427516Y477638I-1501J0D01*
G01Y477637D01*
X1427515D01*
G03X1427467Y477507I152J-130D01*
G01Y477243D01*
G03X1427515Y477113I200J0D01*
G01X1427516Y477112D01*
G02X1427886Y476125I-1131J-987D01*
G02X1424882I-1502J0D01*
G02X1425252Y477112I1501J0D01*
G01Y477113D01*
X1425253D01*
G03X1425301Y477243I-152J130D01*
G01Y477507D01*
G03X1425253Y477637I-200J0D01*
G01X1425252Y477638D01*
G02X1424882Y478625I1131J987D01*
G37*
G36*
G01X1425986Y486270D02*
X1425987Y486269D01*
G03X1426117Y486221I130J152D01*
G01X1426381D01*
G03X1426511Y486269I0J200D01*
G01X1426512Y486270D01*
G02X1427499Y486640I987J-1131D01*
G02X1429001Y485138I0J-1502D01*
G02X1428734Y484283I-1502J0D01*
G01X1428711Y484249D01*
X1428694Y484168D01*
X1428774Y483801D01*
X1428822Y483734D01*
X1428857Y483713D01*
G02X1429586Y482425I-773J-1288D01*
G02X1426582I-1502J0D01*
G02X1426849Y483280I1502J0D01*
G01X1426872Y483314D01*
X1426889Y483395D01*
X1426809Y483762D01*
X1426761Y483829D01*
X1426726Y483850D01*
G02X1426513Y484006I777J1285D01*
G03X1426511Y484007I-88J-173D01*
G03X1426381Y484055I-130J-152D01*
G01X1426117D01*
G03X1425987Y484007I0J-200D01*
G01X1425986Y484006D01*
G02X1424012I-987J1131D01*
G01X1424011D01*
Y484007D01*
G03X1423881Y484055I-130J-152D01*
G01X1423617D01*
G03X1423487Y484007I0J-200D01*
G01X1423486Y484006D01*
G02X1422499Y483636I-987J1131D01*
G02X1421378Y484139I0J1501D01*
G01X1421349Y484172D01*
X1421272Y484206D01*
X1420927Y484204D01*
G03X1420779Y484138I0J-200D01*
G01X1420778Y484137D01*
G02X1419650Y483626I-1129J991D01*
G02Y486630I0J1502D01*
G02X1420771Y486127I0J-1501D01*
G01X1420800Y486094D01*
X1420877Y486060D01*
X1421222Y486062D01*
G03X1421370Y486128I0J200D01*
G01X1421371Y486129D01*
G02X1422499Y486640I1129J-991D01*
G02X1423486Y486270I0J-1501D01*
G01X1423487D01*
Y486269D01*
G03X1423617Y486221I130J152D01*
G01X1423881D01*
G03X1424011Y486269I0J200D01*
G01X1424012Y486270D01*
G02X1425986I987J-1131D01*
G37*
G36*
G01X1432458Y493714D02*
G02X1435462I1502J0D01*
G02X1435092Y492727I-1501J0D01*
G01Y492726D01*
X1435091D01*
G03X1435043Y492596I152J-130D01*
G01Y492332D01*
G03X1435091Y492202I200J0D01*
G01X1435092Y492201D01*
G02X1435462Y491214I-1131J-987D01*
G02X1432458I-1502J0D01*
G02X1432828Y492201I1501J0D01*
G01Y492202D01*
X1432829D01*
G03X1432877Y492332I-152J130D01*
G01Y492596D01*
G03X1432829Y492726I-200J0D01*
G01X1432828Y492727D01*
G02X1432458Y493714I1131J987D01*
G37*
G36*
G01X1436161Y495487D02*
G02X1439165I1502J0D01*
G02X1438795Y494500I-1501J0D01*
G01Y494499D01*
X1438794D01*
G03X1438746Y494369I152J-130D01*
G01Y494105D01*
G03X1438794Y493975I200J0D01*
G01X1438795Y493974D01*
G02X1439165Y492987I-1131J-987D01*
G02X1436161I-1502J0D01*
G02X1436531Y493974I1501J0D01*
G01Y493975D01*
X1436532D01*
G03X1436580Y494105I-152J130D01*
G01Y494369D01*
G03X1436532Y494499I-200J0D01*
G01X1436531Y494500D01*
G02X1436161Y495487I1131J987D01*
G37*
G36*
G01X1447791Y498633D02*
G02X1450795I1502J0D01*
G02X1450425Y497646I-1501J0D01*
G01Y497645D01*
X1450424D01*
G03X1450376Y497515I152J-130D01*
G01Y497251D01*
G03X1450424Y497121I200J0D01*
G01X1450425Y497120D01*
G02Y495146I-1131J-987D01*
G01Y495145D01*
X1450424D01*
G03X1450376Y495015I152J-130D01*
G01Y494751D01*
G03X1450424Y494621I200J0D01*
G01X1450425Y494620D01*
G02Y492646I-1131J-987D01*
G01Y492645D01*
X1450424D01*
G03X1450376Y492515I152J-130D01*
G01Y492251D01*
G03X1450424Y492121I200J0D01*
G01X1450425Y492120D01*
G02X1450795Y491133I-1131J-987D01*
G02X1447791I-1502J0D01*
G02X1448161Y492120I1501J0D01*
G01Y492121D01*
X1448162D01*
G03X1448210Y492251I-152J130D01*
G01Y492515D01*
G03X1448162Y492645I-200J0D01*
G01X1448161Y492646D01*
G02Y494620I1131J987D01*
G01Y494621D01*
X1448162D01*
G03X1448210Y494751I-152J130D01*
G01Y495015D01*
G03X1448162Y495145I-200J0D01*
G01X1448161Y495146D01*
G02Y497120I1131J987D01*
G01Y497121D01*
X1448162D01*
G03X1448210Y497251I-152J130D01*
G01Y497515D01*
G03X1448162Y497645I-200J0D01*
G01X1448161Y497646D01*
G02X1447791Y498633I1131J987D01*
G37*
G36*
G01X1414548Y505957D02*
X1414549Y505956D01*
G03X1414679Y505908I130J152D01*
G01X1414943D01*
G03X1415073Y505956I0J200D01*
G01X1415074Y505957D01*
G02X1416061Y506327I987J-1131D01*
G02Y503323I0J-1502D01*
G02X1415074Y503693I0J1501D01*
G01X1415073D01*
Y503694D01*
G03X1414943Y503742I-130J-152D01*
G01X1414679D01*
G03X1414549Y503694I0J-200D01*
G01X1414548Y503693D01*
G02X1412574I-987J1131D01*
G01X1412573D01*
Y503694D01*
G03X1412443Y503742I-130J-152D01*
G01X1412179D01*
G03X1412049Y503694I0J-200D01*
G01X1412048Y503693D01*
G02X1411061Y503323I-987J1131D01*
G02Y506327I0J1502D01*
G02X1412048Y505957I0J-1501D01*
G01X1412049D01*
Y505956D01*
G03X1412179Y505908I130J152D01*
G01X1412443D01*
G03X1412573Y505956I0J200D01*
G01X1412574Y505957D01*
G02X1414548I987J-1131D01*
G37*
G36*
G01X1414489Y518533D02*
X1414490Y518532D01*
G03X1414620Y518484I130J152D01*
G01X1414884D01*
G03X1415014Y518532I0J200D01*
G01X1415015Y518533D01*
G02X1416002Y518903I987J-1131D01*
G02Y515899I0J-1502D01*
G02X1415015Y516269I0J1501D01*
G01X1415014D01*
Y516270D01*
G03X1414884Y516318I-130J-152D01*
G01X1414620D01*
G03X1414490Y516270I0J-200D01*
G01X1414489Y516269D01*
G02X1412515I-987J1131D01*
G01X1412514D01*
Y516270D01*
G03X1412384Y516318I-130J-152D01*
G01X1412120D01*
G03X1411990Y516270I0J-200D01*
G01X1411989Y516269D01*
G02X1411002Y515899I-987J1131D01*
G02Y518903I0J1502D01*
G02X1411989Y518533I0J-1501D01*
G01X1411990D01*
Y518532D01*
G03X1412120Y518484I130J152D01*
G01X1412384D01*
G03X1412514Y518532I0J200D01*
G01X1412515Y518533D01*
G02X1414489I987J-1131D01*
G37*
G36*
G01X1415601Y523822D02*
Y524116D01*
G03X1415536Y524263I-200J-1D01*
G02X1415051Y525369I1019J1106D01*
G02X1418055I1502J0D01*
G02X1417570Y524263I-1504J0D01*
G03X1417505Y524116I135J-148D01*
G01Y523822D01*
G03X1417570Y523675I200J1D01*
G02X1418055Y522569I-1019J-1106D01*
G02X1415051I-1502J0D01*
G02X1415536Y523675I1504J0D01*
G03X1415601Y523822I-135J148D01*
G37*
G36*
G01X1423177Y538911D02*
Y539205D01*
G03X1423112Y539352I-200J-1D01*
G02X1422627Y540458I1019J1106D01*
G02X1425631I1502J0D01*
G02X1425146Y539352I-1504J0D01*
G03X1425081Y539205I135J-148D01*
G01Y538911D01*
G03X1425146Y538764I200J1D01*
G02X1425631Y537658I-1019J-1106D01*
G02X1422627I-1502J0D01*
G02X1423112Y538764I1504J0D01*
G03X1423177Y538911I-135J148D01*
G37*
G36*
G01X1426330Y542231D02*
G02X1429334I1502J0D01*
G02X1428964Y541244I-1501J0D01*
G01Y541243D01*
X1428963D01*
G03X1428915Y541113I152J-130D01*
G01Y540849D01*
G03X1428963Y540719I200J0D01*
G01X1428964Y540718D01*
G02X1429334Y539731I-1131J-987D01*
G02X1426330I-1502J0D01*
G02X1426700Y540718I1501J0D01*
G01Y540719D01*
X1426701D01*
G03X1426749Y540849I-152J130D01*
G01Y541113D01*
G03X1426701Y541243I-200J0D01*
G01X1426700Y541244D01*
G02X1426330Y542231I1131J987D01*
G37*
G36*
G01X1416650Y554242D02*
X1416356D01*
G03X1416209Y554177I1J-200D01*
G02X1415103Y553692I-1106J1019D01*
G02Y556696I0J1502D01*
G02X1416209Y556211I0J-1504D01*
G03X1416356Y556146I148J135D01*
G01X1416650D01*
G03X1416797Y556211I-1J200D01*
G02X1417903Y556696I1106J-1019D01*
G02Y553692I0J-1502D01*
G02X1416797Y554177I0J1504D01*
G03X1416650Y554242I-148J-135D01*
G37*
G36*
G01Y562242D02*
X1416356D01*
G03X1416209Y562177I1J-200D01*
G02X1415103Y561692I-1106J1019D01*
G02Y564696I0J1502D01*
G02X1416209Y564211I0J-1504D01*
G03X1416356Y564146I148J135D01*
G01X1416650D01*
G03X1416797Y564211I-1J200D01*
G02X1417903Y564696I1106J-1019D01*
G02Y561692I0J-1502D01*
G02X1416797Y562177I0J1504D01*
G03X1416650Y562242I-148J-135D01*
G37*
G36*
G01Y570242D02*
X1416356D01*
G03X1416209Y570177I1J-200D01*
G02X1415103Y569692I-1106J1019D01*
G02Y572696I0J1502D01*
G02X1416209Y572211I0J-1504D01*
G03X1416356Y572146I148J135D01*
G01X1416650D01*
G03X1416797Y572211I-1J200D01*
G02X1417903Y572696I1106J-1019D01*
G02Y569692I0J-1502D01*
G02X1416797Y570177I0J1504D01*
G03X1416650Y570242I-148J-135D01*
G37*
G36*
G01X1417913Y582174D02*
X1418207D01*
G03X1418354Y582239I-1J200D01*
G02X1420566I1106J-1017D01*
G03X1420713Y582174I148J135D01*
G01X1421007D01*
G03X1421154Y582239I-1J200D01*
G02X1422260Y582724I1106J-1019D01*
G02Y579720I0J-1502D01*
G02X1421154Y580205I0J1504D01*
G03X1421007Y580270I-148J-135D01*
G01X1420713D01*
G03X1420566Y580205I1J-200D01*
G02X1418354I-1106J1017D01*
G03X1418207Y580270I-148J-135D01*
G01X1417913D01*
G03X1417766Y580205I1J-200D01*
G02X1416660Y579720I-1106J1019D01*
G02Y582724I0J1502D01*
G02X1417766Y582239I0J-1504D01*
G03X1417913Y582174I148J135D01*
G37*
G36*
G01Y592167D02*
X1418207D01*
G03X1418354Y592232I-1J200D01*
G02X1420566I1106J-1017D01*
G03X1420713Y592167I148J135D01*
G01X1421007D01*
G03X1421154Y592232I-1J200D01*
G02X1422260Y592717I1106J-1019D01*
G02Y589713I0J-1502D01*
G02X1421154Y590198I0J1504D01*
G03X1421007Y590263I-148J-135D01*
G01X1420713D01*
G03X1420566Y590198I1J-200D01*
G02X1418354I-1106J1017D01*
G03X1418207Y590263I-148J-135D01*
G01X1417913D01*
G03X1417766Y590198I1J-200D01*
G02X1416660Y589713I-1106J1019D01*
G02Y592717I0J1502D01*
G02X1417766Y592232I0J-1504D01*
G03X1417913Y592167I148J135D01*
G37*
G36*
G01X1420885Y611514D02*
X1421179D01*
G03X1421326Y611579I-1J200D01*
G02X1423538I1106J-1017D01*
G03X1423685Y611514I148J135D01*
G01X1423979D01*
G03X1424126Y611579I-1J200D01*
G02X1425232Y612064I1106J-1019D01*
G02X1426734Y610562I0J-1502D01*
G02X1426249Y609456I-1504J0D01*
G03X1426184Y609309I135J-148D01*
G01Y609015D01*
G03X1426249Y608868I200J1D01*
G02X1426734Y607762I-1019J-1106D01*
G02X1425232Y606260I-1502J0D01*
G02X1424126Y606745I0J1504D01*
G03X1423979Y606810I-148J-135D01*
G01X1423685D01*
G03X1423538Y606745I1J-200D01*
G02X1421326I-1106J1017D01*
G03X1421179Y606810I-148J-135D01*
G01X1420885D01*
G03X1420738Y606745I1J-200D01*
G02X1418526I-1106J1017D01*
G03X1418379Y606810I-148J-135D01*
G01X1418085D01*
G03X1417938Y606745I1J-200D01*
G02X1416832Y606260I-1106J1019D01*
G02X1415330Y607762I0J1502D01*
G02X1415815Y608868I1504J0D01*
G03X1415880Y609015I-135J148D01*
G01Y609309D01*
G03X1415815Y609456I-200J-1D01*
G02X1415330Y610562I1019J1106D01*
G02X1416832Y612064I1502J0D01*
G02X1417938Y611579I0J-1504D01*
G03X1418085Y611514I148J135D01*
G01X1418379D01*
G03X1418526Y611579I-1J200D01*
G02X1420738I1106J-1017D01*
G03X1420885Y611514I148J135D01*
G37*
G36*
G01X1439978Y617966D02*
Y618260D01*
G03X1439913Y618407I-200J-1D01*
G02X1439428Y619513I1019J1106D01*
G02X1442432I1502J0D01*
G02X1441947Y618407I-1504J0D01*
G03X1441882Y618260I135J-148D01*
G01Y617966D01*
G03X1441947Y617819I200J1D01*
G02Y615607I-1017J-1106D01*
G03X1441882Y615460I135J-148D01*
G01Y615166D01*
G03X1441947Y615019I200J1D01*
G02X1442432Y613913I-1019J-1106D01*
G02X1439428I-1502J0D01*
G02X1439913Y615019I1504J0D01*
G03X1439978Y615166I-135J148D01*
G01Y615460D01*
G03X1439913Y615607I-200J-1D01*
G02Y617819I1017J1106D01*
G03X1439978Y617966I-135J148D01*
G37*
G36*
G01X1452048Y618211D02*
Y618505D01*
G03X1451983Y618652I-200J-1D01*
G02X1451498Y619758I1019J1106D01*
G02X1454502I1502J0D01*
G02X1454017Y618652I-1504J0D01*
G03X1453952Y618505I135J-148D01*
G01Y618211D01*
G03X1454017Y618064I200J1D01*
G02Y615852I-1017J-1106D01*
G03X1453952Y615705I135J-148D01*
G01Y615411D01*
G03X1454017Y615264I200J1D01*
G02X1454502Y614158I-1019J-1106D01*
G02X1451498I-1502J0D01*
G02X1451983Y615264I1504J0D01*
G03X1452048Y615411I-135J148D01*
G01Y615705D01*
G03X1451983Y615852I-200J-1D01*
G02Y618064I1017J1106D01*
G03X1452048Y618211I-135J148D01*
G37*
G36*
G01X1432162Y619106D02*
Y619400D01*
G03X1432097Y619547I-200J-1D01*
G02X1431612Y620653I1019J1106D01*
G02X1434616I1502J0D01*
G02X1434131Y619547I-1504J0D01*
G03X1434066Y619400I135J-148D01*
G01Y619106D01*
G03X1434131Y618959I200J1D01*
G02X1434616Y617853I-1019J-1106D01*
G02X1431612I-1502J0D01*
G02X1432097Y618959I1504J0D01*
G03X1432162Y619106I-135J148D01*
G37*
G36*
G01X1425982Y462004D02*
G02X1428986I1502J0D01*
G02X1427627Y460509I-1502J0D01*
G03X1427473Y460411I19J-199D01*
G01X1427310Y460131D01*
G03X1427300Y459948I173J-101D01*
G02X1427429Y459339I-1373J-609D01*
G02X1427059Y458352I-1501J0D01*
G01Y458351D01*
X1427058D01*
G03X1427010Y458221I152J-130D01*
G01Y457957D01*
G03X1427058Y457827I200J0D01*
G01X1427059Y457826D01*
G02Y455852I-1131J-987D01*
G01Y455851D01*
X1427058D01*
G03X1427010Y455721I152J-130D01*
G01Y455457D01*
G03X1427058Y455327I200J0D01*
G01X1427059Y455326D01*
G02X1427429Y454339I-1131J-987D01*
G02X1425927Y452837I-1502J0D01*
G02X1424940Y453207I0J1501D01*
G01X1424939D01*
Y453208D01*
G03X1424809Y453256I-130J-152D01*
G01X1424545D01*
G03X1424415Y453208I0J-200D01*
G01X1424414Y453207D01*
G02X1423427Y452837I-987J1131D01*
G02X1421925Y454339I0J1502D01*
G02X1422295Y455326I1501J0D01*
G01Y455327D01*
X1422296D01*
G03X1422344Y455457I-152J130D01*
G01Y455721D01*
G03X1422296Y455851I-200J0D01*
G01X1422295Y455852D01*
G02Y457826I1131J987D01*
G01Y457827D01*
X1422296D01*
G03X1422344Y457957I-152J130D01*
G01Y458221D01*
G03X1422296Y458351I-200J0D01*
G01X1422295Y458352D01*
G02X1421925Y459339I1131J987D01*
G02X1423427Y460841I1502J0D01*
G02X1424414Y460471I0J-1501D01*
G01X1424415D01*
Y460470D01*
G03X1424545Y460422I130J152D01*
G01X1424809D01*
G03X1424939Y460470I0J200D01*
G01X1424940Y460471D01*
G02X1425784Y460834I987J-1132D01*
G03X1425938Y460932I-19J199D01*
G01X1426101Y461212D01*
G03X1426111Y461395I-173J101D01*
G02X1425982Y462004I1373J609D01*
G37*
G36*
G01X1443674Y499103D02*
X1443968D01*
G03X1444115Y499168I-1J200D01*
G02X1445221Y499653I1106J-1019D01*
G02X1446723Y498151I0J-1502D01*
G02X1446144Y496966I-1502J0D01*
G03X1446067Y496808I123J-158D01*
G01Y496494D01*
G03X1446144Y496336I200J0D01*
G02X1446723Y495151I-923J-1185D01*
G02X1445221Y493649I-1502J0D01*
G02X1444234Y494019I0J1501D01*
G01X1444233D01*
Y494020D01*
G03X1444103Y494068I-130J-152D01*
G01X1443839D01*
G03X1443709Y494020I0J-200D01*
G01X1443708Y494019D01*
G02X1442721Y493649I-987J1131D01*
G02X1441219Y495151I0J1502D01*
G02X1441691Y496244I1502J0D01*
G01X1441692Y496245D01*
G03X1441753Y496410I-138J145D01*
G01X1441722Y496725D01*
G03X1441628Y496875I-199J-20D01*
G02X1440919Y498151I794J1276D01*
G02X1442421Y499653I1502J0D01*
G02X1443527Y499168I0J-1504D01*
G03X1443674Y499103I148J135D01*
G37*
G36*
G01X1409618Y530446D02*
G02Y533450I0J1502D01*
G02X1410842Y532819I0J-1503D01*
G01X1410869Y532780D01*
X1410953Y532736D01*
X1411321Y532728D01*
G03X1411483Y532805I4J200D01*
G02X1412668Y533384I1185J-923D01*
G02X1413655Y533014I0J-1501D01*
G01X1413656D01*
Y533013D01*
G03X1413786Y532965I130J152D01*
G01X1414050D01*
G03X1414180Y533013I0J200D01*
G01X1414181Y533014D01*
G02X1416155I987J-1131D01*
G01X1416156D01*
Y533013D01*
G03X1416286Y532965I130J152D01*
G01X1416550D01*
G03X1416680Y533013I0J200D01*
G01X1416681Y533014D01*
G02X1417668Y533384I987J-1131D01*
G02X1419170Y531882I0J-1502D01*
G02X1418903Y531027I-1502J0D01*
G01X1418880Y530993D01*
X1418863Y530912D01*
X1418943Y530545D01*
X1418991Y530478D01*
X1419026Y530457D01*
G02X1419755Y529169I-773J-1288D01*
G02X1416751I-1502J0D01*
G02X1417018Y530024I1502J0D01*
G01X1417041Y530058D01*
X1417058Y530139D01*
X1416978Y530506D01*
X1416930Y530573D01*
X1416895Y530594D01*
G02X1416682Y530750I777J1285D01*
G03X1416680Y530751I-88J-173D01*
G03X1416550Y530799I-130J-152D01*
G01X1416286D01*
G03X1416156Y530751I0J-200D01*
G01X1416155Y530750D01*
G02X1414181I-987J1131D01*
G01X1414180D01*
Y530751D01*
G03X1414050Y530799I-130J-152D01*
G01X1413786D01*
G03X1413656Y530751I0J-200D01*
G01X1413655Y530750D01*
G02X1412668Y530380I-987J1131D01*
G02X1411444Y531011I0J1503D01*
G01X1411417Y531050D01*
X1411333Y531094D01*
X1410965Y531102D01*
G03X1410803Y531025I-4J-200D01*
G02X1409618Y530446I-1185J923D01*
G37*
G36*
G01X1433843Y545847D02*
X1434137D01*
G03X1434284Y545912I-1J200D01*
G02X1435390Y546397I1106J-1019D01*
G02X1436892Y544895I0J-1502D01*
G02X1436313Y543710I-1502J0D01*
G03X1436236Y543552I123J-158D01*
G01Y543238D01*
G03X1436313Y543080I200J0D01*
G02X1436892Y541895I-923J-1185D01*
G02X1435390Y540393I-1502J0D01*
G02X1434403Y540763I0J1501D01*
G01X1434402D01*
Y540764D01*
G03X1434272Y540812I-130J-152D01*
G01X1434008D01*
G03X1433878Y540764I0J-200D01*
G01X1433877Y540763D01*
G02X1432890Y540393I-987J1131D01*
G02X1431388Y541895I0J1502D01*
G02X1431860Y542988I1502J0D01*
G01X1431861Y542989D01*
G03X1431922Y543154I-138J145D01*
G01X1431891Y543469D01*
G03X1431797Y543619I-199J-20D01*
G02X1431088Y544895I794J1276D01*
G02X1432590Y546397I1502J0D01*
G02X1433696Y545912I0J-1504D01*
G03X1433843Y545847I148J135D01*
G37*
G36*
G01X1446988Y549920D02*
G02Y546916I0J-1502D01*
G02X1446001Y547286I0J1501D01*
G01X1446000D01*
Y547287D01*
G03X1445870Y547335I-130J-152D01*
G01X1445606D01*
G03X1445476Y547287I0J-200D01*
G01X1445475Y547286D01*
G02X1443501I-987J1131D01*
G01X1443500D01*
Y547287D01*
G03X1443370Y547335I-130J-152D01*
G01X1443106D01*
G03X1442976Y547287I0J-200D01*
G01X1442975Y547286D01*
G02X1441001I-987J1131D01*
G01X1441000D01*
Y547287D01*
G03X1440870Y547335I-130J-152D01*
G01X1440606D01*
G03X1440476Y547287I0J-200D01*
G01X1440475Y547286D01*
G02X1440381Y547211I-983J1135D01*
G03X1440379Y547209I140J-142D01*
G03X1440299Y547051I120J-160D01*
G01X1440296Y546731D01*
G03X1440375Y546570I200J-2D01*
G02X1440964Y545377I-914J-1193D01*
G02X1440594Y544390I-1501J0D01*
G01Y544389D01*
X1440593D01*
G03X1440545Y544259I152J-130D01*
G01Y543995D01*
G03X1440593Y543865I200J0D01*
G01X1440594Y543864D01*
G02Y541890I-1131J-987D01*
G01Y541889D01*
X1440593D01*
G03X1440545Y541759I152J-130D01*
G01Y541495D01*
G03X1440593Y541365I200J0D01*
G01X1440594Y541364D01*
G02Y539390I-1131J-987D01*
G01Y539389D01*
X1440593D01*
G03X1440545Y539259I152J-130D01*
G01Y538995D01*
G03X1440593Y538865I200J0D01*
G01X1440594Y538864D01*
G02X1440964Y537877I-1131J-987D01*
G02X1437960I-1502J0D01*
G02X1438330Y538864I1501J0D01*
G01Y538865D01*
X1438331D01*
G03X1438379Y538995I-152J130D01*
G01Y539259D01*
G03X1438331Y539389I-200J0D01*
G01X1438330Y539390D01*
G02Y541364I1131J987D01*
G01Y541365D01*
X1438331D01*
G03X1438379Y541495I-152J130D01*
G01Y541759D01*
G03X1438331Y541889I-200J0D01*
G01X1438330Y541890D01*
G02Y543864I1131J987D01*
G01Y543865D01*
X1438331D01*
G03X1438379Y543995I-152J130D01*
G01Y544259D01*
G03X1438331Y544389I-200J0D01*
G01X1438330Y544390D01*
G02X1437960Y545377I1131J987D01*
G02X1438569Y546585I1501J1D01*
G01X1438571D01*
Y546586D01*
G03X1438651Y546744I-120J160D01*
G01X1438654Y547064D01*
G03X1438575Y547225I-200J2D01*
G02X1437986Y548418I914J1193D01*
G02X1439488Y549920I1502J0D01*
G02X1440475Y549550I0J-1501D01*
G01X1440476D01*
Y549549D01*
G03X1440606Y549501I130J152D01*
G01X1440870D01*
G03X1441000Y549549I0J200D01*
G01X1441001Y549550D01*
G02X1442975I987J-1131D01*
G01X1442976D01*
Y549549D01*
G03X1443106Y549501I130J152D01*
G01X1443370D01*
G03X1443500Y549549I0J200D01*
G01X1443501Y549550D01*
G02X1445475I987J-1131D01*
G01X1445476D01*
Y549549D01*
G03X1445606Y549501I130J152D01*
G01X1445870D01*
G03X1446000Y549549I0J200D01*
G01X1446001Y549550D01*
G02X1446988Y549920I987J-1131D01*
G37*
G36*
G01X1447891Y566797D02*
G02X1450895I1502J0D01*
G02X1450263Y565573I-1501J0D01*
G03X1450179Y565410I116J-163D01*
G01Y565084D01*
G03X1450263Y564921I200J0D01*
G02X1450895Y563697I-869J-1224D01*
G02X1450489Y562670I-1502J0D01*
G01X1450463Y562643D01*
X1450435Y562572D01*
Y562222D01*
X1450463Y562151D01*
X1450489Y562124D01*
G02Y560070I-1096J-1027D01*
G01X1450463Y560043D01*
X1450435Y559972D01*
Y559622D01*
X1450463Y559551D01*
X1450489Y559524D01*
G02Y557470I-1096J-1027D01*
G01X1450463Y557443D01*
X1450435Y557372D01*
Y557022D01*
X1450463Y556951D01*
X1450489Y556924D01*
G02Y554870I-1096J-1027D01*
G01X1450463Y554843D01*
X1450435Y554772D01*
Y554422D01*
X1450463Y554351D01*
X1450489Y554324D01*
G02X1450895Y553297I-1096J-1027D01*
G02X1447891I-1502J0D01*
G02X1448297Y554324I1502J0D01*
G01X1448323Y554351D01*
X1448351Y554422D01*
Y554772D01*
X1448323Y554843D01*
X1448297Y554870D01*
G02Y556924I1096J1027D01*
G01X1448323Y556951D01*
X1448351Y557022D01*
Y557372D01*
X1448323Y557443D01*
X1448297Y557470D01*
G02Y559524I1096J1027D01*
G01X1448323Y559551D01*
X1448351Y559622D01*
Y559972D01*
X1448323Y560043D01*
X1448297Y560070D01*
G02Y562124I1096J1027D01*
G01X1448323Y562151D01*
X1448351Y562222D01*
Y562572D01*
X1448323Y562643D01*
X1448297Y562670D01*
G02X1447891Y563697I1096J1027D01*
G02X1448523Y564921I1501J0D01*
G03X1448607Y565084I-116J163D01*
G01Y565410D01*
G03X1448523Y565573I-200J0D01*
G02X1447891Y566797I869J1224D01*
G37*
G36*
G01X1445098Y576484D02*
G02X1448102I1502J0D01*
G02X1447460Y575253I-1501J0D01*
G03X1447376Y575114I114J-164D01*
G01X1447333Y574778D01*
X1447357Y574697D01*
X1447385Y574665D01*
G02X1447745Y573689I-1143J-976D01*
G02X1447024Y572406I-1502J0D01*
G01X1446980Y572379D01*
X1446929Y572291D01*
X1446921Y571849D01*
X1446968Y571759D01*
X1447011Y571731D01*
G02X1447685Y570478I-828J-1253D01*
G02X1446183Y568976I-1502J0D01*
G02X1445004Y569547I0J1503D01*
G01X1444978Y569580D01*
X1444904Y569619D01*
X1444525Y569648D01*
X1444447Y569620D01*
X1444416Y569591D01*
G02X1443388Y569184I-1028J1095D01*
G02X1441886Y570686I0J1502D01*
G02X1442387Y571806I1502J0D01*
G01X1442416Y571831D01*
X1442450Y571901D01*
X1442475Y572215D01*
G03X1442431Y572356I-199J15D01*
G02X1442095Y573303I1167J947D01*
G02X1443597Y574805I1502J0D01*
G02X1444488Y574512I0J-1501D01*
G01X1444489D01*
X1444520Y574489D01*
X1444596Y574470D01*
X1444952Y574522D01*
X1445021Y574563D01*
X1445044Y574594D01*
G02X1445383Y574920I1198J-906D01*
G03X1445467Y575059I-114J164D01*
G01X1445510Y575395D01*
X1445486Y575476D01*
X1445458Y575508D01*
G02X1445098Y576484I1143J976D01*
G37*
G36*
G01X1415184Y619590D02*
G02X1414622Y620661I739J1071D01*
G02X1417226I1302J0D01*
G02X1416664Y619590I-1301J0D01*
G03Y618932I228J-329D01*
G02X1417226Y617861I-739J-1071D01*
G02X1414622I-1302J0D01*
G02X1415184Y618932I1301J0D01*
G03Y619590I-228J329D01*
G37*
G36*
G01X1418727D02*
G02X1418165Y620661I739J1071D01*
G02X1420769I1302J0D01*
G02X1420207Y619590I-1301J0D01*
G03Y618932I228J-329D01*
G02X1420769Y617861I-739J-1071D01*
G02X1418165I-1302J0D01*
G02X1418727Y618932I1301J0D01*
G03Y619590I-228J329D01*
G37*
G36*
G01X1422270D02*
G02X1421708Y620661I739J1071D01*
G02X1424312I1302J0D01*
G02X1423750Y619590I-1301J0D01*
G03Y618932I228J-329D01*
G02X1424312Y617861I-739J-1071D01*
G02X1421708I-1302J0D01*
G02X1422270Y618932I1301J0D01*
G03Y619590I-228J329D01*
G37*
G36*
G01X1425814D02*
G02X1425252Y620661I739J1071D01*
G02X1427856I1302J0D01*
G02X1427294Y619590I-1301J0D01*
G03Y618932I228J-329D01*
G02X1427856Y617861I-739J-1071D01*
G02X1425252I-1302J0D01*
G02X1425814Y618932I1301J0D01*
G03Y619590I-228J329D01*
G37*
G36*
G01X1512597Y1199824D02*
G02X1512811Y1199805I1J-1202D01*
G01X1512829Y1199802D01*
X1516111D01*
X1516128Y1199805D01*
G02X1516338Y1199823I207J-1184D01*
G02X1516548Y1199805I3J-1202D01*
G01X1516565Y1199802D01*
X1519851D01*
X1519868Y1199805D01*
G02X1520078Y1199823I207J-1184D01*
G02X1520288Y1199805I3J-1202D01*
G01X1520305Y1199802D01*
X1523592D01*
X1523609Y1199805D01*
G02X1523819Y1199823I207J-1184D01*
G02X1524029Y1199805I3J-1202D01*
G01X1524046Y1199802D01*
X1527332D01*
X1527349Y1199805D01*
G02X1527559Y1199823I207J-1184D01*
G02X1527769Y1199805I3J-1202D01*
G01X1527786Y1199802D01*
X1531072D01*
X1531089Y1199805D01*
G02X1531299Y1199823I207J-1184D01*
G02X1531509Y1199805I3J-1202D01*
G01X1531526Y1199802D01*
X1534812D01*
X1534829Y1199805D01*
G02X1535039Y1199823I207J-1184D01*
G02X1535249Y1199805I3J-1202D01*
G01X1535266Y1199802D01*
X1538552D01*
X1538569Y1199805D01*
G02X1538779Y1199823I207J-1184D01*
G02X1538989Y1199805I3J-1202D01*
G01X1539006Y1199802D01*
X1542292D01*
X1542309Y1199805D01*
G02X1542519Y1199823I207J-1184D01*
G02X1542729Y1199805I3J-1202D01*
G01X1542746Y1199802D01*
X1546032D01*
X1546049Y1199805D01*
G02X1546259Y1199823I207J-1184D01*
G02X1546469Y1199805I3J-1202D01*
G01X1546486Y1199802D01*
X1549773D01*
X1549790Y1199805D01*
G02X1550000Y1199823I207J-1184D01*
G02X1550210Y1199805I3J-1202D01*
G01X1550227Y1199802D01*
X1554034D01*
G03X1554188Y1199874I0J200D01*
G01X1554414Y1200144D01*
X1554436Y1200230D01*
X1554428Y1200274D01*
G02X1554408Y1200491I1182J218D01*
G02X1556812I1202J0D01*
G02X1556792Y1200274I-1202J1D01*
G01X1556784Y1200230D01*
X1556806Y1200144D01*
X1557032Y1199874D01*
G03X1557186Y1199802I154J128D01*
G01X1557774D01*
G03X1557928Y1199874I0J200D01*
G01X1558154Y1200144D01*
X1558176Y1200230D01*
X1558168Y1200274D01*
G02X1558148Y1200491I1182J218D01*
G02X1560552I1202J0D01*
G02X1560532Y1200274I-1202J1D01*
G01X1560524Y1200230D01*
X1560546Y1200144D01*
X1560772Y1199874D01*
G03X1560926Y1199802I154J128D01*
G01X1561514D01*
G03X1561668Y1199874I0J200D01*
G01X1561894Y1200144D01*
X1561916Y1200230D01*
X1561908Y1200274D01*
G02X1561888Y1200491I1182J218D01*
G02X1564292I1202J0D01*
G02X1563987Y1199691I-1202J0D01*
G03X1563936Y1199557I149J-133D01*
G01Y1199437D01*
G03X1563995Y1199295I200J0D01*
G01X1565215Y1198074D01*
G02X1565274Y1197932I-141J-142D01*
G01Y1197860D01*
G03X1565399Y1197675I200J0D01*
G01X1565744Y1197536D01*
G03X1565963Y1197583I75J186D01*
G01Y1197584D01*
G02X1566830Y1197953I867J-834D01*
G02Y1195549I0J-1202D01*
G02X1565963Y1195918I0J1203D01*
G01Y1195919D01*
G03X1565744Y1195966I-144J-139D01*
G01X1565399Y1195827D01*
G03X1565274Y1195642I75J-185D01*
G01Y1194120D01*
G03X1565399Y1193935I200J0D01*
G01X1565744Y1193796D01*
G03X1565963Y1193843I75J186D01*
G01Y1193844D01*
G02X1566830Y1194213I867J-834D01*
G02Y1191809I0J-1202D01*
G02X1565963Y1192178I0J1203D01*
G01Y1192179D01*
G03X1565744Y1192226I-144J-139D01*
G01X1565399Y1192087D01*
G03X1565274Y1191902I75J-185D01*
G01Y1190380D01*
G03X1565399Y1190195I200J0D01*
G01X1565744Y1190056D01*
G03X1565963Y1190103I75J186D01*
G01Y1190104D01*
G02X1566830Y1190473I867J-834D01*
G02Y1188069I0J-1202D01*
G02X1565963Y1188438I0J1203D01*
G01Y1188439D01*
G03X1565744Y1188486I-144J-139D01*
G01X1565399Y1188347D01*
G03X1565274Y1188162I75J-185D01*
G01Y1186640D01*
G03X1565399Y1186455I200J0D01*
G01X1565744Y1186316D01*
G03X1565963Y1186363I75J186D01*
G01Y1186364D01*
G02X1566830Y1186733I867J-834D01*
G02Y1184329I0J-1202D01*
G02X1565963Y1184698I0J1203D01*
G01Y1184699D01*
G03X1565744Y1184746I-144J-139D01*
G01X1565399Y1184607D01*
G03X1565274Y1184422I75J-185D01*
G01Y1182900D01*
G03X1565399Y1182715I200J0D01*
G01X1565744Y1182576D01*
G03X1565963Y1182623I75J186D01*
G01Y1182624D01*
G02X1566830Y1182993I867J-834D01*
G02Y1180589I0J-1202D01*
G02X1565963Y1180958I0J1203D01*
G01Y1180959D01*
G03X1565744Y1181006I-144J-139D01*
G01X1565399Y1180867D01*
G03X1565274Y1180682I75J-185D01*
G01Y1179160D01*
G03X1565399Y1178975I200J0D01*
G01X1565744Y1178836D01*
G03X1565963Y1178883I75J186D01*
G01Y1178884D01*
G02X1566830Y1179253I867J-834D01*
G02Y1176849I0J-1202D01*
G02X1565963Y1177218I0J1203D01*
G01Y1177219D01*
G03X1565744Y1177266I-144J-139D01*
G01X1565399Y1177127D01*
G03X1565274Y1176942I75J-185D01*
G01Y1175968D01*
G02X1565215Y1175826I-200J0D01*
G01X1564280Y1174891D01*
G03X1564231Y1174687I141J-142D01*
G02X1564292Y1174310I-1141J-378D01*
G02X1563090Y1173108I-1202J0D01*
G02X1561891Y1174225I0J1202D01*
G01Y1174227D01*
G03X1561828Y1174358I-199J-15D01*
G01X1561629Y1174544D01*
G03X1561492Y1174598I-137J-146D01*
G01X1560948D01*
G03X1560811Y1174544I0J-200D01*
G01X1560612Y1174358D01*
G03X1560549Y1174227I136J-146D01*
G01Y1174226D01*
G02X1558151Y1174225I-1199J84D01*
G01Y1174227D01*
G03X1558088Y1174358I-199J-15D01*
G01X1557889Y1174544D01*
G03X1557752Y1174598I-137J-146D01*
G01X1557241D01*
G02X1557099Y1174657I0J200D01*
G01X1556998Y1174758D01*
G03X1556715I-141J-141D01*
G01X1556674Y1174717D01*
G02X1556584Y1174665I-142J141D01*
G01X1556389Y1174613D01*
G03X1556242Y1174393I51J-194D01*
G01X1556253Y1174317D01*
X1556366Y1174219D01*
X1556634Y1174221D01*
G02X1556735Y1174195I2J-200D01*
G01X1557272Y1173889D01*
G02X1557878Y1172846I-595J-1043D01*
G01Y1171761D01*
G03X1557997Y1171578I200J0D01*
G01X1558331Y1171430D01*
G03X1558545Y1171464I81J183D01*
G01X1558546D01*
G02X1559350Y1171772I804J-895D01*
G02Y1169368I0J-1202D01*
G02X1558546Y1169676I0J1203D01*
G01X1558545D01*
G03X1558331Y1169710I-133J-149D01*
G01X1557997Y1169562D01*
G03X1557878Y1169379I81J-183D01*
G01Y1168294D01*
G02X1557272Y1167251I-1201J0D01*
G01X1556735Y1166945D01*
G02X1556634Y1166919I-99J174D01*
G01X1556096Y1166924D01*
G02X1555997Y1166951I1J200D01*
G01X1555764Y1167087D01*
X1555762Y1167089D01*
G03X1555611Y1167130I-151J-259D01*
G01X1555610D01*
G03X1555310Y1166831I0J-300D01*
G03X1555322Y1166746I300J-1D01*
G03X1555324Y1166739I193J51D01*
G01X1555397Y1166516D01*
G02X1555404Y1166422I-190J-61D01*
G01X1555360Y1166143D01*
G03X1555405Y1165983I198J-31D01*
G03X1555558Y1165912I153J129D01*
G01X1555884D01*
G02X1556733Y1165560I-1J-1201D01*
G01X1557671Y1164622D01*
G02X1558024Y1163772I-849J-851D01*
G01Y1160657D01*
G03X1558132Y1160479I200J0D01*
G01X1558447Y1160316D01*
G03X1558654Y1160331I91J178D01*
G01X1558655D01*
G02X1559350Y1160552I695J-982D01*
G02Y1158148I0J-1202D01*
G02X1558655Y1158369I0J1203D01*
G01X1558654D01*
G03X1558447Y1158384I-116J-163D01*
G01X1558132Y1158221D01*
G03X1558024Y1158043I92J-178D01*
G01Y1157460D01*
G02X1557671Y1156610I-1202J1D01*
G01X1557458Y1156397D01*
G03X1557403Y1156222I142J-141D01*
G01X1557468Y1155851D01*
X1557527Y1155774D01*
X1557571Y1155753D01*
G02X1557629Y1155724I-508J-1089D01*
G01X1557668Y1155703D01*
X1557758Y1155698D01*
X1558128Y1155851D01*
X1558187Y1155917D01*
X1558200Y1155960D01*
G02X1559350Y1156812I1150J-350D01*
G02Y1154408I0J-1202D01*
G02X1558857Y1154514I1J1202D01*
G01X1558810Y1154535D01*
X1558710Y1154527D01*
X1558385Y1154317D01*
G03X1558294Y1154149I109J-168D01*
G01Y1153331D01*
G03X1558385Y1153163I200J0D01*
G01X1558667Y1152981D01*
G03X1558857Y1152966I109J168D01*
G02X1559350Y1153072I494J-1096D01*
G02X1560552Y1151870I0J-1202D01*
G02X1560024Y1150875I-1202J0D01*
G01X1559983Y1150847D01*
X1559937Y1150760D01*
Y1150710D01*
G03X1560137Y1150510I200J0D01*
G01X1560547D01*
G02X1561397Y1150157I-1J-1202D01*
G01X1561747Y1149807D01*
G02X1561938Y1149558I-850J-850D01*
G02X1562020Y1149388I-1038J-606D01*
G01Y1149386D01*
X1562025Y1149375D01*
X1562085Y1149316D01*
X1562398Y1149198D01*
G03X1562556Y1149206I70J187D01*
G01X1562557D01*
G02X1563090Y1149331I534J-1077D01*
G02Y1146927I0J-1202D01*
G02X1562647Y1147012I1J1202D01*
G01X1562646D01*
G03X1562461Y1146991I-73J-186D01*
G01X1562187Y1146806D01*
G03X1562100Y1146640I113J-165D01*
G01Y1145878D01*
G03X1562187Y1145712I200J-1D01*
G01X1562461Y1145527D01*
G03X1562646Y1145506I112J165D01*
G01X1562647D01*
G02X1563090Y1145591I444J-1117D01*
G02Y1143187I0J-1202D01*
G02X1562647Y1143272I1J1202D01*
G01X1562646D01*
G03X1562461Y1143251I-73J-186D01*
G01X1562187Y1143066D01*
G03X1562100Y1142900I113J-165D01*
G01Y1142138D01*
G03X1562187Y1141972I200J-1D01*
G01X1562461Y1141787D01*
G03X1562646Y1141766I112J165D01*
G01X1562647D01*
G02X1563090Y1141851I444J-1117D01*
G02Y1139447I0J-1202D01*
G02X1561974Y1140202I0J1202D01*
G01X1561959Y1140241D01*
X1561788Y1140411D01*
X1561764Y1140387D01*
G02X1561747Y1140369I-882J816D01*
G01X1561631Y1140254D01*
G02X1560423Y1139957I-849J850D01*
G02X1560350Y1139982I352J1148D01*
G02X1559942Y1139603I-1000J667D01*
G03X1559843Y1139400I99J-174D01*
G01X1559875Y1139183D01*
G02X1559884Y1138912I-1189J-175D01*
G02X1559760Y1138471I-1197J99D01*
G03X1559758Y1138465I187J-66D01*
G01X1559750Y1138448D01*
X1559745Y1138374D01*
X1559840Y1138074D01*
G03X1559932Y1137960I191J60D01*
G01X1559933D01*
G02X1560552Y1136909I-583J-1051D01*
G02X1558148I-1202J0D01*
G01Y1136922D01*
G03X1558090Y1137064I-200J1D01*
G01X1557891Y1137267D01*
G03X1557748Y1137326I-142J-141D01*
G01X1557212D01*
G03X1557069Y1137267I-1J-200D01*
G01X1556870Y1137064D01*
G03X1556812Y1136922I142J-141D01*
G01Y1136909D01*
G02X1554408I-1202J0D01*
G01Y1136922D01*
G03X1554350Y1137064I-200J1D01*
G01X1554151Y1137267D01*
G03X1554008Y1137326I-142J-141D01*
G01X1553472D01*
G03X1553329Y1137267I-1J-200D01*
G01X1553130Y1137064D01*
G03X1553072Y1136922I142J-141D01*
G01Y1136909D01*
G02X1550668I-1202J0D01*
G01Y1136922D01*
G03X1550610Y1137064I-200J1D01*
G01X1550411Y1137267D01*
G03X1550268Y1137326I-142J-141D01*
G01X1549732D01*
G03X1549589Y1137267I-1J-200D01*
G01X1549390Y1137064D01*
G03X1549332Y1136922I142J-141D01*
G01Y1136909D01*
G02X1546928I-1202J0D01*
G01Y1136922D01*
G03X1546870Y1137064I-200J1D01*
G01X1546671Y1137267D01*
G03X1546528Y1137326I-142J-141D01*
G01X1545991D01*
G03X1545848Y1137267I-1J-200D01*
G01X1545649Y1137064D01*
G03X1545591Y1136922I142J-141D01*
G01Y1136909D01*
G02X1543187I-1202J0D01*
G02X1543201Y1137095I1202J3D01*
G01X1543204Y1137110D01*
Y1137126D01*
G03X1543004Y1137326I-200J0D01*
G01X1542980D01*
G03X1542838Y1137267I0J-200D01*
G01X1542767Y1137196D01*
Y1137195D01*
G02X1541929Y1136842I-851J849D01*
G01X1541927D01*
X1541849Y1136840D01*
G02X1540718Y1135709I-1200J69D01*
G01X1540716Y1135637D01*
Y1135633D01*
G02X1540363Y1134791I-1202J9D01*
G01X1540362D01*
X1536867Y1131296D01*
G03X1536818Y1131092I141J-142D01*
G01X1536930Y1130752D01*
G03X1537089Y1130617I190J63D01*
G01X1537090D01*
G02X1538111Y1129429I-181J-1188D01*
G02X1535707I-1202J0D01*
G02X1535726Y1129640I1202J-2D01*
G01X1535734Y1129688D01*
X1535705Y1129781D01*
X1535670Y1129816D01*
G03X1535388I-141J-142D01*
G01X1535368Y1129797D01*
X1535287Y1129716D01*
Y1129715D01*
G02X1534449Y1129362I-851J849D01*
G01X1534447D01*
X1534369Y1129360D01*
G02X1533238Y1128229I-1200J69D01*
G01X1533236Y1128157D01*
Y1128153D01*
G02X1532883Y1127311I-1202J9D01*
G01X1532882D01*
X1532781Y1127210D01*
G03Y1126927I141J-141D01*
G01X1532816Y1126892D01*
X1532909Y1126863D01*
X1532957Y1126871D01*
G02X1533169Y1126890I213J-1183D01*
G02X1531967Y1125688I0J-1202D01*
G02X1531986Y1125900I1202J-1D01*
G01X1531994Y1125948D01*
X1531965Y1126041D01*
X1531871Y1126136D01*
X1531790D01*
G03X1531648Y1126077I0J-200D01*
G01X1531545Y1125973D01*
G02X1530708Y1125622I-849J851D01*
G01X1530705D01*
X1530629Y1125620D01*
G02X1529497Y1124488I-1200J68D01*
G01X1529495Y1124416D01*
Y1124412D01*
G02X1529144Y1123572I-1202J9D01*
G01X1528981Y1123410D01*
Y1123246D01*
X1529076Y1123152D01*
X1529169Y1123123D01*
X1529217Y1123131D01*
G02X1529429Y1123150I213J-1183D01*
G02X1528227Y1121948I0J-1202D01*
G02X1528246Y1122160I1202J-1D01*
G01X1528254Y1122208D01*
X1528225Y1122301D01*
X1528131Y1122396D01*
X1528050D01*
G03X1527908Y1122337I0J-200D01*
G01X1527805Y1122233D01*
G02X1526968Y1121882I-849J851D01*
G01X1526965D01*
X1526889Y1121880D01*
G02X1525757Y1120748I-1200J68D01*
G01X1525755Y1120676D01*
Y1120672D01*
G02X1525404Y1119832I-1202J9D01*
G01X1525241Y1119670D01*
Y1119506D01*
X1525336Y1119412D01*
X1525429Y1119383D01*
X1525477Y1119391D01*
G02X1525689Y1119410I213J-1183D01*
G02X1524487Y1118208I0J-1202D01*
G02X1524506Y1118420I1202J-1D01*
G01X1524514Y1118468D01*
X1524485Y1118561D01*
X1524391Y1118656D01*
X1524310D01*
G03X1524168Y1118597I0J-200D01*
G01X1524065Y1118493D01*
G02X1523228Y1118142I-849J851D01*
G01X1523225D01*
X1523149Y1118140D01*
G02X1522017Y1117008I-1200J68D01*
G01X1522015Y1116936D01*
Y1116932D01*
G02X1521664Y1116092I-1202J9D01*
G01X1521501Y1115930D01*
Y1115766D01*
X1521596Y1115672D01*
X1521689Y1115643D01*
X1521737Y1115651D01*
G02X1521949Y1115670I213J-1183D01*
G02Y1113266I0J-1202D01*
G02X1520750Y1114384I0J1202D01*
G03X1520653Y1114543I-200J-13D01*
G01X1520327Y1114736D01*
X1520230Y1114741D01*
X1520185Y1114720D01*
G02X1519978Y1114648I-497J1094D01*
G02X1519686Y1114612I-292J1165D01*
G01X1519609D01*
G03X1519409Y1114420I0J-200D01*
G02X1517007I-1201J48D01*
G03X1516807Y1114612I-200J-8D01*
G01X1515869D01*
G03X1515669Y1114420I0J-200D01*
G02X1513267I-1201J48D01*
G03X1513067Y1114612I-200J-8D01*
G01X1497790D01*
X1497679Y1114517D01*
X1497667Y1114444D01*
G02X1496185Y1113189I-1482J248D01*
G02X1494683Y1114691I0J1502D01*
G02X1494887Y1115446I1502J-1D01*
G01X1494921Y1115505D01*
X1494904Y1115639D01*
X1494043Y1116500D01*
G02X1493984Y1116642I141J142D01*
G01Y1125037D01*
G02X1494043Y1125179I200J0D01*
G01X1494727Y1125862D01*
X1494977Y1126112D01*
G03X1494995Y1126375I-141J142D01*
G01X1494994Y1126376D01*
G02X1494683Y1127291I1191J915D01*
G01Y1127294D01*
G02X1494756Y1127755I1502J-2D01*
G01X1494773Y1127808D01*
X1494747Y1127918D01*
X1493905Y1128761D01*
G02X1493846Y1128903I141J142D01*
G01Y1137282D01*
G02X1493905Y1137424I200J0D01*
G01X1495019Y1138538D01*
G03X1495077Y1138676I-142J141D01*
G01X1495080Y1138795D01*
G03X1495033Y1138927I-200J3D01*
G02X1494709Y1139611I1152J964D01*
G01X1494699Y1139664D01*
X1494629Y1139745D01*
X1494097Y1139928D01*
G02X1493286Y1141064I391J1136D01*
G01Y1150273D01*
G02X1493639Y1151123I1202J-1D01*
G01X1493909Y1151393D01*
G02X1494435Y1151701I850J-849D01*
G01X1494471Y1151711D01*
X1494532Y1151757D01*
X1494693Y1152025D01*
G03X1494717Y1152171I-171J103D01*
G02X1494683Y1152491I1468J318D01*
G02X1494752Y1152942I1502J1D01*
G01X1494770Y1152998D01*
X1494739Y1153112D01*
X1494467Y1153355D01*
G02X1494066Y1154250I800J896D01*
G01Y1162235D01*
G02X1494418Y1163084I1201J-1D01*
G01X1495078Y1163744D01*
G02X1495099Y1163764I839J-860D01*
G01X1495103Y1163967D01*
G03X1495054Y1164103I-200J5D01*
G02X1494693Y1164921I1131J988D01*
G01Y1164922D01*
G03X1494494Y1165098I-199J-24D01*
G01X1485384D01*
G03X1485185Y1164922I0J-200D01*
G01Y1164921D01*
G02X1483693Y1163589I-1492J170D01*
G02X1482191Y1165091I0J1502D01*
G02X1482775Y1166280I1502J0D01*
G01X1482786Y1166288D01*
X1482795Y1166297D01*
G03X1482794Y1166580I-142J141D01*
G01X1482744Y1166630D01*
X1482621Y1166754D01*
G02X1482469Y1166956I879J820D01*
G02X1482300Y1167540I1032J615D01*
G01Y1175825D01*
G02X1482458Y1176386I1201J-35D01*
G02X1482532Y1176501I1046J-592D01*
G03X1482526Y1176745I-161J118D01*
G02Y1178637I1167J946D01*
G03X1482532Y1178881I-155J126D01*
G02X1482458Y1178996I972J707D01*
G02X1482300Y1179557I1043J596D01*
G01Y1191260D01*
G02X1482359Y1191402I200J0D01*
G01X1490699Y1199743D01*
G02X1490841Y1199802I142J-141D01*
G01X1512365D01*
X1512383Y1199805D01*
G02X1512597Y1199824I213J-1183D01*
G37*
G36*
G01X1494638Y1105091D02*
G02X1497642I1502J0D01*
G02X1497081Y1103920I-1503J0D01*
G01X1497045Y1103891D01*
X1497006Y1103808D01*
X1497011Y1103446D01*
G03X1497090Y1103289I200J2D01*
G02X1497687Y1102091I-905J-1199D01*
G02X1494683I-1502J0D01*
G02X1495244Y1103262I1503J0D01*
G01X1495280Y1103291D01*
X1495319Y1103374D01*
X1495314Y1103736D01*
G03X1495235Y1103893I-200J-2D01*
G02X1494638Y1105091I905J1199D01*
G37*
G36*
G01X1480675Y1200601D02*
G02X1482177Y1202103I0J1502D01*
G02X1482168Y1201941I-1502J2D01*
G01X1482163Y1201897D01*
X1482192Y1201813D01*
X1482468Y1201527D01*
X1482551Y1201496D01*
X1482595Y1201499D01*
G02X1482704Y1201503I110J-1498D01*
G01X1482705D01*
G02X1481203Y1200001I0J-1502D01*
G02X1481212Y1200163I1502J-2D01*
G01X1481217Y1200207D01*
X1481188Y1200291D01*
X1480912Y1200577D01*
X1480829Y1200608D01*
X1480785Y1200605D01*
G02X1480676Y1200601I-110J1498D01*
G01X1480675D01*
G37*
G36*
G01X1545057Y1101377D02*
G02X1546259Y1100175I1202J0D01*
G02X1546037Y1100196I2J1202D01*
G01X1545988Y1100205D01*
X1545895Y1100176D01*
X1545590Y1099871D01*
X1545561Y1099778D01*
X1545570Y1099729D01*
G02X1545591Y1099507I-1181J-224D01*
G02X1545570Y1099285I-1202J2D01*
G01X1545561Y1099236D01*
X1545590Y1099143D01*
X1545895Y1098838D01*
X1545988Y1098809D01*
X1546037Y1098818D01*
G02X1546259Y1098839I224J-1181D01*
G02X1545057Y1097637I0J-1202D01*
G02X1545078Y1097859I1202J-2D01*
G01X1545087Y1097908D01*
X1545058Y1098001D01*
X1544753Y1098306D01*
X1544660Y1098335D01*
X1544611Y1098326D01*
G02X1544389Y1098305I-224J1181D01*
G02Y1100709I0J1202D01*
G02X1544611Y1100688I-2J-1202D01*
G01X1544660Y1100679D01*
X1544753Y1100708D01*
X1545058Y1101013D01*
X1545087Y1101106D01*
X1545078Y1101155D01*
G02X1545057Y1101377I1181J224D01*
G37*
G36*
G01X1544611Y1105807D02*
G02X1544389Y1105786I-224J1181D01*
G02X1545591Y1106988I0J1202D01*
G02X1545570Y1106765I-1202J1D01*
G03X1546037Y1106298I393J-74D01*
G02X1546259Y1106319I224J-1181D01*
G02X1545057Y1105117I0J-1202D01*
G02X1545078Y1105340I1202J-1D01*
G03X1544611Y1105807I-393J74D01*
G37*
G36*
G01X1550668Y1110728D02*
G02X1553072I1202J0D01*
G02X1553051Y1110506I-1202J2D01*
G01X1553042Y1110457D01*
X1553071Y1110364D01*
X1553376Y1110059D01*
X1553469Y1110030D01*
X1553518Y1110039D01*
G02X1553740Y1110060I224J-1181D01*
G02X1552538Y1108858I0J-1202D01*
G02X1552559Y1109080I1202J-2D01*
G01X1552568Y1109129D01*
X1552539Y1109222D01*
X1552234Y1109527D01*
X1552141Y1109556D01*
X1552092Y1109547D01*
G02X1551870Y1109526I-224J1181D01*
G02X1551648Y1109547I2J1202D01*
G01X1551599Y1109556D01*
X1551506Y1109527D01*
X1551201Y1109222D01*
X1551172Y1109129D01*
X1551181Y1109080D01*
G02X1551202Y1108858I-1181J-224D01*
G02X1548798I-1202J0D01*
G02X1548819Y1109080I1202J-2D01*
G01X1548828Y1109129D01*
X1548799Y1109222D01*
X1548494Y1109527D01*
X1548401Y1109556D01*
X1548352Y1109547D01*
G02X1548130Y1109526I-224J1181D01*
G02X1549332Y1110728I0J1202D01*
G02X1549311Y1110506I-1202J2D01*
G01X1549302Y1110457D01*
X1549331Y1110364D01*
X1549636Y1110059D01*
X1549729Y1110030D01*
X1549778Y1110039D01*
G02X1550000Y1110060I224J-1181D01*
G02X1550222Y1110039I-2J-1202D01*
G01X1550271Y1110030D01*
X1550364Y1110059D01*
X1550669Y1110364D01*
X1550698Y1110457D01*
X1550689Y1110506D01*
G02X1550668Y1110728I1181J224D01*
G37*
G36*
G01X1588069Y1114468D02*
G02X1589271Y1113266I1202J0D01*
G02X1589049Y1113287I2J1202D01*
G01X1589000Y1113296D01*
X1588907Y1113267D01*
X1588602Y1112962D01*
X1588573Y1112869D01*
X1588582Y1112820D01*
G02X1588603Y1112598I-1181J-224D01*
G02X1586199I-1202J0D01*
G02X1586220Y1112820I1202J-2D01*
G01X1586229Y1112869D01*
X1586200Y1112962D01*
X1585895Y1113267D01*
X1585802Y1113296D01*
X1585753Y1113287D01*
G02X1585531Y1113266I-224J1181D01*
G02X1586733Y1114468I0J1202D01*
G02X1586712Y1114246I-1202J2D01*
G01X1586703Y1114197D01*
X1586732Y1114104D01*
X1587037Y1113799D01*
X1587130Y1113770D01*
X1587179Y1113779D01*
G02X1587401Y1113800I224J-1181D01*
G02X1587623Y1113779I-2J-1202D01*
G01X1587672Y1113770D01*
X1587765Y1113799D01*
X1588070Y1114104D01*
X1588099Y1114197D01*
X1588090Y1114246D01*
G02X1588069Y1114468I1181J224D01*
G37*
G36*
G01X1553962Y1216141D02*
G02X1553740Y1216120I-224J1181D01*
G02X1554942Y1217322I0J1202D01*
G02X1554921Y1217100I-1202J2D01*
G03X1555388Y1216633I393J-74D01*
G02X1555610Y1216654I224J-1181D01*
G02X1554408Y1215452I0J-1202D01*
G02X1554429Y1215674I1202J-2D01*
G03X1553962Y1216141I-393J74D01*
G37*
G36*
G01X1567498Y1221062D02*
G02X1568700Y1219860I1202J0D01*
G02X1568478Y1219881I2J1202D01*
G01X1568429Y1219890D01*
X1568336Y1219861D01*
X1568031Y1219556D01*
X1568002Y1219463D01*
X1568011Y1219414D01*
G02X1568032Y1219192I-1181J-224D01*
G02X1565628I-1202J0D01*
G02X1565649Y1219414I1202J-2D01*
G01X1565658Y1219463D01*
X1565629Y1219556D01*
X1565324Y1219861D01*
X1565231Y1219890D01*
X1565182Y1219881D01*
G02X1564960Y1219860I-224J1181D01*
G02X1564738Y1219881I2J1202D01*
G01X1564689Y1219890D01*
X1564596Y1219861D01*
X1564291Y1219556D01*
X1564262Y1219463D01*
X1564271Y1219414D01*
G02X1564292Y1219192I-1181J-224D01*
G02X1561888I-1202J0D01*
G02X1561909Y1219414I1202J-2D01*
G01X1561918Y1219463D01*
X1561889Y1219556D01*
X1561584Y1219861D01*
X1561491Y1219890D01*
X1561442Y1219881D01*
G02X1561220Y1219860I-224J1181D01*
G02X1562422Y1221062I0J1202D01*
G02X1562401Y1220840I-1202J2D01*
G01X1562392Y1220791D01*
X1562421Y1220698D01*
X1562726Y1220393D01*
X1562819Y1220364D01*
X1562868Y1220373D01*
G02X1563090Y1220394I224J-1181D01*
G02X1563312Y1220373I-2J-1202D01*
G01X1563361Y1220364D01*
X1563454Y1220393D01*
X1563759Y1220698D01*
X1563788Y1220791D01*
X1563779Y1220840D01*
G02X1563758Y1221062I1181J224D01*
G02X1566162I1202J0D01*
G02X1566141Y1220840I-1202J2D01*
G01X1566132Y1220791D01*
X1566161Y1220698D01*
X1566466Y1220393D01*
X1566559Y1220364D01*
X1566608Y1220373D01*
G02X1566830Y1220394I224J-1181D01*
G02X1567052Y1220373I-2J-1202D01*
G01X1567101Y1220364D01*
X1567194Y1220393D01*
X1567499Y1220698D01*
X1567528Y1220791D01*
X1567519Y1220840D01*
G02X1567498Y1221062I1181J224D01*
G37*
G36*
G01X1597420D02*
G02X1598622Y1219860I1202J0D01*
G02X1598400Y1219881I2J1202D01*
G01X1598351Y1219890D01*
X1598258Y1219861D01*
X1597953Y1219556D01*
X1597924Y1219463D01*
X1597933Y1219414D01*
G02X1597954Y1219192I-1181J-224D01*
G02X1595550I-1202J0D01*
G02X1595571Y1219414I1202J-2D01*
G01X1595580Y1219463D01*
X1595551Y1219556D01*
X1595246Y1219861D01*
X1595153Y1219890D01*
X1595104Y1219881D01*
G02X1594882Y1219860I-224J1181D01*
G02X1594659Y1219881I1J1202D01*
G01X1594610Y1219890D01*
X1594517Y1219861D01*
X1594247Y1219592D01*
G03X1594192Y1219415I142J-141D01*
G01Y1219414D01*
G02X1594213Y1219192I-1181J-224D01*
G02X1593011Y1217990I-1202J0D01*
G02X1592789Y1218011I2J1202D01*
G01X1592740Y1218020D01*
X1592647Y1217991D01*
X1592342Y1217686D01*
X1592313Y1217593D01*
X1592322Y1217544D01*
G02X1592343Y1217322I-1181J-224D01*
G02X1592322Y1217101I-1202J3D01*
G01Y1217099D01*
G03X1592377Y1216922I197J-36D01*
G01X1592647Y1216653D01*
X1592740Y1216624D01*
X1592789Y1216633D01*
G02X1593012Y1216654I224J-1181D01*
G02X1591810Y1215452I0J-1202D01*
G02X1591831Y1215673I1202J-3D01*
G01Y1215675D01*
G03X1591776Y1215852I-197J36D01*
G01X1591506Y1216121D01*
X1591413Y1216150D01*
X1591364Y1216141D01*
G02X1591141Y1216120I-224J1181D01*
G02X1590919Y1216141I2J1202D01*
G01X1590870Y1216150D01*
X1590777Y1216121D01*
X1590472Y1215816D01*
X1590443Y1215723D01*
X1590452Y1215674D01*
G02X1590473Y1215452I-1181J-224D01*
G02X1589271Y1216654I-1202J0D01*
G02X1589493Y1216633I-2J-1202D01*
G01X1589542Y1216624D01*
X1589635Y1216653D01*
X1589940Y1216958D01*
X1589969Y1217051D01*
X1589960Y1217100D01*
G02X1589939Y1217322I1181J224D01*
G02X1591141Y1218524I1202J0D01*
G02X1591363Y1218503I-2J-1202D01*
G01X1591412Y1218494D01*
X1591505Y1218523D01*
X1591810Y1218828D01*
X1591839Y1218921D01*
X1591830Y1218970D01*
G02X1591809Y1219192I1181J224D01*
G02X1591830Y1219414I1202J-2D01*
G01X1591839Y1219463D01*
X1591810Y1219556D01*
X1591505Y1219861D01*
X1591412Y1219890D01*
X1591363Y1219881D01*
G02X1591141Y1219860I-224J1181D01*
G02X1592343Y1221062I0J1202D01*
G02X1592322Y1220840I-1202J2D01*
G01X1592313Y1220791D01*
X1592342Y1220698D01*
X1592647Y1220393D01*
X1592740Y1220364D01*
X1592789Y1220373D01*
G02X1593011Y1220394I224J-1181D01*
G02X1593234Y1220373I-1J-1202D01*
G01X1593283Y1220364D01*
X1593376Y1220393D01*
X1593646Y1220662D01*
G03X1593701Y1220839I-142J141D01*
G01Y1220840D01*
G02X1593680Y1221062I1181J224D01*
G02X1596084I1202J0D01*
G02X1596063Y1220840I-1202J2D01*
G01X1596054Y1220791D01*
X1596083Y1220698D01*
X1596388Y1220393D01*
X1596481Y1220364D01*
X1596530Y1220373D01*
G02X1596752Y1220394I224J-1181D01*
G02X1596974Y1220373I-2J-1202D01*
G01X1597023Y1220364D01*
X1597116Y1220393D01*
X1597421Y1220698D01*
X1597450Y1220791D01*
X1597441Y1220840D01*
G02X1597420Y1221062I1181J224D01*
G37*
G36*
G01X1429322Y262678D02*
G02Y265682I0J1502D01*
G02X1430309Y265312I0J-1501D01*
G01X1430310D01*
Y265311D01*
G03X1430440Y265263I130J152D01*
G01X1430704D01*
G03X1430834Y265311I0J200D01*
G01X1430835Y265312D01*
G02X1431822Y265682I987J-1131D01*
G02Y262678I0J-1502D01*
G02X1430835Y263048I0J1501D01*
G01X1430834D01*
Y263049D01*
G03X1430704Y263097I-130J-152D01*
G01X1430440D01*
G03X1430310Y263049I0J-200D01*
G01X1430309Y263048D01*
G02X1429322Y262678I-987J1131D01*
G37*
G36*
G01X1469007Y264395D02*
G02Y267399I0J1502D01*
G02X1469994Y267029I0J-1501D01*
G01X1469995D01*
Y267028D01*
G03X1470125Y266980I130J152D01*
G01X1470389D01*
G03X1470519Y267028I0J200D01*
G01X1470520Y267029D01*
G02X1471507Y267399I987J-1131D01*
G02Y264395I0J-1502D01*
G02X1470520Y264765I0J1501D01*
G01X1470519D01*
Y264766D01*
G03X1470389Y264814I-130J-152D01*
G01X1470125D01*
G03X1469995Y264766I0J-200D01*
G01X1469994Y264765D01*
G02X1469007Y264395I-987J1131D01*
G37*
G36*
G01X1439469Y270978D02*
X1439763D01*
G03X1439910Y271043I-1J200D01*
G02X1441016Y271528I1106J-1019D01*
G02X1442003Y271158I0J-1501D01*
G01X1442004D01*
Y271157D01*
G03X1442134Y271109I130J152D01*
G01X1442398D01*
G03X1442528Y271157I0J200D01*
G01X1442529Y271158D01*
G02X1443516Y271528I987J-1131D01*
G02X1445018Y270026I0J-1502D01*
G02X1444648Y269039I-1501J0D01*
G01Y269038D01*
X1444647D01*
G03X1444599Y268908I152J-130D01*
G01Y268644D01*
G03X1444647Y268514I200J0D01*
G01X1444648Y268513D01*
G02X1445018Y267526I-1131J-987D01*
G02X1443516Y266024I-1502J0D01*
G02X1442529Y266394I0J1501D01*
G01X1442528D01*
Y266395D01*
G03X1442398Y266443I-130J-152D01*
G01X1442134D01*
G03X1442004Y266395I0J-200D01*
G01X1442003Y266394D01*
G02X1441016Y266024I-987J1131D01*
G02X1439910Y266509I0J1504D01*
G03X1439763Y266574I-148J-135D01*
G01X1439469D01*
G03X1439322Y266509I1J-200D01*
G02X1438216Y266024I-1106J1019D01*
G02X1436714Y267526I0J1502D01*
G02X1437084Y268513I1501J0D01*
G01Y268514D01*
X1437085D01*
G03X1437133Y268644I-152J130D01*
G01Y268908D01*
G03X1437085Y269038I-200J0D01*
G01X1437084Y269039D01*
G02X1436714Y270026I1131J987D01*
G02X1438216Y271528I1502J0D01*
G02X1439322Y271043I0J-1504D01*
G03X1439469Y270978I148J135D01*
G37*
G36*
G01X1462547Y272197D02*
G02X1463653Y271712I0J-1504D01*
G03X1463800Y271647I148J135D01*
G01X1464094D01*
G03X1464241Y271712I-1J200D01*
G02X1465347Y272197I1106J-1019D01*
G02X1466849Y270695I0J-1502D01*
G02X1466479Y269708I-1501J0D01*
G01Y269707D01*
X1466478D01*
G03X1466430Y269577I152J-130D01*
G01Y269313D01*
G03X1466478Y269183I200J0D01*
G01X1466479Y269182D01*
G02X1466849Y268195I-1131J-987D01*
G02X1465347Y266693I-1502J0D01*
G02X1464241Y267178I0J1504D01*
G03X1464094Y267243I-148J-135D01*
G01X1463800D01*
G03X1463653Y267178I1J-200D01*
G02X1462547Y266693I-1106J1019D01*
G02X1461560Y267063I0J1501D01*
G01X1461559D01*
Y267064D01*
G03X1461429Y267112I-130J-152D01*
G01X1461165D01*
G03X1461035Y267064I0J-200D01*
G01X1461034Y267063D01*
G02X1460047Y266693I-987J1131D01*
G02X1458545Y268195I0J1502D01*
G02X1458915Y269182I1501J0D01*
G01Y269183D01*
X1458916D01*
G03X1458964Y269313I-152J130D01*
G01Y269577D01*
G03X1458916Y269707I-200J0D01*
G01X1458915Y269708D01*
G02X1458545Y270695I1131J987D01*
G02X1460047Y272197I1502J0D01*
G02X1461034Y271827I0J-1501D01*
G01X1461035D01*
Y271826D01*
G03X1461165Y271778I130J152D01*
G01X1461429D01*
G03X1461559Y271826I0J200D01*
G01X1461560Y271827D01*
G02X1462547Y272197I987J-1131D01*
G37*
G36*
G01X1447558Y352361D02*
G02X1450562I1502J0D01*
G02X1449798Y351053I-1502J0D01*
G03X1449698Y350911I97J-175D01*
G01X1449639Y350559D01*
X1449664Y350473D01*
X1449695Y350439D01*
G02X1450074Y349442I-1123J-998D01*
G01Y349441D01*
G02X1447070I-1502J0D01*
G02X1447834Y350749I1502J0D01*
G03X1447934Y350891I-97J175D01*
G01X1447993Y351243D01*
X1447968Y351329D01*
X1447937Y351363D01*
G02X1447558Y352360I1123J998D01*
G01Y352361D01*
G37*
G36*
G01X1447979Y331612D02*
G02X1447232Y332910I754J1298D01*
G02X1450236I1502J0D01*
G02X1449747Y331801I-1502J0D01*
G03X1449815Y331159I269J-296D01*
G02X1450562Y329861I-754J-1298D01*
G02X1447558I-1502J0D01*
G02X1448047Y330970I1502J0D01*
G03X1447979Y331612I-269J296D01*
G37*
G36*
G01X1495012Y821444D02*
G02X1496447Y822502I1435J-444D01*
G02Y819498I0J-1502D01*
G02X1495232Y820117I0J1502D01*
G03X1494527Y820000I-323J-236D01*
G02X1493092Y818942I-1435J444D01*
G02Y821946I0J1502D01*
G02X1494307Y821327I0J-1502D01*
G03X1495012Y821444I323J236D01*
G37*
G36*
G01X1495328Y941553D02*
X1495375Y941943D01*
X1495349Y942026D01*
X1495319Y942059D01*
G02X1494923Y943075I1105J1016D01*
G02X1497927I1502J0D01*
G02X1497252Y941821I-1502J0D01*
G01X1497215Y941797D01*
X1497169Y941723D01*
X1497122Y941333D01*
X1497148Y941250D01*
X1497178Y941217D01*
G02X1497574Y940201I-1105J-1016D01*
G02X1494570I-1502J0D01*
G02X1495245Y941455I1502J0D01*
G01X1495282Y941479D01*
X1495328Y941553D01*
G37*
G36*
G01X1510065Y972398D02*
G02X1509238Y973740I675J1342D01*
G02X1512242I1502J0D01*
G02X1511620Y972523I-1502J0D01*
G03X1511675Y971842I235J-324D01*
G02X1512502Y970500I-675J-1342D01*
G02X1509498I-1502J0D01*
G02X1510120Y971717I1502J0D01*
G03X1510065Y972398I-235J324D01*
G37*
G36*
G01X1635464Y263097D02*
X1635128D01*
X1635061Y263072D01*
X1635033Y263048D01*
G02X1634046Y262678I-987J1131D01*
G02Y265682I0J1502D01*
G02X1635033Y265312I0J-1501D01*
G01X1635061Y265288D01*
X1635128Y265263D01*
X1635464D01*
X1635531Y265288D01*
X1635559Y265312D01*
G02X1636546Y265682I987J-1131D01*
G02Y262678I0J-1502D01*
G02X1635559Y263048I0J1501D01*
G01X1635531Y263072D01*
X1635464Y263097D01*
G37*
G36*
G01X1675149Y264814D02*
X1674813D01*
X1674746Y264789D01*
X1674718Y264765D01*
G02X1673731Y264395I-987J1131D01*
G02Y267399I0J1502D01*
G02X1674718Y267029I0J-1501D01*
G01X1674746Y267005D01*
X1674813Y266980D01*
X1675149D01*
X1675216Y267005D01*
X1675244Y267029D01*
G02X1676231Y267399I987J-1131D01*
G02Y264395I0J-1502D01*
G02X1675244Y264765I0J1501D01*
G01X1675216Y264789D01*
X1675149Y264814D01*
G37*
G36*
G01X1644193Y270978D02*
X1644487D01*
G03X1644634Y271043I-1J200D01*
G02X1645740Y271528I1105J-1017D01*
G02X1646727Y271158I0J-1501D01*
G01X1646755Y271134D01*
X1646822Y271109D01*
X1647158D01*
X1647225Y271134D01*
X1647253Y271158D01*
G02X1648240Y271528I987J-1131D01*
G02X1649742Y270026I0J-1502D01*
G02X1649372Y269039I-1501J0D01*
G01X1649348Y269011D01*
X1649323Y268944D01*
Y268608D01*
X1649348Y268541D01*
X1649372Y268513D01*
G02X1649742Y267526I-1131J-987D01*
G02X1648240Y266024I-1502J0D01*
G02X1647253Y266394I0J1501D01*
G01X1647225Y266418D01*
X1647158Y266443D01*
X1646822D01*
X1646755Y266418D01*
X1646727Y266394D01*
G02X1645740Y266024I-987J1131D01*
G02X1644634Y266509I-1J1502D01*
G03X1644487Y266574I-148J-135D01*
G01X1644193D01*
G03X1644046Y266509I1J-200D01*
G02X1642940Y266024I-1105J1017D01*
G02X1641438Y267526I0J1502D01*
G02X1641808Y268513I1501J0D01*
G01X1641832Y268541D01*
X1641857Y268608D01*
Y268944D01*
X1641832Y269011D01*
X1641808Y269039D01*
G02X1641438Y270026I1131J987D01*
G02X1642940Y271528I1502J0D01*
G02X1644046Y271043I1J-1502D01*
G03X1644193Y270978I148J135D01*
G37*
G36*
G01X1665853Y271778D02*
X1666189D01*
X1666256Y271803D01*
X1666284Y271827D01*
G02X1667271Y272197I987J-1131D01*
G02X1668377Y271712I1J-1502D01*
G03X1668524Y271647I148J135D01*
G01X1668818D01*
G03X1668965Y271712I-1J200D01*
G02X1670071Y272197I1105J-1017D01*
G02X1671573Y270695I0J-1502D01*
G02X1671203Y269708I-1501J0D01*
G01X1671179Y269680D01*
X1671154Y269613D01*
Y269277D01*
X1671179Y269210D01*
X1671203Y269182D01*
G02X1671573Y268195I-1131J-987D01*
G02X1670071Y266693I-1502J0D01*
G02X1668965Y267178I-1J1502D01*
G03X1668818Y267243I-148J-135D01*
G01X1668524D01*
G03X1668377Y267178I1J-200D01*
G02X1667271Y266693I-1105J1017D01*
G02X1666284Y267063I0J1501D01*
G01X1666256Y267087D01*
X1666189Y267112D01*
X1665853D01*
X1665786Y267087D01*
X1665758Y267063D01*
G02X1664771Y266693I-987J1131D01*
G02X1663269Y268195I0J1502D01*
G02X1663639Y269182I1501J0D01*
G01X1663663Y269210D01*
X1663688Y269277D01*
Y269613D01*
X1663663Y269680D01*
X1663639Y269708D01*
G02X1663269Y270695I1131J987D01*
G02X1664771Y272197I1502J0D01*
G02X1665758Y271827I0J-1501D01*
G01X1665786Y271803D01*
X1665853Y271778D01*
G37*
G36*
G01X1662873Y1140649D02*
G02X1664075Y1139447I1202J0D01*
G02X1663852Y1139468I1J1202D01*
G01X1663803Y1139477D01*
X1663710Y1139448D01*
X1663440Y1139179D01*
G03X1663385Y1139002I142J-141D01*
G01Y1139001D01*
G02X1663406Y1138779I-1181J-224D01*
G02X1661002I-1202J0D01*
G02X1661023Y1139001I1202J-2D01*
G01X1661032Y1139050D01*
X1661003Y1139143D01*
X1660698Y1139448D01*
X1660605Y1139477D01*
X1660556Y1139468D01*
G02X1660334Y1139447I-224J1181D01*
G02X1661536Y1140649I0J1202D01*
G02X1661515Y1140427I-1202J2D01*
G01X1661506Y1140378D01*
X1661535Y1140285D01*
X1661840Y1139980D01*
X1661933Y1139951D01*
X1661982Y1139960D01*
G02X1662204Y1139981I224J-1181D01*
G02X1662427Y1139960I-1J-1202D01*
G01X1662476Y1139951D01*
X1662569Y1139980D01*
X1662839Y1140249D01*
G03X1662894Y1140426I-142J141D01*
G01Y1140427D01*
G02X1662873Y1140649I1181J224D01*
G37*
G36*
G01X1739075Y1148843D02*
G02X1738415Y1150087I842J1244D01*
G02X1741419I1502J0D01*
G02X1740759Y1148843I-1502J0D01*
G03Y1148181I224J-331D01*
G02X1741419Y1146937I-842J-1244D01*
G02X1738415I-1502J0D01*
G02X1739075Y1148181I1502J0D01*
G03Y1148843I-224J331D01*
G37*
G36*
G01X1723896Y1158669D02*
G02X1723796Y1158666I-95J1499D01*
G02X1725298Y1160168I0J1502D01*
G02X1725184Y1159594I-1502J0D01*
G03X1725580Y1159043I370J-152D01*
G02X1725680Y1159046I95J-1499D01*
G02X1724178Y1157544I0J-1502D01*
G02X1724292Y1158118I1502J0D01*
G03X1723896Y1158669I-370J152D01*
G37*
G36*
G01X1783220Y1146739D02*
X1782884D01*
X1782817Y1146714D01*
X1782789Y1146690D01*
G02X1781802Y1146320I-987J1131D01*
G02Y1149324I0J1502D01*
G02X1782789Y1148954I0J-1501D01*
G01X1782817Y1148930D01*
X1782884Y1148905D01*
X1783220D01*
X1783287Y1148930D01*
X1783315Y1148954D01*
G02X1784302Y1149324I987J-1131D01*
G02Y1146320I0J-1502D01*
G02X1783315Y1146690I0J1501D01*
G01X1783287Y1146714D01*
X1783220Y1146739D01*
G37*
G36*
G01X1795927Y1264627D02*
X1796263D01*
X1796330Y1264652D01*
X1796358Y1264676D01*
G02X1798332I987J-1131D01*
G01X1798360Y1264652D01*
X1798427Y1264627D01*
X1798763D01*
X1798830Y1264652D01*
X1798858Y1264676D01*
G02X1799845Y1265046I987J-1131D01*
G02X1801347Y1263544I0J-1502D01*
G02X1800977Y1262557I-1501J0D01*
G01X1800953Y1262529D01*
X1800928Y1262462D01*
Y1262126D01*
X1800953Y1262059D01*
X1800977Y1262031D01*
G02X1801347Y1261044I-1131J-987D01*
G02X1799845Y1259542I-1502J0D01*
G02X1798858Y1259912I0J1501D01*
G01X1798830Y1259936D01*
X1798763Y1259961D01*
X1798427D01*
X1798360Y1259936D01*
X1798332Y1259912D01*
G02X1796358I-987J1131D01*
G01X1796330Y1259936D01*
X1796263Y1259961D01*
X1795927D01*
X1795860Y1259936D01*
X1795832Y1259912D01*
G02X1794845Y1259542I-987J1131D01*
G02X1793343Y1261044I0J1502D01*
G02X1793713Y1262031I1501J0D01*
G01X1793737Y1262059D01*
X1793762Y1262126D01*
Y1262462D01*
X1793737Y1262529D01*
X1793713Y1262557D01*
G02X1793343Y1263544I1131J987D01*
G02X1794845Y1265046I1502J0D01*
G02X1795832Y1264676I0J-1501D01*
G01X1795860Y1264652D01*
X1795927Y1264627D01*
G37*
G36*
G01X1789555Y1083668D02*
X1789546Y1084014D01*
X1789517Y1084082D01*
X1789491Y1084109D01*
G02X1789070Y1085152I1081J1043D01*
G02X1792074I1502J0D01*
G02X1791706Y1084167I-1502J0D01*
G01X1791681Y1084139D01*
X1791656Y1084069D01*
X1791665Y1083723D01*
X1791694Y1083655D01*
X1791720Y1083628D01*
G02X1792141Y1082585I-1081J-1043D01*
G02X1789137I-1502J0D01*
G02X1789505Y1083570I1502J0D01*
G01X1789530Y1083598D01*
X1789555Y1083668D01*
G37*
G36*
G01X1778850Y1093393D02*
X1779202D01*
X1779271Y1093421D01*
X1779299Y1093447D01*
G02X1781353I1027J-1096D01*
G01X1781381Y1093421D01*
X1781450Y1093393D01*
X1781802D01*
X1781871Y1093421D01*
X1781899Y1093447D01*
G02X1782926Y1093853I1027J-1096D01*
G02X1784428Y1092351I0J-1502D01*
G02X1784058Y1091364I-1501J0D01*
G01X1784034Y1091336D01*
X1784009Y1091269D01*
Y1090933D01*
X1784034Y1090866D01*
X1784058Y1090838D01*
G02X1784428Y1089851I-1131J-987D01*
G02X1782926Y1088349I-1502J0D01*
G02X1781899Y1088755I0J1502D01*
G01X1781871Y1088781D01*
X1781802Y1088809D01*
X1781450D01*
X1781381Y1088781D01*
X1781353Y1088755D01*
G02X1779299I-1027J1096D01*
G01X1779271Y1088781D01*
X1779202Y1088809D01*
X1778850D01*
X1778781Y1088781D01*
X1778753Y1088755D01*
G02X1776699I-1027J1096D01*
G01X1776671Y1088781D01*
X1776602Y1088809D01*
X1776250D01*
X1776181Y1088781D01*
X1776153Y1088755D01*
G02X1775126Y1088349I-1027J1096D01*
G02X1773624Y1089851I0J1502D01*
G02X1773994Y1090838I1501J0D01*
G01X1774018Y1090866D01*
X1774043Y1090933D01*
Y1091269D01*
X1774018Y1091336D01*
X1773994Y1091364D01*
G02X1773624Y1092351I1131J987D01*
G02X1775126Y1093853I1502J0D01*
G02X1776153Y1093447I0J-1502D01*
G01X1776181Y1093421D01*
X1776250Y1093393D01*
X1776602D01*
X1776671Y1093421D01*
X1776699Y1093447D01*
G02X1778753I1027J-1096D01*
G01X1778781Y1093421D01*
X1778850Y1093393D01*
G37*
G36*
G01X1815910Y1095487D02*
Y1095803D01*
G03X1815833Y1095960I-200J-1D01*
G02X1815254Y1097145I923J1185D01*
G02X1818258I1502J0D01*
G02X1817679Y1095960I-1502J0D01*
G03X1817602Y1095803I123J-158D01*
G01Y1095487D01*
G03X1817679Y1095330I200J1D01*
G02X1818258Y1094145I-923J-1185D01*
G02X1815254I-1502J0D01*
G02X1815833Y1095330I1502J0D01*
G03X1815910Y1095487I-123J158D01*
G37*
G36*
G01X1815303Y1135829D02*
X1814967D01*
X1814900Y1135804D01*
X1814872Y1135780D01*
G02X1813885Y1135410I-987J1131D01*
G02Y1138414I0J1502D01*
G02X1814872Y1138044I0J-1501D01*
G01X1814900Y1138020D01*
X1814967Y1137995D01*
X1815303D01*
X1815370Y1138020D01*
X1815398Y1138044D01*
G02X1816385Y1138414I987J-1131D01*
G02Y1135410I0J-1502D01*
G02X1815398Y1135780I0J1501D01*
G01X1815370Y1135804D01*
X1815303Y1135829D01*
G37*
G54D48*
X898869Y351114D03*
X1779404Y826570D03*
X1791041Y818795D03*
X1651443Y981515D03*
X1173034Y765060D03*
X1190210Y900909D03*
X1192367Y903785D03*
X1193219Y940703D03*
X1191151Y936296D03*
X1174595Y771744D03*
X1176500Y784933D03*
X1184340Y851072D03*
X1185516Y844248D03*
X1183012Y856553D03*
X1180239Y868430D03*
X1187431Y868340D03*
X1185058Y883475D03*
X1181654Y894671D03*
X1187151Y921000D03*
X1189219Y940703D03*
X1182000Y936500D03*
X1162863Y678519D03*
X1159173Y678462D03*
X1169256Y694983D03*
X1166115Y718469D03*
X1163774Y713347D03*
X1171934Y733857D03*
X1164732Y802269D03*
X1169697Y791935D03*
X1164925Y791607D03*
X1173122Y802759D03*
X1161535Y844167D03*
X1163579Y850774D03*
X1174461Y914515D03*
X1152512Y728543D03*
X1148962Y747253D03*
X1147468Y766093D03*
X1152485Y764552D03*
X1154985Y802897D03*
X1153485Y813142D03*
X1145910Y803642D03*
X769609Y124283D03*
X775118Y110784D03*
X780118D03*
X779697Y124663D03*
X774675Y124879D03*
X810406Y448214D03*
X810453Y453330D03*
X824650Y450034D03*
Y455034D03*
X1770135Y490711D03*
X1745231Y489036D03*
X1614538Y618288D03*
X1613362Y656321D03*
X1621362D03*
X1617362D03*
X1619950Y678519D03*
X1616260Y678462D03*
X1596260Y540500D03*
X1611316Y685800D03*
X1616622Y542712D03*
Y546712D03*
X1596760Y530000D03*
X1595300Y558800D03*
X1595364Y562800D03*
X1594760Y568000D03*
X1571755Y577937D03*
X1579260Y604567D03*
X1574760Y606929D03*
X1579760Y595500D03*
X1580354Y616317D03*
X1580418Y610072D03*
X1575001Y612592D03*
X1574720Y618400D03*
X1577077Y631712D03*
X1576297Y627600D03*
X1571888Y649380D03*
X1574880Y645891D03*
X1572141Y662981D03*
X1569434Y677111D03*
X1288144Y489036D03*
X1160275Y656321D03*
X1159535Y542712D03*
Y546712D03*
X1157451Y618288D03*
X1156275Y656321D03*
X1139673Y530000D03*
X1139173Y540500D03*
X1138213Y558800D03*
X1138277Y562800D03*
X1114668Y577937D03*
X1122173Y604567D03*
X1122673Y595500D03*
X1117673Y606929D03*
X1117914Y612592D03*
X1117633Y618400D03*
X1123267Y616317D03*
X1123331Y610072D03*
X1115151Y650119D03*
X1115320Y646449D03*
X1105298Y610400D03*
X833269Y506683D03*
X833953Y530621D03*
X658392Y200864D03*
X943183Y281652D03*
X1786170Y448931D03*
X1792527Y452799D03*
X1786693Y459170D03*
X1791088Y77296D03*
X1809095Y435101D03*
X1803700Y440101D03*
X1803530Y431112D03*
X1809358Y442114D03*
X1803335Y452718D03*
X1809346Y452601D03*
X1797907Y452987D03*
X1809338Y447121D03*
X1804933Y461607D03*
X1796933D03*
X1796136Y471334D03*
X1800933Y461607D03*
X1768586Y467560D03*
X1764903Y470382D03*
X1776561Y467560D03*
X1779232Y55513D03*
X1775457Y68581D03*
X1785246Y60660D03*
X1781832Y60513D03*
X1790664Y71908D03*
X1790712Y81713D03*
X1790373Y94663D03*
X1786466Y94279D03*
X1782517Y94351D03*
X1777289Y200864D03*
X1777378Y212455D03*
X1777312Y207037D03*
X1762102Y168697D03*
X1763190Y191941D03*
X1763887Y266114D03*
X1761360Y281982D03*
X1753784Y265701D03*
X1758871Y265896D03*
X1755419Y281716D03*
X1748497Y371060D03*
X1752497Y371076D03*
X1755433Y379028D03*
X1756553Y466409D03*
X1738824Y456034D03*
Y461034D03*
X1758848Y177616D03*
X1759429Y172190D03*
X1715228Y387966D03*
X1718851Y391533D03*
X1720571Y385644D03*
X1725746Y385123D03*
X1718318Y399918D03*
X1725154Y406060D03*
X1721423Y412106D03*
X1724627Y459330D03*
X1724580Y454214D03*
X1737746Y385123D03*
X1741420Y391569D03*
X1739847Y401066D03*
X1697984Y226320D03*
X1705686Y230556D03*
X1709941Y228747D03*
X1704671Y242078D03*
X1699902Y232971D03*
X1696552Y244571D03*
X1703895Y256394D03*
X1713788Y97667D03*
X1710547Y238714D03*
X1683556Y204864D03*
X1679197Y219379D03*
X1693932Y249108D03*
X1683523Y324518D03*
X1677810Y324466D03*
X1688593Y353470D03*
X1680518Y377912D03*
Y381912D03*
X1704934Y97667D03*
X1700590Y102495D03*
X1700324Y142862D03*
X1673203Y328867D03*
X1670260Y377912D03*
X1669260Y391496D03*
X1663618Y393858D03*
X1663780Y384410D03*
X1666959Y382047D03*
X1670260Y386500D03*
X1669260Y409000D03*
X1665260Y398583D03*
X1670348Y397912D03*
X1667260Y403500D03*
X1688011Y86012D03*
Y94374D03*
X1680155Y94351D03*
X1684104Y94279D03*
X1694291Y110784D03*
X1689291D03*
X1683782Y124283D03*
X1693870Y124663D03*
X1688848Y124879D03*
X1695214Y138838D03*
X1682189Y161306D03*
X1683524Y168665D03*
Y176665D03*
Y192665D03*
X1683637Y186778D03*
X1649773Y449961D03*
X1653490Y458572D03*
X1645826Y446606D03*
X1676870Y55513D03*
X1673095Y68581D03*
X1667318Y198828D03*
X1674927Y200864D03*
X1674950Y207037D03*
X1675016Y212455D03*
X1658645Y143740D03*
X1656025Y148277D03*
X1656486Y177616D03*
X1659740Y168697D03*
X1657067Y172190D03*
X1660828Y191941D03*
X1645685Y381500D03*
X1648835Y390500D03*
X1650044Y435158D03*
X1649789Y440489D03*
X1646209Y442606D03*
X1650087Y444841D03*
X1635170Y442856D03*
X1632439Y452265D03*
X1633225Y458455D03*
X1636271Y453881D03*
X1635185Y446595D03*
X1647406Y147540D03*
X1651178Y141247D03*
X1603324Y230556D03*
X1607579Y227824D03*
X1608185Y238714D03*
X1602309Y242078D03*
X1597540Y232971D03*
X1607947Y332326D03*
X1599527Y396718D03*
X1628636Y422088D03*
X1625772Y438323D03*
X1621596Y456386D03*
X1620385Y465874D03*
X1592635Y455911D03*
X1591443Y465332D03*
X1602572Y97667D03*
X1611426D03*
X1598228Y102495D03*
X1597962Y142862D03*
X1586929Y110784D03*
X1591929D03*
X1586486Y124879D03*
X1591508Y124663D03*
X1592852Y138838D03*
X1581162Y168665D03*
Y176665D03*
Y192665D03*
Y196665D03*
X1581275Y186778D03*
X1581194Y204864D03*
X1595622Y226320D03*
X1594190Y244571D03*
X1591570Y249108D03*
X1582951Y248371D03*
X1574775Y333549D03*
X1563877Y329863D03*
Y343363D03*
Y334363D03*
X1578587Y341787D03*
X1578420Y338309D03*
X1563877Y352363D03*
X1575935Y382109D03*
X1585649Y86012D03*
Y94374D03*
X1571895Y58013D03*
X1570733Y68581D03*
X1581742Y94279D03*
X1577793Y94351D03*
X1581420Y124283D03*
X1579827Y161306D03*
X1572565Y200864D03*
X1572654Y212455D03*
X1572588Y207037D03*
X1576835Y219379D03*
X1563877Y325363D03*
Y316363D03*
X1557378Y168697D03*
X1554705Y172190D03*
X1554124Y177616D03*
X1558466Y191941D03*
X1559163Y266114D03*
X1554147Y265896D03*
X1556636Y281982D03*
X1550695Y281716D03*
X1554403Y316363D03*
X1553910Y331798D03*
X1539140Y320863D03*
X1542797Y329863D03*
X1538133Y354553D03*
X1545434Y352363D03*
X1548816Y141247D03*
X1556283Y143740D03*
X1553663Y148277D03*
X1545044Y147540D03*
X1549060Y265701D03*
X1519321Y378600D03*
Y382600D03*
X1500962Y230556D03*
X1505217Y227824D03*
X1505823Y238714D03*
X1499947Y242078D03*
X1493260Y226320D03*
X1495178Y232971D03*
X1491828Y244571D03*
X1489208Y249108D03*
X1486360Y322700D03*
X1486913Y340327D03*
X1487152Y331272D03*
X1509064Y97667D03*
X1484124Y124879D03*
X1477465Y161306D03*
X1478800Y168665D03*
Y176665D03*
Y192665D03*
Y196665D03*
X1470203Y200864D03*
X1478913Y186778D03*
X1478832Y204864D03*
X1470292Y212455D03*
X1470226Y207037D03*
X1474473Y219379D03*
X1477549Y327200D03*
Y322700D03*
Y345200D03*
Y340700D03*
Y331700D03*
X1489556Y17645D03*
X1489829Y29424D03*
X1490563Y23043D03*
X1500210Y97667D03*
X1483287Y94374D03*
X1495866Y102495D03*
X1489567Y110784D03*
X1489146Y124663D03*
X1495600Y142862D03*
X1490490Y138838D03*
X1479972Y40780D03*
X1472146Y55513D03*
X1468371Y68581D03*
X1483287Y86012D03*
X1475431Y94351D03*
X1479380Y94279D03*
X1484567Y110784D03*
X1479058Y124283D03*
X1457347Y31518D03*
X1457829Y26425D03*
X1453921Y143740D03*
X1455016Y168697D03*
X1452343Y172190D03*
X1456104Y191941D03*
X1442682Y147540D03*
X1446454Y141247D03*
X1451301Y148277D03*
X1451762Y177616D03*
X1406702Y97667D03*
X1403461Y238714D03*
X1397848Y97667D03*
X1393504Y102495D03*
X1393238Y142862D03*
X1394279Y148717D03*
X1388128Y138838D03*
X1390898Y226320D03*
X1402855Y227824D03*
X1398600Y230556D03*
X1392816Y232971D03*
X1389466Y244571D03*
X1396809Y256394D03*
X1360719Y424601D03*
X1382205Y110784D03*
X1387205D03*
X1386784Y124663D03*
X1376696Y124283D03*
X1381762Y124879D03*
X1375103Y161306D03*
X1386846Y249108D03*
X1378227Y248371D03*
X1383551Y337808D03*
X1384265Y329871D03*
X1383634Y342766D03*
X1384265Y334371D03*
X1383963Y366675D03*
X1335440Y452799D03*
X1329083Y448931D03*
X1329606Y459170D03*
X1336646Y22627D03*
X1336551Y26534D03*
X1340320Y147540D03*
X1344092Y141247D03*
X1351559Y143740D03*
X1348939Y148277D03*
X1349763Y371908D03*
X1346443Y431112D03*
X1352008Y435101D03*
X1352271Y442114D03*
X1346613Y440101D03*
X1352259Y452601D03*
X1352251Y447121D03*
X1346248Y452718D03*
X1340820Y452987D03*
X1347846Y461607D03*
X1339846D03*
X1339049Y471334D03*
X1343846Y461607D03*
X1311488Y471560D03*
X1307835Y470382D03*
X1319474Y467560D03*
X1324120Y22742D03*
X1336623Y30483D03*
X1328799Y168665D03*
Y176665D03*
Y192665D03*
Y196665D03*
X1328912Y186778D03*
X1328831Y204864D03*
X1324472Y219379D03*
X1325007Y370951D03*
X1306103Y191941D03*
X1314157Y192490D03*
X1320202Y200864D03*
X1310115Y192300D03*
X1320225Y207037D03*
X1320291Y212455D03*
X1306800Y266114D03*
X1291410Y371060D03*
X1295410Y371076D03*
X1293048Y379088D03*
X1298346Y379028D03*
X1299466Y466409D03*
X1310853Y37543D03*
X1305015Y168697D03*
X1302139Y26325D03*
X1302785Y31168D03*
X1301761Y177616D03*
X1302342Y172190D03*
X1296697Y265701D03*
X1301784Y265896D03*
X1304273Y281982D03*
X1298332Y281716D03*
X1289345Y330655D03*
X1287437Y379429D03*
X1280699Y377173D03*
X1284659D03*
X1274436Y377350D03*
X1280659Y385123D03*
X1284333Y391569D03*
X1282760Y401066D03*
X1281737Y461034D03*
Y456034D03*
X1259991Y340691D03*
X1264659Y377173D03*
X1267944Y371767D03*
X1261764Y391533D03*
X1263484Y385644D03*
X1268659Y385123D03*
X1268067Y406060D03*
X1261231Y399918D03*
X1264336Y412106D03*
X1267493Y454214D03*
X1243503Y102495D03*
X1243237Y142862D03*
X1240897Y226320D03*
X1248599Y230556D03*
X1252854Y227824D03*
X1253460Y238714D03*
X1247584Y242078D03*
X1242815Y232971D03*
X1246808Y256394D03*
X1241205Y303962D03*
X1232204Y110784D03*
X1237204D03*
X1236783Y124663D03*
X1226695Y124283D03*
X1231761Y124879D03*
X1238127Y138838D03*
X1225102Y161306D03*
X1226437Y176665D03*
Y168665D03*
Y192665D03*
X1226550Y186778D03*
X1226469Y204864D03*
X1239465Y244571D03*
X1236845Y249108D03*
X1226436Y324518D03*
X1229438Y332584D03*
X1235589Y348015D03*
X1229942Y347937D03*
X1231506Y353470D03*
X1247847Y97667D03*
X1256701D03*
X1207753Y192300D03*
X1211795Y192490D03*
X1210268Y198671D03*
X1217863Y207037D03*
X1217929Y212455D03*
X1220723Y324466D03*
X1211892Y339559D03*
X1215776Y331072D03*
X1213173Y377912D03*
X1209872Y382047D03*
X1212173Y391496D03*
X1206693Y384410D03*
X1213173Y386500D03*
X1213261Y397912D03*
X1210173Y403500D03*
X1212173Y409000D03*
X1230924Y86012D03*
Y94374D03*
X1227017Y94279D03*
X1223068Y94351D03*
X1201113Y315039D03*
X1206531Y393858D03*
X1208173Y398583D03*
X1192702Y440489D03*
X1192957Y435158D03*
X1193000Y444841D03*
X1192686Y449961D03*
X1196403Y458572D03*
X1219783Y55513D03*
X1216008Y68581D03*
X1217840Y200864D03*
X1190319Y147540D03*
X1194091Y141247D03*
X1201558Y143740D03*
X1198938Y148277D03*
X1199980Y172190D03*
X1202653Y168697D03*
X1199399Y177616D03*
X1203741Y191941D03*
X1199422Y265896D03*
X1204438Y266114D03*
X1194335Y265701D03*
X1201911Y281982D03*
X1195970Y281716D03*
X1179761Y336380D03*
X1191748Y392676D03*
X1188598Y381500D03*
X1189122Y442606D03*
X1176699Y451108D03*
X1176138Y458455D03*
X1179184Y453881D03*
X1188739Y446606D03*
X1171445Y422088D03*
X1168398Y456309D03*
X1163298Y465874D03*
X1146237Y230556D03*
X1150492Y227824D03*
X1151098Y238714D03*
X1145222Y242078D03*
X1145587Y339148D03*
X1142440Y396718D03*
X1138535Y226320D03*
X1140453Y232971D03*
X1137103Y244571D03*
X1137830Y336230D03*
X1135548Y455804D03*
X1134629Y465551D03*
X1145485Y97667D03*
X1154339D03*
X1128562Y86012D03*
Y94374D03*
X1141141Y102495D03*
X1129842Y110784D03*
X1134842D03*
X1129399Y124879D03*
X1134421Y124663D03*
X1140875Y142862D03*
X1135765Y138838D03*
X1114781Y58013D03*
X1113646Y68581D03*
X1120706Y94351D03*
X1124655Y94279D03*
X1124333Y124283D03*
X1122740Y161306D03*
X1124075Y168665D03*
Y176665D03*
X1115478Y200864D03*
X1124188Y186778D03*
X1124107Y204864D03*
X1115501Y207037D03*
X1115567Y212455D03*
X1115000Y329000D03*
Y334000D03*
Y339000D03*
X1118848Y382109D03*
X1102076Y266114D03*
X1097060Y265896D03*
X1099549Y281982D03*
X1108779Y327705D03*
X1487318Y318200D03*
X1105012Y353504D03*
X1091031Y374810D03*
X1099196Y143740D03*
X1096576Y148277D03*
X1100291Y168697D03*
X1097618Y172190D03*
X1097037Y177616D03*
X1101379Y191941D03*
X1109433Y192490D03*
X1087957Y147540D03*
X1091729Y141247D03*
X1091973Y265701D03*
X1093608Y281716D03*
X1060679Y368276D03*
X1062234Y378600D03*
Y382600D03*
X1060679Y356151D03*
X1030220Y313554D03*
X1041783Y321114D03*
X1043106Y340230D03*
X1042948Y333696D03*
X1031259Y350427D03*
X1051977Y97667D03*
X1048130Y227824D03*
X1048736Y238714D03*
X1061387Y343509D03*
X1020406Y350772D03*
X1043123Y97667D03*
X1038779Y102495D03*
X1032480Y110784D03*
X1032059Y124663D03*
X1038513Y142862D03*
X1033403Y138838D03*
X1036173Y226320D03*
X1043875Y230556D03*
X1042860Y242078D03*
X1038091Y232971D03*
X1034741Y244571D03*
X1032121Y249108D03*
X1042084Y256394D03*
X1045650Y300093D03*
X1029639Y300141D03*
X1001105Y318006D03*
X997020Y345354D03*
X996024Y352132D03*
X1015059Y55513D03*
X1026200Y86012D03*
Y94374D03*
X1022293Y94279D03*
X1018344Y94351D03*
X1027480Y110784D03*
X1021971Y124283D03*
X1027037Y124879D03*
X1020378Y161306D03*
X1021713Y168665D03*
X1021745Y204864D03*
X1016635Y300276D03*
X1012635D03*
X1025749D03*
X1020635D03*
X1012936Y178560D03*
X997929Y168697D03*
X999017Y191941D03*
X1003029Y192300D03*
X1012346Y190185D03*
X1007071Y192490D03*
X1013139Y207037D03*
X999714Y266114D03*
X1000698Y300276D03*
X1002580Y309619D03*
X994675Y177616D03*
X989611Y265701D03*
X994698Y265896D03*
X991246Y281716D03*
X997187Y281982D03*
X987517Y314092D03*
X993552Y318175D03*
X983956Y346652D03*
X989630Y343862D03*
X983717Y341665D03*
X993026Y353813D03*
X981719Y352217D03*
X988631Y349496D03*
X980045Y366559D03*
X986373Y370467D03*
X1011284Y68581D03*
X977150Y331972D03*
X985595Y147540D03*
X989367Y141247D03*
X996834Y143740D03*
X994214Y148277D03*
X995256Y172190D03*
X947040Y223885D03*
X948785Y242464D03*
X951278Y250583D03*
X950953Y317947D03*
X960376Y392807D03*
X936151Y142862D03*
X937192Y148717D03*
X934477Y211491D03*
X946234Y213390D03*
X942179Y215727D03*
X936395Y218142D03*
X947733Y319680D03*
X934128Y355168D03*
X934464Y358618D03*
X944238Y360828D03*
X934047Y369160D03*
X936175Y364823D03*
X949615Y97667D03*
X913057Y311046D03*
X915653Y307438D03*
X923311Y349959D03*
X929943Y372600D03*
X940761Y97667D03*
X936417Y102495D03*
X930118Y110784D03*
X925118D03*
X924675Y124879D03*
X929697Y124663D03*
X919609Y124283D03*
X931041Y138838D03*
X918016Y161306D03*
X916453Y167975D03*
X899573Y158195D03*
X905000Y362158D03*
X906161Y367191D03*
X913288Y372752D03*
X910646Y376084D03*
X906344Y372524D03*
X883233Y147540D03*
X887005Y141247D03*
X894472Y143740D03*
X891852Y148277D03*
X898533Y334498D03*
X896592Y358369D03*
Y354369D03*
X876200Y86012D03*
Y94374D03*
X872293Y94279D03*
X868344Y94351D03*
X871713Y168665D03*
Y176665D03*
Y196665D03*
Y192665D03*
X871745Y204864D03*
X862999Y172665D03*
X862936Y178560D03*
X849017Y191941D03*
X857071Y192490D03*
X862346Y190185D03*
X853029Y192300D03*
X863205Y212455D03*
X863139Y207037D03*
X865059Y55513D03*
X861284Y68581D03*
X844698Y265896D03*
X839611Y265701D03*
X849714Y266114D03*
X841246Y281716D03*
X847187Y281982D03*
X842515Y461382D03*
X842916Y467009D03*
X847929Y168697D03*
X844675Y177616D03*
X845256Y172190D03*
X829485Y345101D03*
X822626Y348066D03*
X805952Y301675D03*
X817456Y313368D03*
X801097Y325858D03*
X817100Y319600D03*
X809490Y325368D03*
Y317368D03*
Y321368D03*
X786151Y142862D03*
X795768Y227824D03*
X791513Y230556D03*
X796374Y238714D03*
X790498Y242078D03*
X785729Y232971D03*
X789722Y256394D03*
X800155Y337368D03*
X800029Y333368D03*
X797141Y350368D03*
X789581Y405011D03*
X769351Y176665D03*
Y168665D03*
Y192665D03*
X769464Y186778D03*
X769383Y204864D03*
X783811Y226320D03*
X782379Y244571D03*
X779759Y249108D03*
X784118Y303962D03*
X778502Y348015D03*
X772859Y347937D03*
X774419Y353470D03*
X799615Y97667D03*
X790761D03*
X786417Y102495D03*
X769349Y324518D03*
X759029Y328867D03*
X754805Y339559D03*
X759624Y353961D03*
X756086Y377912D03*
X766344D03*
X756086Y386500D03*
X766344Y381912D03*
X755086Y391496D03*
X756174Y397912D03*
X755086Y409000D03*
X766344Y397912D03*
X773838Y86012D03*
Y94374D03*
X781041Y138838D03*
X768016Y161306D03*
X735599Y449961D03*
X739316Y458572D03*
X762697Y55513D03*
X758922Y68581D03*
X765982Y94351D03*
X769931Y94279D03*
X760637Y172665D03*
X760574Y178560D03*
X754709Y192490D03*
X759984Y190185D03*
X753182Y198671D03*
X760843Y212455D03*
X760777Y207037D03*
X741852Y148277D03*
X745567Y168697D03*
X742894Y172190D03*
X742313Y177616D03*
X746655Y191941D03*
X750667Y192300D03*
X747352Y266114D03*
X742336Y265896D03*
X744825Y281982D03*
X738884Y281716D03*
X741051Y316389D03*
X749444Y393858D03*
X749606Y384410D03*
X752785Y382047D03*
X753086Y403500D03*
X751086Y398583D03*
X722097Y453881D03*
X731952Y446606D03*
X722097Y446595D03*
X737005Y141247D03*
X744472Y143740D03*
X733233Y147540D03*
X737249Y265701D03*
X723404Y379657D03*
X721900Y384500D03*
X723440Y391496D03*
Y398583D03*
X732035Y442606D03*
X712692Y356779D03*
X717105Y410964D03*
X717420Y404334D03*
X709781Y442956D03*
X720996Y442856D03*
X711598Y438323D03*
X719051Y458455D03*
X719612Y451108D03*
X710643Y456335D03*
X711764Y445873D03*
X689151Y230556D03*
X693406Y227824D03*
X694012Y238714D03*
X688136Y242078D03*
X690504Y253198D03*
X697253Y97667D03*
X688399D03*
X671476Y94374D03*
X684055Y102495D03*
X677756Y110784D03*
X672756D03*
X677335Y124663D03*
X683789Y142862D03*
X678679Y138838D03*
X681449Y226320D03*
X683367Y232971D03*
X677397Y249108D03*
X680017Y244571D03*
X661761Y382109D03*
X657507Y58013D03*
X656560Y68581D03*
X671476Y86012D03*
X663620Y94351D03*
X667569Y94279D03*
X667247Y124283D03*
X672313Y124879D03*
X665654Y161306D03*
X666989Y176665D03*
Y168665D03*
X658275Y172665D03*
X658212Y178560D03*
X657622Y190185D03*
X666989Y196665D03*
Y192665D03*
X667102Y186778D03*
X667021Y204864D03*
X658481Y212455D03*
X658415Y207037D03*
X644990Y266114D03*
X642463Y281982D03*
X642110Y143740D03*
X640532Y172190D03*
X643205Y168697D03*
X644293Y191941D03*
X652347Y192490D03*
X639974Y265896D03*
X634887Y265701D03*
X636522Y281716D03*
X630871Y147540D03*
X634643Y141247D03*
X639490Y148277D03*
X639951Y177616D03*
X594891Y97667D03*
X591650Y238714D03*
X605147Y378600D03*
Y382600D03*
X586037Y97667D03*
X581693Y102495D03*
X575394Y110784D03*
X581427Y142862D03*
X576317Y138838D03*
X579087Y226320D03*
X586789Y230556D03*
X591044Y227824D03*
X585774Y242078D03*
X581005Y232971D03*
X577655Y244571D03*
X584998Y256394D03*
X573479Y374705D03*
X557973Y55513D03*
X569114Y86012D03*
Y94374D03*
X561258Y94351D03*
X565207Y94279D03*
X570394Y110784D03*
X574973Y124663D03*
X569951Y124879D03*
X563292Y161306D03*
X564627Y176665D03*
Y168665D03*
Y196665D03*
Y192665D03*
X564740Y186778D03*
X564659Y204864D03*
X575035Y249108D03*
X533189Y390723D03*
X531953Y385749D03*
X531992Y397552D03*
X554198Y68581D03*
X540843Y168697D03*
X555850Y178560D03*
X555913Y172665D03*
X541931Y191941D03*
X555260Y190185D03*
X549985Y192490D03*
X556119Y212455D03*
X556053Y207037D03*
X542628Y266114D03*
X532281Y141247D03*
X528509Y147540D03*
X539748Y143740D03*
X537128Y148277D03*
X538170Y172190D03*
X537589Y177616D03*
X532525Y265701D03*
X537612Y265896D03*
X534160Y281716D03*
X540101Y281982D03*
X532659Y359557D03*
X526388Y351301D03*
X531612Y354272D03*
X531636Y349057D03*
X528812Y369164D03*
X533211Y364746D03*
X533115Y371856D03*
X530144Y376062D03*
X531953Y380749D03*
X512943Y443071D03*
X520823Y442603D03*
X518240Y459371D03*
X492817Y357111D03*
X491843Y351089D03*
X496023Y362913D03*
X497048Y369450D03*
X495750Y377531D03*
X506500Y379687D03*
X495203Y386890D03*
X503729Y439919D03*
X503682Y448419D03*
X492529Y97667D03*
X483675D03*
X479331Y102495D03*
X479065Y142862D03*
X480106Y148717D03*
X493272Y230117D03*
X484427Y230556D03*
X488682Y227824D03*
X478643Y232971D03*
X489288Y238714D03*
X473032Y110784D03*
X468032D03*
X462523Y124283D03*
X467589Y124879D03*
X472611Y124663D03*
X473955Y138838D03*
X429919Y141247D03*
X437386Y143740D03*
X434766Y148277D03*
X450436Y143518D03*
X422473Y22627D03*
X422450Y30483D03*
X422378Y26534D03*
X426147Y147540D03*
X414626Y176665D03*
Y168665D03*
Y196665D03*
Y192665D03*
X414739Y186778D03*
X414658Y204864D03*
X405912Y172665D03*
X405849Y178560D03*
X399984Y192490D03*
X405259Y190185D03*
X406029Y200864D03*
X395942Y192300D03*
X406052Y207037D03*
X403419Y221642D03*
X387611Y265896D03*
X382524Y265701D03*
X392627Y266114D03*
X384159Y281716D03*
X390100Y281982D03*
X410789Y22627D03*
X396680Y37543D03*
X388612Y31168D03*
X387948Y27288D03*
X387588Y177616D03*
X390842Y168697D03*
X388169Y172190D03*
X391930Y191941D03*
X339287Y238714D03*
X333411Y242078D03*
X330905Y15806D03*
Y19806D03*
Y27806D03*
X333674Y97667D03*
X342528D03*
X329330Y102495D03*
X343271Y230117D03*
X338681Y227824D03*
X334426Y230556D03*
X312263Y324518D03*
X301943Y328867D03*
X299000Y377912D03*
Y386500D03*
X299088Y397912D03*
X322847Y19806D03*
X321840Y14408D03*
X322113Y26187D03*
X316751Y86012D03*
Y94374D03*
X318031Y110784D03*
X323031D03*
X322610Y124663D03*
X317588Y124879D03*
X329064Y142862D03*
X323954Y138838D03*
X326724Y226320D03*
X328642Y232971D03*
X322672Y249108D03*
X325292Y244571D03*
X327032Y303962D03*
X312256Y37543D03*
X305610Y55513D03*
X301835Y68581D03*
X312844Y94279D03*
X308895Y94351D03*
X310929Y161306D03*
X303550Y172665D03*
X303487Y178560D03*
X312264Y176665D03*
Y168665D03*
Y196665D03*
Y192665D03*
X312377Y186778D03*
X312296Y204864D03*
X303756Y212455D03*
X303690Y207037D03*
X288480Y168697D03*
X285226Y177616D03*
X289568Y191941D03*
X290265Y266114D03*
X285249Y265896D03*
X287738Y281982D03*
X286940Y315039D03*
X297719Y339559D03*
X291396Y350223D03*
X292520Y384410D03*
X292358Y393858D03*
X298000Y391496D03*
X295699Y382047D03*
X296000Y403500D03*
X298000Y409000D03*
X294000Y398583D03*
X289797Y36735D03*
X284666Y34068D03*
X290113Y23188D03*
X289631Y28281D03*
X287385Y143740D03*
X284765Y148277D03*
X285807Y172190D03*
X276146Y147540D03*
X279918Y141247D03*
X280162Y265701D03*
X281797Y281716D03*
X278784Y435158D03*
X256475Y422088D03*
X222930Y244571D03*
X240166Y97667D03*
X236319Y227824D03*
X236925Y238714D03*
X231312Y97667D03*
X226968Y102495D03*
X220669Y110784D03*
X220248Y124663D03*
X226702Y142862D03*
X221592Y138838D03*
X224362Y226320D03*
X232064Y230556D03*
X231049Y242078D03*
X226280Y232971D03*
X220310Y249108D03*
X203248Y55513D03*
X199473Y68581D03*
X214389Y86012D03*
Y94374D03*
X206533Y94351D03*
X210482Y94279D03*
X215669Y110784D03*
X215226Y124879D03*
X208567Y161306D03*
X209902Y176665D03*
Y168665D03*
Y196665D03*
Y192665D03*
X210015Y186778D03*
X209934Y204864D03*
X204675Y382109D03*
X201125Y178560D03*
X186118Y168697D03*
X201188Y172665D03*
X187206Y191941D03*
X195260Y192490D03*
X200535Y190185D03*
X201394Y212455D03*
X201328Y207037D03*
X187903Y266114D03*
X185376Y281982D03*
X179435Y281716D03*
X173784Y147540D03*
X177556Y141247D03*
X185023Y143740D03*
X182403Y148277D03*
X182864Y177616D03*
X183445Y172190D03*
X177800Y265701D03*
X182887Y265896D03*
X137804Y97667D03*
X148061Y378600D03*
Y382600D03*
X117886Y124663D03*
X112864Y124879D03*
X107798Y124283D03*
X119230Y138838D03*
X128950Y97667D03*
X124606Y102495D03*
X124340Y142862D03*
X125381Y148717D03*
X118307Y110784D03*
X113307D03*
X32350Y63562D03*
Y59562D03*
X28442Y55340D03*
X32350Y67562D03*
X22439Y102495D03*
X11011Y79720D03*
X18298Y102141D03*
X1756894Y472020D03*
X1756954Y477318D03*
X1768575Y475560D03*
X1764906Y474382D03*
X1777061Y475560D03*
X1790061Y474513D03*
X1299867Y477318D03*
X1299807Y472020D03*
X1311488Y475560D03*
X1307819Y474382D03*
X1319974Y475560D03*
X1332974Y474513D03*
X842779Y473076D03*
X1093841Y371335D03*
X1103432Y340544D03*
X1455013Y43128D03*
X1027216Y289440D03*
X201305Y200864D03*
X1098845Y353404D03*
X1480702Y368516D03*
X945018Y276051D03*
X1022604Y290262D03*
X1611327Y735973D03*
X1486860Y327200D03*
X1615913Y692245D03*
X1578000Y678776D03*
X1624000Y760900D03*
X1611873Y795127D03*
X1609500Y776100D03*
X1630327Y774627D03*
X1620100Y738300D03*
X1628027Y801427D03*
X1606709Y819165D03*
X1611027Y722427D03*
X1629927Y787327D03*
X1611627Y780327D03*
X1612573Y761427D03*
X1635283Y728117D03*
X1613117Y828117D03*
X1620500Y723200D03*
X1616683Y744517D03*
X1628200Y711417D03*
X1620600Y705900D03*
X1612800D03*
X1628343Y747288D03*
X1606190Y803774D03*
X1805463Y969260D03*
X1801963Y969160D03*
X1789363D03*
X1802000Y892447D03*
X1780016Y874400D03*
X1746884Y884649D03*
X1644325Y942120D03*
X1746600Y935100D03*
X1750915Y902055D03*
X1647402Y881460D03*
X1749267Y918413D03*
X1789537Y930498D03*
X1746897Y879199D03*
X1793474Y930374D03*
X1775904Y924546D03*
X1751200Y931100D03*
X1778047Y916120D03*
X1635176Y886761D03*
X1648375Y886766D03*
X1648387Y945554D03*
X1644552Y871353D03*
X1647470Y952125D03*
X1650205Y925911D03*
X1647763Y919268D03*
X1635000Y919263D03*
X1644718Y909263D03*
X1797365Y930761D03*
X1819900Y906900D03*
X1154652Y791056D03*
X863116Y200864D03*
X556030D03*
X760754D03*
X303667D03*
X1124075Y192665D03*
Y196665D03*
X55596Y1210466D03*
X55188Y1205179D03*
X51023Y1201416D03*
X48842Y1211109D03*
X53479Y1216256D03*
X31631Y1198651D03*
X27340Y230556D03*
X31595Y227824D03*
X32507Y180517D03*
X16909Y153263D03*
X21909D03*
X19638Y226320D03*
X18206Y244571D03*
X98943Y200864D03*
X129702Y230556D03*
X133957Y227824D03*
X128687Y242078D03*
X123918Y232971D03*
X134044Y246874D03*
X120568Y244571D03*
X127911Y256394D03*
X134563Y238714D03*
X106205Y161306D03*
X107540Y176665D03*
Y168665D03*
Y196665D03*
Y192665D03*
X107653Y186778D03*
X107572Y204864D03*
X117948Y249108D03*
X109329Y248371D03*
X122000Y226320D03*
X98826Y172665D03*
X98763Y178560D03*
X92898Y192490D03*
X98173Y190185D03*
X98966Y207037D03*
X99032Y212455D03*
X80502Y177616D03*
X81083Y172190D03*
X83756Y168697D03*
X84844Y191941D03*
X75438Y265701D03*
X85541Y266114D03*
X80525Y265896D03*
X83014Y281982D03*
X77073Y281716D03*
X26325Y262078D03*
X25549Y256394D03*
X31682Y266874D03*
X29116Y281129D03*
X25549Y276394D03*
X48476Y180812D03*
X14807Y282181D03*
X18206Y264571D03*
X86367Y848086D03*
X86289Y822088D03*
X68649Y827218D03*
X72149Y827318D03*
X56049Y827218D03*
X53549Y843118D03*
X69049Y847718D03*
X74700Y842890D03*
X34845Y291756D03*
X26629Y295619D03*
X27686Y629311D03*
Y625311D03*
X36692Y633724D03*
X36575Y627713D03*
X30123Y611071D03*
X27686Y621311D03*
X36494Y616905D03*
X36306Y622285D03*
X34425Y546553D03*
X34448Y552726D03*
X30177Y534211D03*
X34359Y541135D03*
X34732Y534909D03*
X54192Y633473D03*
X42172Y633716D03*
X49192Y628078D03*
X47179Y633736D03*
X40362Y610548D03*
X43804Y500202D03*
X45256Y495993D03*
X43948Y492108D03*
X64692Y642184D03*
X66530Y625013D03*
X58181Y627908D03*
X64408Y582747D03*
X63859Y590801D03*
X78735Y683426D03*
X82562Y680037D03*
X84314Y686107D03*
X79043Y667391D03*
X82648Y670679D03*
X73914Y660107D03*
X84845Y659857D03*
X78733Y578405D03*
X84159Y578986D03*
X86788Y581659D03*
X67670Y464818D03*
X65737Y445603D03*
X57857Y446071D03*
X48643Y442919D03*
X63154Y462371D03*
X48596Y451419D03*
X49643Y464419D03*
X41643Y464919D03*
X61588Y1074481D03*
X55049Y1082343D03*
X55004Y1086937D03*
X62109Y1079656D03*
Y1091656D03*
X57218Y1123867D03*
X47314Y1072228D03*
X50366Y1086981D03*
Y1082388D03*
X38200Y1089721D03*
X44365Y1086404D03*
X41172Y1079064D03*
X46166Y1093757D03*
X38216D03*
X21544Y1489648D03*
Y1479662D03*
X19365Y1494298D03*
X15889Y1494254D03*
X13606Y1476707D03*
X25674Y1486291D03*
X32195Y1511279D03*
X32079Y1517641D03*
Y1521641D03*
X31237Y1532096D03*
X32079Y1525641D03*
X35237Y1532096D03*
X40195Y1511279D03*
X48195D03*
X44195D03*
X48079Y1521641D03*
Y1529641D03*
X39237Y1532096D03*
X48079Y1525641D03*
X16304Y1468196D03*
X22284Y1464612D03*
X12327Y1519202D03*
X18409Y1554202D03*
X11995Y1535134D03*
X22381Y1554152D03*
X14375Y1553121D03*
X52048Y1556062D03*
X56114Y1556061D03*
X35850Y1556096D03*
X60747Y1555890D03*
X71910Y1625009D03*
X87000Y1597855D03*
X60554Y1612002D03*
X66291Y1633801D03*
X69816Y1592527D03*
X74909Y1593009D03*
X78291Y1625743D03*
X74291Y1633801D03*
X83689Y1624736D03*
X86291Y1633801D03*
X147836Y988813D03*
X139836D03*
X151836D03*
X143836D03*
X142026Y1012354D03*
X135836Y988813D03*
X131836D03*
X123836D03*
X127836D03*
X120617Y1016827D03*
X111836Y988813D03*
X119836D03*
X115836D03*
X107836D03*
X114770Y1016827D03*
X103836Y988813D03*
X100200Y988800D03*
X95836Y988813D03*
X94398Y1006648D03*
X94586Y1023900D03*
X91765Y1018307D03*
X88007Y1013678D03*
X97609Y1018469D03*
X87632Y1007522D03*
X130434Y1144964D03*
X130380Y1155491D03*
X130434Y1170164D03*
X130380Y1105091D03*
Y1117691D03*
Y1130291D03*
X103124Y1147364D03*
X108971D03*
X103124Y1159964D03*
X108971D03*
X103124Y1172564D03*
X108971D03*
X103861Y1182703D03*
X103124Y1122164D03*
X108971D03*
X103124Y1109564D03*
X108971D03*
X103124Y1134764D03*
X108971D03*
X595809Y1532133D03*
Y1546214D03*
X591809Y1542407D03*
X588859Y1490895D03*
X590826Y1495688D03*
X588507Y1514141D03*
X582027Y1502800D03*
X581803Y1509687D03*
X575809Y1532912D03*
X587809Y1528389D03*
X583809Y1533025D03*
X579809Y1528163D03*
X587809Y1545854D03*
X583809Y1541607D03*
X577571Y1544013D03*
X570796Y1530309D03*
X563968Y1541445D03*
X568279Y1538438D03*
X572507Y1541375D03*
X419619Y1539978D03*
X421454Y1544625D03*
X422539Y1534361D03*
X426701Y1541947D03*
X418151Y1552470D03*
X404500Y1452500D03*
X408964Y1531149D03*
X399373Y1555855D03*
X255909Y1542043D03*
X250790Y1539759D03*
X234976Y1481676D03*
X243535Y1511473D03*
X237633Y1511909D03*
X244600Y1531700D03*
X240808Y1519942D03*
X235687Y1522578D03*
X237580Y1528604D03*
X245937Y1524237D03*
X239949Y1541327D03*
X244912Y1539389D03*
X226135Y1502442D03*
X230758Y1505046D03*
X226971Y1514578D03*
X227552Y1530675D03*
X232622Y1531104D03*
X226971Y1522578D03*
X219981Y1530797D03*
X223322Y1518578D03*
X222119Y1539941D03*
X227882Y1540816D03*
X233753Y1539752D03*
X224780Y1478149D03*
X217985Y1483055D03*
X225765Y1471985D03*
X233313Y1476699D03*
X221899Y1488800D03*
X218021Y1494724D03*
X222843Y1498442D03*
X217614Y1489671D03*
X233180Y1486442D03*
X233166Y1491454D03*
X395380Y1485778D03*
X395199Y1482223D03*
X417305Y1359169D03*
X418430Y1394237D03*
X420636Y1383912D03*
X410172Y1402446D03*
X391757Y1383480D03*
X420925Y1390330D03*
X425283Y1364023D03*
X366133Y1170767D03*
X366521Y1208993D03*
X360877Y1157404D03*
X354420Y1157544D03*
X349276Y1217228D03*
X351940Y1219895D03*
X355215Y1223170D03*
X340500Y1147500D03*
X278827Y444841D03*
X280220Y448493D03*
X307937Y219379D03*
X459461Y473805D03*
X459414Y468689D03*
X459757Y463520D03*
X451144Y468809D03*
X464199Y510184D03*
X459929Y491669D03*
X460537Y501905D03*
X459952Y496842D03*
X459645Y509486D03*
X376881Y518564D03*
X450852Y372054D03*
X426647Y452987D03*
X421267Y452799D03*
X414910Y448931D03*
X415433Y459170D03*
X425673Y461607D03*
X424876Y471334D03*
X432270Y431112D03*
X432440Y440101D03*
X438098Y442114D03*
X437835Y435101D03*
X432075Y452718D03*
X438086Y452601D03*
X438078Y447121D03*
X433673Y461607D03*
X429673D03*
X397315Y471560D03*
X405301Y467560D03*
X420422Y367859D03*
X412318Y367903D03*
X384173Y379028D03*
X381237Y371076D03*
X393662Y470382D03*
X385293Y466409D03*
X367564Y456034D03*
Y461034D03*
X377237Y371060D03*
X373264Y379429D03*
X378875Y379088D03*
X366526Y377173D03*
X370486D03*
X366486Y385123D03*
X370160Y391569D03*
X368587Y401066D03*
X347058Y399918D03*
X351136Y372334D03*
X358491Y377173D03*
X350486D03*
X347591Y391533D03*
X349311Y385644D03*
X354486Y385123D03*
X353894Y406060D03*
X350163Y412106D03*
X353320Y454214D03*
X385634Y472020D03*
X385694Y477318D03*
X397315Y475560D03*
X405801D03*
X418801Y474513D03*
X373971Y489036D03*
X413461Y1569560D03*
X409461D03*
X405461D03*
X382017Y1555700D03*
Y1547700D03*
Y1551700D03*
X468850Y545586D03*
X447279Y637031D03*
X447921Y630789D03*
X453552Y631779D03*
X456469Y638302D03*
X446987Y643360D03*
X443144Y628667D03*
X441162Y638313D03*
X424993Y728291D03*
X406200Y741300D03*
X423963Y625778D03*
X475588Y1043055D03*
X470610Y1033783D03*
X471755Y1038665D03*
X470978Y1046591D03*
X503933Y981392D03*
X498585Y1016266D03*
X506566Y1012266D03*
X502562Y1158200D03*
X493091Y989550D03*
X498435Y1008766D03*
X506566Y996766D03*
Y1008766D03*
X487091Y989550D03*
X485678Y1039880D03*
X485633Y1036155D03*
X468850Y1160834D03*
X459360Y1004680D03*
X464385Y1038534D03*
X459700Y1035716D03*
X477765Y1093432D03*
X451304Y1297045D03*
X458120Y974701D03*
X451460Y974695D03*
X459360Y1012325D03*
X451140Y1021793D03*
X447091Y1019766D03*
X450875Y1028416D03*
X452091Y1039880D03*
X459700Y1032266D03*
X433063Y1221428D03*
X429063D03*
X433063Y1225428D03*
Y1229428D03*
Y1233428D03*
Y1237428D03*
X429063Y1225428D03*
Y1229428D03*
Y1233428D03*
Y1237428D03*
X433063Y1241428D03*
Y1245428D03*
X429063Y1241428D03*
Y1245428D03*
X430527Y1289198D03*
X440906D03*
X443091Y1026266D03*
X437132Y1158266D03*
X425063Y1221428D03*
X421063D03*
X417063D03*
X413063D03*
X425063Y1225428D03*
Y1229428D03*
Y1233428D03*
Y1237428D03*
X421063Y1225428D03*
Y1229428D03*
Y1233428D03*
Y1237428D03*
X417063Y1225428D03*
Y1229428D03*
Y1233428D03*
Y1237428D03*
X413063Y1225428D03*
Y1229428D03*
Y1233428D03*
Y1237428D03*
X425063Y1241428D03*
Y1245428D03*
X421063Y1241428D03*
Y1245428D03*
X417063Y1241428D03*
Y1245428D03*
X413063Y1241428D03*
Y1245428D03*
X413526Y1288938D03*
X419977Y1288843D03*
X413640Y1292856D03*
X403263Y1160834D03*
X409063Y1221428D03*
X405063D03*
X401063D03*
X397063D03*
X409063Y1225428D03*
Y1229428D03*
Y1233428D03*
Y1237428D03*
X405063Y1225428D03*
Y1229428D03*
Y1233428D03*
Y1237428D03*
X401063Y1225428D03*
Y1229428D03*
Y1233428D03*
Y1237428D03*
X397063Y1225428D03*
Y1229428D03*
Y1233428D03*
X409063Y1241428D03*
Y1245428D03*
X405063Y1241428D03*
Y1245428D03*
X401063Y1241428D03*
X407767Y1292198D03*
X403678Y1295426D03*
X405466Y881299D03*
X397431Y870654D03*
X401108Y878487D03*
X397252Y962861D03*
X396671Y968287D03*
X392910Y948536D03*
X393998Y971780D03*
X386589Y864408D03*
X392584Y875845D03*
X382675Y870151D03*
X391614Y930676D03*
X384856Y947987D03*
X464795Y1000647D03*
X498727Y1128759D03*
X441296Y325061D03*
X428459Y331255D03*
X435793D03*
X428500Y345776D03*
X435793Y345738D03*
X421231Y338523D03*
Y331255D03*
Y345776D03*
X413432Y346797D03*
X410086Y336795D03*
X410688Y344736D03*
X430600Y797400D03*
X459245Y807152D03*
X590957Y1105091D03*
X587467D03*
X578298Y1215195D03*
X584024Y1209607D03*
X569135Y1214372D03*
X564890Y1218169D03*
X569882Y1223749D03*
X569520Y1102091D03*
X560211D03*
X566020D03*
X569520Y1114691D03*
X566020D03*
X560211D03*
Y1109564D03*
X566058D03*
X560211Y1122164D03*
X566058D03*
X569520Y1139891D03*
X566020D03*
X560211D03*
X566020Y1127291D03*
X560211D03*
X569520D03*
X560211Y1134764D03*
X566058D03*
X566020Y1152491D03*
X560211D03*
X569520D03*
X560211Y1147364D03*
X566058D03*
X566020Y1165091D03*
X560211D03*
Y1172564D03*
X566058D03*
X560211Y1159964D03*
X566058D03*
X560211Y1177691D03*
X566020D03*
X566058Y1185164D03*
X560211D03*
X563673Y1204932D03*
X575620Y1207737D03*
X556493Y1118351D03*
X510562Y1222194D03*
X514562D03*
X518562D03*
X522562D03*
X510562Y1238194D03*
Y1234194D03*
Y1230194D03*
Y1226194D03*
X514562Y1238194D03*
Y1234194D03*
Y1230194D03*
Y1226194D03*
X518562Y1234194D03*
Y1230194D03*
Y1226194D03*
X522562D03*
X510562Y1246194D03*
Y1242194D03*
X514562Y1246194D03*
Y1242194D03*
X494562Y1222194D03*
X498562D03*
X502562D03*
X506562D03*
X494562Y1238194D03*
Y1234194D03*
Y1230194D03*
Y1226194D03*
X498562Y1238194D03*
Y1234194D03*
Y1230194D03*
Y1226194D03*
X502562Y1238194D03*
Y1234194D03*
Y1230194D03*
Y1226194D03*
X506562Y1238194D03*
Y1234194D03*
Y1230194D03*
Y1226194D03*
X498562Y1246194D03*
Y1242194D03*
X502562Y1246194D03*
Y1242194D03*
X506562Y1246194D03*
Y1242194D03*
X494562D03*
Y1246194D03*
X592885Y1229402D03*
X593519Y1224472D03*
X586502Y1227300D03*
X583520Y1230407D03*
X594183Y1220068D03*
X592634Y1234921D03*
X541245Y578986D03*
X535819Y578405D03*
X529601Y596089D03*
X540770Y596729D03*
X534820Y596782D03*
X524770Y597232D03*
X536770Y605443D03*
X520945Y590801D03*
X521494Y582747D03*
X524770Y605637D03*
X520770Y597130D03*
X516770Y605443D03*
X520770D03*
X511278Y633473D03*
X515267Y627908D03*
X523616Y625013D03*
X521778Y642184D03*
X501224Y492050D03*
X502493Y495917D03*
X500890Y500202D03*
X497448Y610548D03*
X506278Y628078D03*
X499258Y633716D03*
X504265Y633736D03*
X491445Y541135D03*
X491818Y534909D03*
X491511Y546553D03*
X491534Y552726D03*
X493580Y616905D03*
X493392Y622285D03*
X487209Y611071D03*
X493778Y633724D03*
X493661Y627713D03*
X494465Y657772D03*
X518812Y662874D03*
X521868Y666577D03*
X488765Y667224D03*
X522200Y677613D03*
X504966Y678098D03*
X510425Y683246D03*
X521540Y686319D03*
X536087Y702364D03*
X500714Y708755D03*
X502832Y720491D03*
X561401Y811242D03*
X567559Y812850D03*
X559741Y822149D03*
X568990Y844721D03*
X560813Y840574D03*
X559196Y846296D03*
X544741Y823149D03*
X556741Y820149D03*
X548464Y823156D03*
X540807Y816556D03*
X541129Y828335D03*
X549241Y841388D03*
X548665Y850399D03*
X545237Y850319D03*
X544878Y816309D03*
X544741Y809649D03*
X553871Y811298D03*
X545741Y804149D03*
X532304Y806649D03*
X531313Y822693D03*
X530741Y845149D03*
X532316Y833649D03*
X527733Y847026D03*
X536641Y838649D03*
X534632Y849830D03*
X522481Y824661D03*
X521565Y820931D03*
X524741Y845149D03*
X520720Y846133D03*
X534672Y785037D03*
X550420Y793743D03*
X540578Y793889D03*
X544515Y793875D03*
X558241Y796389D03*
X569186Y787332D03*
X562400Y818900D03*
X537578Y772428D03*
X616923Y988813D03*
X618878Y1011914D03*
X600923Y988813D03*
X592923D03*
X604923D03*
X596923D03*
X599113Y1012354D03*
Y1024954D03*
X584923Y988813D03*
X576923D03*
X580923D03*
X588923D03*
X572923D03*
X556923Y980523D03*
X564923Y988813D03*
X556923D03*
X568923D03*
X1093474Y1638213D03*
X1101474Y1637820D03*
X1089474Y1638213D03*
X1097474Y1637753D03*
X1105474Y1629450D03*
X1096941Y1627905D03*
X1090093Y1628297D03*
X1085474Y1629028D03*
X1101946Y1614709D03*
X1098904Y1602138D03*
X1088021Y1606949D03*
X1082176Y1600598D03*
X1104233Y1587983D03*
X1102904Y1566668D03*
X1090469Y1588435D03*
X1083900Y1593206D03*
X1086469Y1588435D03*
X1100476Y1579318D03*
X1090876Y1554183D03*
X1100876D03*
X1099371Y1561153D03*
X1091569Y1561300D03*
X762671Y1619367D03*
X756358Y1613767D03*
X732268Y1618260D03*
X732825Y1604100D03*
X768361Y1610083D03*
X736067Y1611892D03*
X749704Y1608631D03*
X737892Y1602340D03*
X749786Y1590517D03*
X747140Y1581335D03*
X781110Y1595254D03*
X1086904Y1599004D03*
X1105474Y1638426D03*
X1098617Y1546183D03*
X1107620Y1603602D03*
X1096780Y1535400D03*
X1091525Y1546300D03*
X1091529Y1528718D03*
X1095250Y1531600D03*
X778045Y1619395D03*
X738325Y1634485D03*
X743331Y1627871D03*
X778358Y1627418D03*
X755187Y1580821D03*
X825335Y1137129D03*
X823220Y1162817D03*
X809632Y1142666D03*
X817964Y1157404D03*
X815034Y1159455D03*
X810018Y1167768D03*
X815037D03*
X797160Y1146609D03*
X806787Y1148000D03*
X793842Y1143384D03*
X908799Y1100659D03*
X902353Y1104333D03*
X903959Y1207823D03*
X906784Y1216607D03*
X894713Y1210419D03*
X898878Y1214182D03*
X899286Y1219469D03*
X892532Y1220112D03*
X897169Y1225259D03*
X875321Y1207654D03*
X906309Y1226647D03*
X992906Y578405D03*
X981857Y605637D03*
X986688Y596089D03*
X991907Y596782D03*
X981857Y597232D03*
X993857Y605443D03*
X980703Y625013D03*
X978032Y590801D03*
X978581Y582747D03*
X977857Y597130D03*
X973857Y605443D03*
X977857D03*
X968365Y633473D03*
X972354Y627908D03*
X950865Y633724D03*
X961352Y633736D03*
X963365Y628078D03*
X958124Y492354D03*
X957977Y500202D03*
X959600Y496486D03*
X950667Y616905D03*
X954535Y610548D03*
X950479Y622285D03*
X956345Y633716D03*
X950748Y627713D03*
X917811Y544325D03*
X923642Y561578D03*
X923599Y581578D03*
X913728Y550495D03*
X914296Y558143D03*
X910789Y598726D03*
X866938Y549771D03*
X892931Y534093D03*
X891933Y618143D03*
X874649Y545296D03*
X867093Y554703D03*
Y586828D03*
Y574703D03*
X876351Y605023D03*
Y608523D03*
X879135Y632552D03*
X981843Y464818D03*
X972030Y446071D03*
X979910Y445603D03*
X977327Y462371D03*
X962769Y451419D03*
X955816Y464919D03*
X963816Y464419D03*
X941872Y440942D03*
X933424Y458455D03*
X933161Y451442D03*
X933404Y463462D03*
X933412Y468942D03*
X927766Y456442D03*
X927596Y447453D03*
X921973Y469328D03*
X927401Y469059D03*
X916593Y469140D03*
X910236Y465272D03*
X885989Y309368D03*
Y305368D03*
Y317368D03*
X885953Y325368D03*
X885989Y313368D03*
X885953Y321368D03*
Y329368D03*
Y333368D03*
X877977Y309368D03*
Y313368D03*
Y325368D03*
Y317368D03*
Y321368D03*
Y333368D03*
Y329368D03*
X874005Y344917D03*
X872158Y359962D03*
X868086Y373750D03*
X876736Y383125D03*
X877909Y391731D03*
X882925Y391099D03*
X872736Y391754D03*
X867586Y393000D03*
Y385000D03*
X869342Y407627D03*
X868586Y398500D03*
X855017Y411969D03*
X858586Y374500D03*
X863086D03*
X860586Y383000D03*
X861235Y394000D03*
X864086Y384000D03*
X849591Y411388D03*
X882954Y486256D03*
X891454Y486303D03*
X910759Y475511D03*
X920999Y477948D03*
X954182Y481467D03*
X959816Y472905D03*
X955816Y473419D03*
X963816Y472905D03*
X976397Y473045D03*
X882195Y539204D03*
X899407Y560019D03*
X892856Y1102760D03*
X884890Y1098724D03*
X884906Y1102760D03*
X891055Y1095407D03*
X910977Y266929D03*
Y257480D03*
Y252756D03*
X898576Y253056D03*
X910977Y238583D03*
X919577Y255118D03*
Y259843D03*
Y245669D03*
X936962Y249807D03*
X933403Y245507D03*
X940158Y245707D03*
X907884Y829866D03*
X980726Y1080659D03*
Y1084659D03*
X980969Y1076659D03*
X966330Y1104333D03*
X972776Y1100659D03*
X967936Y1207823D03*
X958690Y1210419D03*
X963263Y1219469D03*
X962855Y1214182D03*
X956509Y1220112D03*
X961146Y1225259D03*
X939298Y1207654D03*
X939992Y536726D03*
Y544726D03*
Y548726D03*
Y540726D03*
Y552726D03*
X941859Y621311D03*
Y625311D03*
Y629311D03*
X978352Y730766D03*
X970839Y729923D03*
X973450Y747280D03*
X978059Y747438D03*
X964070Y807686D03*
Y813006D03*
X957487Y798553D03*
X955225Y788984D03*
X956051Y793937D03*
X966127Y776382D03*
X948883Y1102760D03*
X948867Y1098724D03*
X955032Y1095407D03*
X956833Y1102760D03*
X1044553Y1105091D03*
Y1117691D03*
Y1130291D03*
Y1142891D03*
Y1155491D03*
Y1168091D03*
X1023144Y1109564D03*
X1023106Y1165091D03*
X1017297Y1177691D03*
X1023106D03*
Y1127291D03*
Y1139891D03*
Y1152491D03*
X1282421Y1137129D03*
X1271921Y1134729D03*
X1275794D03*
X1282830Y1150087D03*
X1275050Y1157404D03*
X1280306Y1170767D03*
X1272541Y1201043D03*
X1276575Y1201039D03*
X1280575Y1200969D03*
X1280694Y1208993D03*
X1267921Y1134729D03*
X1266718Y1142666D03*
X1268593Y1157544D03*
X1267104Y1167768D03*
X1272123D03*
X1268571Y1201043D03*
X1263449Y1217228D03*
X1266113Y1219895D03*
X1269388Y1223170D03*
X1254200Y1146600D03*
X1250928Y1142828D03*
X1439258Y1414600D03*
X1267333Y1531334D03*
X1262891Y1527334D03*
X1267183Y1539334D03*
X1262891Y1535334D03*
X1254275Y1531334D03*
X1249894Y1527805D03*
X1254275Y1539334D03*
X1250434Y1535334D03*
X1758390Y1577905D03*
X1432258Y1414600D03*
X1421964Y1502813D03*
X1420877Y1494706D03*
X1446135Y1530876D03*
X1407255Y1571732D03*
X1423930Y1520364D03*
X1429587Y1527450D03*
X1432913Y1568679D03*
X1443103Y1527201D03*
X1407747Y1549054D03*
X1433405Y1546001D03*
X1441145Y1540415D03*
X1440153Y1563093D03*
X1408536Y1536570D03*
X1430374Y1492474D03*
X1408044Y1559306D03*
X1253904Y1519645D03*
X1443769Y1562173D03*
X1435669Y1005366D03*
X1435197Y1028372D03*
X1420740Y996766D03*
X1428740Y1000766D03*
X1420740Y1008766D03*
X1428864Y996766D03*
X1428740Y1016266D03*
X1420740Y1012266D03*
X1428823Y1020266D03*
X1416736Y1158200D03*
X1419446Y977192D03*
X1389762Y1043055D03*
X1399807Y1036155D03*
X1399852Y1039779D03*
X1392086Y1092743D03*
X1396869Y958707D03*
X1384784Y1033783D03*
X1385929Y1038665D03*
X1373874Y1032266D03*
Y1035716D03*
X1385152Y1046591D03*
X1383024Y1160834D03*
X1373534Y1012325D03*
Y1004680D03*
X1378938Y1000586D03*
X1378559Y1038534D03*
X1357265Y1026266D03*
X1366265Y1039880D03*
X1351149Y1158200D03*
X1347237Y1221428D03*
X1343237D03*
X1339237D03*
X1347237Y1237428D03*
Y1233428D03*
Y1229428D03*
X1343237D03*
Y1233428D03*
Y1237428D03*
X1339237D03*
Y1233428D03*
Y1229428D03*
Y1225428D03*
X1347237Y1245428D03*
Y1241428D03*
X1343237D03*
Y1245428D03*
X1339237D03*
Y1241428D03*
X1335237D03*
X1323237Y1245428D03*
Y1241428D03*
X1327237Y1221428D03*
X1331237D03*
X1335237D03*
X1323237D03*
X1327237Y1237428D03*
Y1233428D03*
Y1229428D03*
Y1225428D03*
X1331237Y1237428D03*
Y1233428D03*
Y1229428D03*
Y1225428D03*
X1335237Y1237428D03*
Y1233428D03*
Y1229428D03*
Y1225428D03*
X1323237Y1237428D03*
Y1233428D03*
Y1229428D03*
Y1225428D03*
X1327237Y1245428D03*
Y1241428D03*
X1331237Y1245428D03*
Y1241428D03*
X1335237Y1245428D03*
X1321028Y961749D03*
X1325550Y960445D03*
X1332000Y969500D03*
X1327000D03*
X1320549Y1037876D03*
X1322773Y1040599D03*
X1319237Y1221428D03*
X1311237Y1233428D03*
Y1229428D03*
Y1225428D03*
X1315237Y1237428D03*
Y1233428D03*
Y1229428D03*
Y1225428D03*
X1319237Y1237428D03*
Y1233428D03*
Y1229428D03*
Y1225428D03*
X1315237Y1241428D03*
X1319237D03*
X1311000Y961500D03*
X1307000Y960500D03*
X1315441Y960000D03*
X1311000Y970124D03*
X1307707Y979870D03*
X1307561Y986951D03*
X1315606Y1042825D03*
X1315756Y1039344D03*
X1312873Y1036543D03*
X1306385Y1036646D03*
X1317437Y1160834D03*
X1311237Y1221428D03*
X1315237D03*
X1414143Y985486D03*
X1412759Y1016266D03*
X1412609Y1008766D03*
X1412698Y997590D03*
X1383162Y991829D03*
X1413177Y1128894D03*
X1455419Y578986D03*
X1458912Y581659D03*
X1437790Y625013D03*
X1435952Y642184D03*
X1449993Y578405D03*
X1435668Y582747D03*
X1435119Y590801D03*
X1425452Y633473D03*
X1430175Y627852D03*
X1420452Y628078D03*
X1415623Y492268D03*
X1416413Y495649D03*
X1415064Y500202D03*
X1405619Y541135D03*
X1405992Y534909D03*
X1401438Y534211D03*
X1405708Y552726D03*
X1405685Y546553D03*
X1407754Y616905D03*
X1407566Y622285D03*
X1411622Y610548D03*
X1401383Y611071D03*
X1407835Y627713D03*
X1413432Y633716D03*
X1407952Y633724D03*
X1418439Y633736D03*
X1431000Y591000D03*
X1436930Y461818D03*
X1434997Y442603D03*
X1427117Y443071D03*
X1432414Y459371D03*
X1418903Y469905D03*
X1431484Y470045D03*
X1403085Y460565D03*
X1417856Y448419D03*
X1414903Y469905D03*
X1410903Y461919D03*
X1418903Y461419D03*
X1411269Y481467D03*
X1415823Y482165D03*
X1410903Y470419D03*
X1480193Y1177691D03*
X1474384D03*
X1480231Y1185164D03*
X1474384D03*
X1480231Y1122164D03*
X1474384D03*
X1483693Y1114691D03*
X1480193D03*
X1474384D03*
X1480231Y1134764D03*
X1474384D03*
X1483693Y1127291D03*
X1480193D03*
X1474384D03*
X1480231Y1147364D03*
X1474384D03*
X1483693Y1139891D03*
X1480193D03*
X1474384D03*
X1480231Y1159964D03*
X1474384D03*
X1483693Y1152491D03*
X1480193D03*
X1474384D03*
X1480231Y1172564D03*
X1474384D03*
X1480193Y1165091D03*
X1474384D03*
X1501640Y1105091D03*
X1480231Y1109564D03*
X1474384D03*
X1505130Y1105091D03*
X1483693Y1102091D03*
X1480193D03*
X1474384D03*
X1489793Y1207737D03*
X1498197Y1209607D03*
X1492471Y1215195D03*
X1484055Y1223749D03*
X1471374Y1118654D03*
X1477846Y1204932D03*
X1483308Y1214372D03*
X1479063Y1218169D03*
X1436736Y1222194D03*
Y1226194D03*
X1432736Y1222194D03*
X1428736D03*
X1424736D03*
X1420736D03*
X1432736Y1226194D03*
Y1230194D03*
Y1234194D03*
X1428736Y1226194D03*
Y1230194D03*
Y1234194D03*
Y1238194D03*
X1424736Y1226194D03*
Y1230194D03*
Y1234194D03*
Y1238194D03*
X1420736Y1226194D03*
Y1230194D03*
Y1234194D03*
Y1238194D03*
X1428736Y1242194D03*
Y1246194D03*
X1424736Y1242194D03*
Y1246194D03*
X1420736Y1242194D03*
Y1246194D03*
X1416736Y1222194D03*
X1412736D03*
X1408736D03*
X1416736Y1226194D03*
Y1230194D03*
Y1234194D03*
Y1238194D03*
X1412736Y1226194D03*
Y1230194D03*
Y1234194D03*
Y1238194D03*
X1408736Y1226194D03*
Y1230194D03*
Y1234194D03*
Y1238194D03*
Y1246194D03*
Y1242194D03*
X1416736D03*
Y1246194D03*
X1412736Y1242194D03*
Y1246194D03*
X1425652Y1297411D03*
X1500675Y1227300D03*
X1507058Y1229402D03*
X1508356Y1220068D03*
X1507692Y1224472D03*
X1506807Y1234921D03*
X1497693Y1230407D03*
X1404019Y1285290D03*
X1415903Y1282590D03*
X1456801Y266114D03*
X1454274Y281982D03*
X1459060Y320861D03*
Y325361D03*
Y329861D03*
Y338861D03*
Y343361D03*
Y334361D03*
Y347861D03*
Y352361D03*
X1448822Y345324D03*
X1448500Y340575D03*
X1439712Y336673D03*
X1449060Y356861D03*
X1447502Y360785D03*
X1443041Y363648D03*
X1434608Y362584D03*
X1445906Y366030D03*
X1451785Y265896D03*
X1446698Y265701D03*
X1448333Y281716D03*
X1448948Y326448D03*
X1449060Y320861D03*
X1438829Y329861D03*
X1437064Y320861D03*
X1440420Y346833D03*
X1434166Y325361D03*
X1434164Y339232D03*
X1434038Y334114D03*
X1409830Y347649D03*
X1547644Y903060D03*
X1504495Y796844D03*
X1510527Y833500D03*
X1495170Y796670D03*
X1486957Y792457D03*
X1493716Y789898D03*
X1491425Y798425D03*
X1496806Y817000D03*
X1496845Y809000D03*
X1487050Y809413D03*
X1496621Y829000D03*
X1495240Y825000D03*
X1493038Y833898D03*
X1486386Y825296D03*
X1492625Y837324D03*
X1486957Y836457D03*
X1491425Y842425D03*
X1496629Y765000D03*
X1496763Y777000D03*
X1493301Y776911D03*
X1496814Y773000D03*
X1496756Y785000D03*
X1499633Y787794D03*
X1497000Y781000D03*
X1552000Y969850D03*
X1551163Y952888D03*
X1515179Y921094D03*
X1521500Y947500D03*
X1505337Y921240D03*
X1509274Y921226D03*
X1509500Y944138D03*
Y937000D03*
X1514354Y938811D03*
X1510500Y931500D03*
X1509500Y950500D03*
X1512161Y957541D03*
X1513955Y950396D03*
X1505888Y965964D03*
X1501400Y966000D03*
X1514000Y968739D03*
X1498973Y975443D03*
X1497063Y934000D03*
X1487240Y952012D03*
X1497075Y961000D03*
X1496072Y950044D03*
X1495500Y972500D03*
X1516500Y947500D03*
X1656509Y265896D03*
X1661525Y266114D03*
X1651422Y265701D03*
X1653057Y281716D03*
X1658998Y281982D03*
X1658200Y315039D03*
X1739508Y1137129D03*
X1732137Y1157404D03*
X1729207Y1159455D03*
X1737393Y1162817D03*
X1729210Y1167768D03*
X1723805Y1142666D03*
X1724191Y1167768D03*
X1711333Y1146609D03*
X1720960Y1148000D03*
X1708015Y1142700D03*
X1812130Y1205349D03*
X1814741Y1217093D03*
X1811482Y1226423D03*
X1806835Y1214668D03*
X1800489Y1220598D03*
X1807243Y1219955D03*
X1802670Y1210905D03*
X1805126Y1225745D03*
X1783278Y1208140D03*
X1762041Y1631511D03*
X1768422Y1632245D03*
X1773820Y1631238D03*
X1777131Y1604357D03*
X1765040Y1599511D03*
X1759947Y1599029D03*
X1750685Y1618504D03*
X1756422Y1640303D03*
X1764422D03*
X1776422D03*
X1779868Y1446668D03*
X1774216Y1470165D03*
X1807270Y1468535D03*
X1807393Y1436345D03*
X1812202Y1432624D03*
X1793879Y1472952D03*
X1786564Y1478858D03*
X1802813Y1464015D03*
X1786091Y1443715D03*
X1793976Y1440762D03*
X1787745Y1437765D03*
X1783178Y1437550D03*
X1795374Y1444543D03*
X1809696Y1091832D03*
X1816756Y1089145D03*
X1816235Y1083970D03*
X1809651Y1096426D03*
X1816756Y1101145D03*
X1810310Y1104819D03*
X1815865Y1133356D03*
X1805013Y1091877D03*
X1801961Y1081717D03*
X1795819Y1088553D03*
X1792847Y1099210D03*
X1799012Y1095893D03*
X1805013Y1096470D03*
X1800813Y1103246D03*
X1792863D03*
G54D55*
X391284Y1307238D03*
X1822594Y1211054D03*
Y1215324D03*
G54D50*
X219881Y1078936D03*
X223622Y1082677D03*
X227362Y1078936D03*
X223622Y1086417D03*
X219881Y1075196D03*
X208661Y1082677D03*
X216141Y1086417D03*
X201181Y1082677D03*
X216141D03*
X201181Y1086417D03*
X208661D03*
X204921Y1078936D03*
Y1075196D03*
X212401D03*
Y1078936D03*
X186220Y1082677D03*
Y1086417D03*
X189960Y1078936D03*
X193700Y1086417D03*
Y1082677D03*
X197440Y1078936D03*
X189960Y1075196D03*
X197440D03*
X174999Y1078936D03*
X182480D03*
X178740Y1082677D03*
Y1086417D03*
X169389Y1084547D03*
Y1080807D03*
X174999Y1075196D03*
X182480D03*
X165649Y1077066D03*
X161909Y1084547D03*
Y1080807D03*
X165649Y1073326D03*
X178740Y1217322D03*
X182480Y1108858D03*
X257283D03*
X204921Y1221062D03*
X208661D03*
X219881D03*
X322736Y1155610D03*
X318996Y1144389D03*
X315255D03*
X318996Y1155610D03*
X315255Y1151869D03*
X318996D03*
Y1148129D03*
X322736Y1144389D03*
Y1151870D03*
X315255Y1148129D03*
Y1155610D03*
X322736Y1166830D03*
X315255Y1159350D03*
X318996D03*
X315255Y1166830D03*
X318996D03*
X322736Y1159350D03*
Y1140649D03*
X318996D03*
X315255D03*
X322736Y1148129D03*
X294685Y1127558D03*
X298425Y1123818D03*
Y1131299D03*
X311515Y1140649D03*
X296555Y1151869D03*
X304035Y1155610D03*
Y1148129D03*
X300295Y1155610D03*
Y1151869D03*
Y1148129D03*
Y1144389D03*
X296555D03*
X311515D03*
X307775Y1148129D03*
X311515Y1151869D03*
X307775Y1155610D03*
X304035Y1144389D03*
Y1151869D03*
X307775Y1144389D03*
Y1151869D03*
X296555Y1155610D03*
X311515Y1148129D03*
Y1155610D03*
X307775Y1159350D03*
X296555D03*
X300295D03*
X296555Y1166830D03*
X300295D03*
X311515D03*
Y1159350D03*
X304035Y1166830D03*
Y1159350D03*
X307775Y1166830D03*
X302165Y1101377D03*
Y1105117D03*
X298425D03*
Y1101376D03*
Y1108858D03*
X302165D03*
X298425Y1112598D03*
Y1120078D03*
Y1116338D03*
X307775Y1140649D03*
X304035D03*
X300295D03*
X298425Y1135039D03*
X294685D03*
X298425Y1127558D03*
X178740Y1194881D03*
X281594Y1140649D03*
Y1136909D03*
X294684Y1123818D03*
Y1131299D03*
X285334Y1140649D03*
Y1136909D03*
X281594Y1148129D03*
Y1155610D03*
Y1151869D03*
X285334D03*
X289074D03*
Y1155610D03*
Y1144389D03*
X292814Y1151869D03*
Y1144389D03*
X285334Y1155610D03*
X281594Y1144389D03*
X285334Y1148129D03*
Y1144389D03*
X289074Y1148129D03*
X292815D03*
Y1155610D03*
X281594Y1159350D03*
X289074Y1166830D03*
Y1159350D03*
X281594Y1170570D03*
Y1166830D03*
X292814Y1159350D03*
Y1166830D03*
X285334Y1170570D03*
Y1166830D03*
Y1159350D03*
X281594Y1178051D03*
Y1174310D03*
X285334D03*
X287204Y1101377D03*
Y1105117D03*
X294684Y1101377D03*
X294685Y1105117D03*
X283464Y1101376D03*
Y1105117D03*
X290944Y1101376D03*
Y1105117D03*
X294684Y1120078D03*
Y1112598D03*
Y1116338D03*
X285334Y1118208D03*
X281594D03*
X285334Y1114468D03*
X281594D03*
X277854Y1178051D03*
Y1174310D03*
X274114Y1178051D03*
X270373Y1204232D03*
X266633D03*
X270373Y1200491D03*
X266633D03*
X272244Y1101377D03*
Y1105117D03*
X279724Y1101377D03*
Y1105117D03*
X268503D03*
X275984D03*
X268503Y1101376D03*
X275984D03*
X274114Y1118208D03*
Y1121948D03*
X270373Y1118208D03*
X266633Y1121948D03*
X270373D03*
X277854Y1118208D03*
Y1121948D03*
X270373Y1114468D03*
X274114D03*
X277854D03*
Y1129429D03*
X274114Y1125688D03*
X270373D03*
Y1129429D03*
X266633Y1125688D03*
X277854Y1133169D03*
Y1125688D03*
X266633Y1129429D03*
X277854Y1181791D03*
X274114Y1174310D03*
X247933Y1204232D03*
X255413D03*
X251673D03*
X259153D03*
X262893D03*
X259153Y1200491D03*
X262893D03*
X251673D03*
X247933D03*
X255413D03*
X249803Y1105117D03*
Y1101377D03*
X257283D03*
Y1105117D03*
X264763Y1101377D03*
Y1105117D03*
X253543D03*
Y1101376D03*
X261023Y1105117D03*
Y1101376D03*
X255413Y1121948D03*
X251673D03*
X247933D03*
X262893D03*
X259153D03*
X262893Y1118208D03*
X259153Y1114468D03*
X262893D03*
X255413Y1118208D03*
Y1114468D03*
X247933D03*
X259153Y1118208D03*
X251673Y1114468D03*
X247933Y1118208D03*
X251673D03*
X247933Y1125688D03*
X251673D03*
X255413D03*
X259153D03*
X262893D03*
X247933Y1129429D03*
X259153D03*
X262893D03*
X255413D03*
X251673D03*
X236712Y1200491D03*
X244192D03*
X240452Y1207972D03*
Y1211712D03*
X242322Y1221062D03*
X244192Y1207972D03*
X236712D03*
Y1211712D03*
X238582Y1224803D03*
Y1228543D03*
X234842D03*
Y1224803D03*
X242322Y1228543D03*
Y1224803D03*
Y1105117D03*
X234842Y1101377D03*
X242322D03*
X234842Y1105117D03*
X246062D03*
X238582Y1101376D03*
X246062D03*
X238582Y1105117D03*
X236712Y1121948D03*
X240452D03*
X244192D03*
X240452Y1114468D03*
X244192D03*
X236712Y1118208D03*
X244192D03*
X236712Y1114468D03*
X240452Y1118208D03*
X236712Y1125688D03*
X240452D03*
X244192D03*
Y1129429D03*
X240452D03*
X236712D03*
X240452Y1204232D03*
X236712D03*
X244192D03*
X240452Y1200491D03*
X231102Y1228543D03*
Y1224803D03*
X219881Y1232283D03*
Y1236023D03*
X227362Y1228543D03*
Y1224803D03*
X219881Y1228543D03*
Y1224803D03*
X231102Y1232283D03*
X223622Y1224803D03*
Y1228543D03*
X218011Y1114468D03*
X225492Y1125688D03*
X218011D03*
X221751D03*
X229330Y1132677D03*
X229232Y1125688D03*
Y1129429D03*
X218011D03*
X221751D03*
X225492D03*
X218011Y1204232D03*
X229232D03*
X225492D03*
X221751D03*
X218011Y1200491D03*
X221751D03*
X225492D03*
X229232D03*
X225492Y1207972D03*
X218011Y1211712D03*
X221751Y1207972D03*
X218011D03*
X229232D03*
Y1211712D03*
Y1215452D03*
X225492Y1211712D03*
X221752D03*
X231102Y1101376D03*
X223621D03*
Y1105117D03*
X231102Y1097637D03*
X227362Y1101377D03*
Y1105117D03*
X219881Y1101377D03*
Y1105117D03*
X231102D03*
X225492Y1118208D03*
Y1121948D03*
X218011Y1118208D03*
X221751D03*
X218011Y1121948D03*
X221751D03*
X229232D03*
Y1118208D03*
Y1114468D03*
X225492D03*
X221752D03*
X214271Y1215452D03*
X204921Y1232283D03*
X201181Y1224803D03*
X212401Y1232283D03*
X208661Y1228543D03*
X212401D03*
X216141Y1232283D03*
X212401Y1224803D03*
X216141Y1236023D03*
X208661Y1232283D03*
X204921Y1228543D03*
X201181Y1232283D03*
X204921Y1224803D03*
X201181Y1236023D03*
X208661D03*
X212401D03*
X216141Y1224803D03*
X208661D03*
X201181Y1228543D03*
X216141D03*
X204921Y1236023D03*
X199311Y1129429D03*
X206791D03*
X199311Y1204232D03*
X203051D03*
X206791D03*
X210531D03*
X214271D03*
Y1200491D03*
X210531D03*
X199311D03*
X206791D03*
X203051D03*
X206791Y1207972D03*
X203051D03*
X210531D03*
X214271D03*
Y1211712D03*
X216141Y1101376D03*
X208661D03*
X204921Y1101377D03*
Y1105117D03*
X212401Y1101377D03*
Y1105117D03*
X208661D03*
X216141D03*
X201181Y1101376D03*
Y1105117D03*
X199311Y1118208D03*
Y1121948D03*
X206791Y1118208D03*
X203051D03*
Y1121948D03*
X206791D03*
X210531Y1118208D03*
X214271Y1114468D03*
X210531Y1121948D03*
X214271Y1118208D03*
Y1121948D03*
X203051Y1114468D03*
X199311D03*
X206791D03*
X210531D03*
X199311Y1125688D03*
X203051D03*
X206791D03*
X214271D03*
X210531D03*
X214271Y1129429D03*
X210531D03*
X203051D03*
X186220Y1217322D03*
X189960Y1213582D03*
X186220Y1224803D03*
X193700Y1228543D03*
X197440Y1224803D03*
X189960Y1228543D03*
Y1224803D03*
X197440Y1228543D03*
X186220D03*
X193700Y1224803D03*
X195570Y1121948D03*
X188090Y1114468D03*
X191830D03*
X195570D03*
X191830Y1125688D03*
X188090D03*
X184350D03*
X188090Y1129429D03*
X184350D03*
X188090Y1133169D03*
X184350D03*
X188090Y1136909D03*
X195570Y1133169D03*
Y1129429D03*
Y1125688D03*
X184350Y1136909D03*
X191830Y1129429D03*
Y1133169D03*
X188090Y1193011D03*
X191830Y1204232D03*
Y1196751D03*
Y1200491D03*
X195570D03*
Y1204232D03*
X193700Y1105117D03*
X186220D03*
X189960Y1101377D03*
Y1105117D03*
X197440Y1101377D03*
Y1105117D03*
X193700Y1101376D03*
X186220D03*
X191830Y1118208D03*
X188090D03*
X184350D03*
X191830Y1121948D03*
X188090D03*
X184350D03*
X195570Y1118208D03*
X171259Y1198621D03*
X174999Y1206102D03*
X171259Y1209842D03*
X174999Y1217322D03*
X171259Y1221062D03*
X174999D03*
X171259Y1217322D03*
X174999Y1209842D03*
X171259Y1213582D03*
X174999D03*
X178740Y1228543D03*
X171259Y1224803D03*
Y1228543D03*
X178740Y1224803D03*
X174999Y1228543D03*
Y1224803D03*
X182480Y1228543D03*
Y1224803D03*
X180610Y1136909D03*
X173129Y1174310D03*
Y1178051D03*
Y1181791D03*
X174999Y1191141D03*
X171259D03*
Y1202362D03*
Y1194881D03*
X174999Y1202362D03*
Y1194881D03*
Y1198621D03*
X171259Y1206102D03*
X174999Y1101377D03*
X169389Y1106988D03*
X174999Y1105117D03*
X182480Y1101377D03*
Y1105117D03*
X178740Y1108858D03*
Y1101376D03*
Y1105117D03*
X169389Y1103247D03*
Y1121948D03*
X176870Y1118208D03*
Y1121948D03*
X169389Y1110728D03*
X180610Y1118208D03*
Y1121948D03*
X173129Y1133169D03*
X169389D03*
X176870Y1125688D03*
Y1129429D03*
Y1133169D03*
Y1136909D03*
X173129Y1129428D03*
X169389D03*
X180610Y1125688D03*
Y1129429D03*
Y1133169D03*
X167519Y1228543D03*
Y1224803D03*
Y1221062D03*
X150689Y1151870D03*
X158169Y1155610D03*
X154429D03*
X150689D03*
X165649Y1148129D03*
Y1144389D03*
Y1155610D03*
X150689Y1159350D03*
X158169Y1166830D03*
X154429D03*
X150688D03*
X154429Y1170570D03*
X150688D03*
X161909Y1159350D03*
X165649Y1166830D03*
Y1170570D03*
Y1178050D03*
Y1174310D03*
X154429Y1092027D03*
X150689D03*
X154429Y1084547D03*
Y1080807D03*
X158169Y1099507D03*
X150689D03*
X158169Y1103247D03*
X150689D03*
X158169Y1106988D03*
X161909Y1095767D03*
X165649Y1099507D03*
Y1103247D03*
Y1106988D03*
X161909D03*
X154429D03*
X150689D03*
X154429Y1095767D03*
X165649D03*
X161909Y1103247D03*
X158169Y1095767D03*
X154429Y1103247D03*
X150689Y1095767D03*
X161909Y1099507D03*
X154429D03*
X158169Y1110728D03*
Y1114468D03*
X154429D03*
X150689D03*
X158169Y1118208D03*
Y1121948D03*
X154429D03*
X150689D03*
X165649Y1114468D03*
X161909D03*
Y1118208D03*
Y1121948D03*
X165649Y1110728D03*
X161909D03*
X154429D03*
Y1118208D03*
X150689Y1110728D03*
Y1118208D03*
X158169Y1133169D03*
X161909Y1140649D03*
X158169Y1125688D03*
Y1129429D03*
X154429D03*
X150689D03*
Y1136909D03*
X154429Y1140649D03*
X150689D03*
X165649D03*
X161909Y1125688D03*
X165649Y1129429D03*
X161909D03*
X165649Y1136909D03*
X158169Y1140649D03*
X154429Y1125688D03*
X150689D03*
X161909Y1144389D03*
Y1148129D03*
Y1151870D03*
Y1155610D03*
X150689Y1144389D03*
X158169Y1151869D03*
X154429D03*
X150689Y1148129D03*
X154429Y1073326D03*
X150689D03*
X150688Y1077066D03*
X154429D03*
X150689Y1080807D03*
Y1084547D03*
X154429Y1088287D03*
X150689D03*
X143208Y1095767D03*
X146948D03*
Y1103247D03*
Y1099507D03*
X143208D03*
X146948Y1106988D03*
X143208D03*
Y1110728D03*
Y1118208D03*
X146948Y1110728D03*
Y1118208D03*
Y1114468D03*
Y1121948D03*
X143208Y1114468D03*
Y1121948D03*
X146948Y1133169D03*
Y1140649D03*
X139468Y1136909D03*
X143208Y1125688D03*
Y1133169D03*
Y1140649D03*
X146948Y1125688D03*
Y1129429D03*
X143208D03*
Y1144389D03*
Y1151870D03*
X146948Y1144389D03*
Y1151870D03*
Y1148129D03*
X143208D03*
Y1159350D03*
X146949Y1166830D03*
X146948Y1159350D03*
Y1092027D03*
X143208Y1103247D03*
X261023Y1108858D03*
X212401Y1221062D03*
X197440Y1108858D03*
X204921D03*
X201181D03*
X197440Y1221062D03*
X186220Y1209842D03*
Y1108858D03*
X290944Y1120078D03*
X178740Y1198621D03*
X290944Y1116338D03*
X178740Y1206102D03*
X146947Y1174310D03*
X290944Y1112598D03*
X150688Y1174310D03*
X178740Y1191141D03*
X182480Y1217322D03*
X189960Y1108858D03*
X253543D03*
X249803D03*
X182480Y1209842D03*
X238582Y1221062D03*
X234842D03*
X201181D03*
X182480Y1206102D03*
X223622Y1221062D03*
X294685Y1108858D03*
X290944D03*
X287204D03*
X283464D03*
X279724D03*
X275984D03*
X182480Y1202362D03*
X178740D03*
X242322Y1108858D03*
X227362Y1221062D03*
X231102D03*
X246062Y1108858D03*
X290944Y1135039D03*
Y1131299D03*
Y1127558D03*
Y1123818D03*
X238582Y1108858D03*
X234842D03*
X193700D03*
X231102D03*
X227362D03*
X223622D03*
X219881D03*
X186220Y1221062D03*
Y1213582D03*
X264763Y1108858D03*
X268503D03*
X272244D03*
X182480Y1221062D03*
X178740D03*
Y1213582D03*
X182480D03*
X178740Y1209842D03*
X208661Y1108858D03*
X216141Y1221062D03*
X266633Y1181791D03*
X270373Y1189271D03*
X266633Y1174310D03*
Y1185531D03*
Y1178051D03*
X270373Y1193011D03*
X266633D03*
Y1140649D03*
X270373D03*
X274114Y1155610D03*
Y1151869D03*
Y1148129D03*
X266633D03*
X270373Y1144389D03*
Y1148129D03*
Y1151869D03*
Y1155610D03*
X266633D03*
Y1151869D03*
Y1144389D03*
X274114Y1166830D03*
Y1159350D03*
X266633Y1170570D03*
Y1159350D03*
X270373D03*
Y1166830D03*
X266633D03*
Y1189271D03*
X270373Y1185531D03*
X251673Y1144389D03*
X247933D03*
X255413D03*
X262893Y1166830D03*
X251673Y1170570D03*
X255413Y1166830D03*
X247933D03*
X251673Y1159350D03*
X259153D03*
Y1170570D03*
X251673Y1166830D03*
X255413Y1170570D03*
X247933D03*
X255413Y1159350D03*
X247933D03*
X259153Y1166830D03*
X262893Y1170570D03*
Y1159350D03*
X247933Y1181791D03*
X251673D03*
X255413D03*
X247933Y1189271D03*
X251673D03*
X255413D03*
X262893D03*
Y1174310D03*
X259153Y1181791D03*
X262893D03*
X259153Y1189271D03*
X255413Y1174310D03*
X247933D03*
X251673D03*
X259153D03*
X247933Y1185531D03*
X255413D03*
X251673D03*
X259153D03*
X262893D03*
X251673Y1178051D03*
X247933D03*
X255413D03*
X259153D03*
X262893D03*
X251673Y1193011D03*
X255413D03*
X247933D03*
X262893D03*
X259153D03*
X247933Y1140649D03*
X251673D03*
X255413D03*
X262893D03*
X259153D03*
Y1148129D03*
X262893D03*
Y1155610D03*
X247933Y1148129D03*
X251673D03*
X255413D03*
X247933Y1155610D03*
X255413D03*
X251673D03*
X259153D03*
Y1151869D03*
X262893D03*
X247933D03*
X255413D03*
X251673D03*
X262893Y1144389D03*
X259153D03*
X236712Y1140649D03*
X240452D03*
X244192D03*
X236712Y1148129D03*
X240452D03*
X244192D03*
X240452Y1155610D03*
X236712D03*
X244192D03*
X240452Y1151869D03*
X236712D03*
X244192D03*
X240452Y1144389D03*
X236712D03*
X244192D03*
X240452Y1166830D03*
X236712Y1170570D03*
Y1159350D03*
X244192Y1170570D03*
Y1159350D03*
X236712Y1166830D03*
X240452Y1170570D03*
Y1159350D03*
X244192Y1166830D03*
X240452Y1181791D03*
X236712D03*
Y1189271D03*
X240452D03*
X244192Y1181791D03*
Y1189271D03*
X240452Y1174310D03*
X236712D03*
X244192D03*
X240452Y1185531D03*
X236712D03*
X244192D03*
X240452Y1178051D03*
X236712D03*
X244192D03*
X240452Y1193011D03*
X236712D03*
X244192D03*
X225492Y1140649D03*
X218011D03*
X221751D03*
X229232D03*
X225492Y1148129D03*
X221751D03*
X218011D03*
X229232D03*
X221751Y1155610D03*
X229232D03*
X218011D03*
X225492D03*
Y1144389D03*
X221751D03*
X218011D03*
X229232D03*
Y1151870D03*
X221752D03*
X218011D03*
X225492D03*
Y1170570D03*
Y1159350D03*
X218011Y1170570D03*
X221752Y1166830D03*
X218011Y1159350D03*
X229232Y1166830D03*
X225492D03*
X221751Y1170570D03*
X218011Y1166830D03*
X221751Y1159350D03*
X229232Y1170570D03*
Y1159350D03*
X225492Y1181791D03*
Y1189271D03*
X221751Y1181791D03*
X218011D03*
X221751Y1189271D03*
X218011D03*
X229232Y1181791D03*
Y1189271D03*
X221751Y1174310D03*
X229232D03*
X225492D03*
X218011D03*
X225492Y1185531D03*
X218011D03*
X221751D03*
X229232D03*
X225492Y1178051D03*
X221751D03*
X218011D03*
X229232D03*
X218011Y1193011D03*
X221751D03*
X225492D03*
X229232D03*
X203051Y1148129D03*
X199311D03*
X206791D03*
X214271D03*
X210531D03*
X199311Y1155610D03*
X206791D03*
X214271D03*
X210531D03*
X203051D03*
X206791Y1144389D03*
X203051D03*
X199311D03*
X214271D03*
X210531D03*
X214271Y1151870D03*
X210531D03*
X206791D03*
X203051D03*
X199311D03*
X206791Y1166830D03*
X203051Y1159350D03*
X199311Y1166830D03*
X203051Y1170570D03*
X214271Y1166830D03*
X210531Y1159350D03*
Y1170570D03*
X214271D03*
X210531Y1166830D03*
X214271Y1159350D03*
X206791Y1170570D03*
X203051Y1166830D03*
X199311Y1170570D03*
X206791Y1159350D03*
X199311D03*
X206791Y1181791D03*
X203051D03*
X199311D03*
X206791Y1189271D03*
X203051D03*
X199311D03*
X214271Y1181791D03*
X210531D03*
X214271Y1189271D03*
X210531D03*
X199311Y1174310D03*
X206791D03*
X214271D03*
X203051D03*
X210531D03*
X203051Y1185531D03*
X199311D03*
X206791D03*
X214271D03*
X210531D03*
X206791Y1178051D03*
X203051D03*
X199311D03*
X214271D03*
X210531D03*
X214271Y1193011D03*
X210531D03*
X199311D03*
X203051D03*
X206791D03*
X199311Y1140649D03*
X203051D03*
X206791D03*
X210531D03*
X214271D03*
X195570D03*
X188090Y1144389D03*
Y1151870D03*
X191830Y1155610D03*
Y1148129D03*
X195570Y1151869D03*
Y1144389D03*
X191830D03*
Y1151869D03*
X195570Y1148129D03*
Y1155610D03*
X188090D03*
X184350Y1151870D03*
X188090Y1148129D03*
Y1159350D03*
Y1170570D03*
X191830Y1166830D03*
X195570Y1159350D03*
Y1170570D03*
X191830Y1159350D03*
Y1170570D03*
X195570Y1166830D03*
X184350Y1159350D03*
Y1170570D03*
X188090Y1166830D03*
Y1185531D03*
Y1178051D03*
X195570Y1189271D03*
X191830Y1181791D03*
Y1174310D03*
X195570Y1185531D03*
Y1178051D03*
X191830Y1185531D03*
Y1178051D03*
X195570Y1181791D03*
Y1174310D03*
X188090D03*
X184350Y1178051D03*
X180610Y1148129D03*
X173129Y1144389D03*
Y1148129D03*
Y1155610D03*
Y1151870D03*
X180610Y1155610D03*
Y1151870D03*
Y1144389D03*
X173129Y1159350D03*
Y1166830D03*
X180610D03*
Y1159350D03*
X188090Y1181791D03*
X317125Y1236023D03*
X324606Y1239763D03*
X313385Y1247243D03*
X320866D03*
X317125Y1250984D03*
X320866Y1239763D03*
X313385Y1243503D03*
X324606Y1247243D03*
X317125Y1254724D03*
X302165Y1236023D03*
X298425Y1247243D03*
X309645Y1250984D03*
X298425Y1243503D03*
X305905D03*
Y1247243D03*
X302165Y1250984D03*
X309645Y1254724D03*
X302165D03*
X294685Y1236023D03*
X309645D03*
X279724D03*
X287204D03*
X268503Y1228543D03*
X264763Y1236023D03*
Y1232283D03*
X268503Y1224803D03*
X272244Y1236023D03*
Y1232283D03*
X261023Y1224803D03*
X253543Y1228543D03*
X257283Y1232283D03*
Y1236023D03*
X261023Y1228543D03*
X253543Y1224803D03*
X662008Y1101377D03*
X665748Y1101376D03*
Y1093897D03*
X658268D03*
Y1101376D03*
X688189Y1097637D03*
X718110Y1108858D03*
X669488Y1090157D03*
Y1086417D03*
X665748Y1078936D03*
X669488Y1082677D03*
X727460Y1181791D03*
X723720Y1196751D03*
X719980D03*
Y1200491D03*
X723720D03*
X719980Y1193011D03*
X723720D03*
X727460Y1121948D03*
X719980D03*
X723720D03*
X727460Y1118208D03*
Y1114468D03*
X719980Y1118208D03*
Y1114468D03*
X727460Y1140649D03*
X723720Y1125688D03*
X719980D03*
X727460Y1129429D03*
Y1125688D03*
X723720Y1140649D03*
X719980D03*
X727460Y1133169D03*
X723720D03*
X719980D03*
X727460Y1136909D03*
X719980Y1129429D03*
X723720D03*
X719980Y1136909D03*
X723720D03*
X727460Y1151869D03*
Y1148129D03*
Y1144389D03*
X723720Y1148129D03*
X719980D03*
Y1155610D03*
X727460D03*
X723720D03*
X719980Y1166830D03*
X727460Y1185531D03*
Y1189271D03*
X723720Y1181791D03*
X719980D03*
Y1174310D03*
X727460Y1178051D03*
X723720Y1189271D03*
X719980D03*
X727460Y1174310D03*
X723720D03*
X705020Y1114468D03*
X712500D03*
X716240D03*
X705020Y1118208D03*
X712500D03*
X708760D03*
X716240Y1140649D03*
Y1125688D03*
Y1133169D03*
X712500Y1125688D03*
X708760D03*
X705020D03*
X712500Y1140649D03*
X708760D03*
X705020D03*
X712500Y1133169D03*
X708760D03*
X705020D03*
Y1129429D03*
X708760D03*
X712500D03*
X716240D03*
Y1136909D03*
X705020D03*
X708760D03*
X712500D03*
X716240Y1148129D03*
X712500D03*
X708760D03*
X705020D03*
X712500Y1155610D03*
X705020D03*
X708760D03*
X716240D03*
Y1170570D03*
Y1159350D03*
X708760D03*
X705020Y1166830D03*
X712500D03*
X708760Y1170570D03*
X716240Y1166830D03*
X705020Y1159350D03*
X712500D03*
X705020Y1170570D03*
X712500D03*
X708760Y1166830D03*
X716240Y1189271D03*
Y1181791D03*
X712500Y1189271D03*
X708760D03*
X705020D03*
X712500Y1181791D03*
X708760D03*
X705020D03*
Y1174310D03*
X712500D03*
X716240D03*
X708760D03*
X716240Y1196751D03*
X712500D03*
X708760D03*
X705020D03*
X712500Y1200491D03*
X705020D03*
X708760D03*
X716240D03*
X708760Y1193011D03*
X712500D03*
X705020D03*
X716240D03*
Y1121948D03*
X705020D03*
X708760D03*
X712500D03*
X708760Y1114468D03*
X716240Y1118208D03*
X693799Y1121948D03*
X697539D03*
X701279D03*
X693799Y1114468D03*
Y1118208D03*
X701279Y1114468D03*
X697539Y1118208D03*
Y1114468D03*
X701279Y1118208D03*
X693799Y1133464D03*
X697539Y1133169D03*
X686417Y1132677D03*
X693799Y1140649D03*
X697539D03*
X693799Y1125688D03*
X697539D03*
X701279D03*
Y1140649D03*
Y1133169D03*
Y1129429D03*
X697539D03*
X693799D03*
X697539Y1136909D03*
X693799D03*
X701279D03*
X697539Y1148129D03*
X701279D03*
X693799D03*
X697539Y1155610D03*
X701279D03*
X693799D03*
X697539Y1166830D03*
X693799Y1170570D03*
Y1159350D03*
X701279D03*
Y1170570D03*
X693799Y1166830D03*
X697539Y1170570D03*
Y1159350D03*
X701279Y1166830D03*
X693799Y1181791D03*
Y1189271D03*
X697539D03*
X701279D03*
Y1181791D03*
X697539D03*
Y1174310D03*
X701279D03*
X693799D03*
Y1204232D03*
Y1196751D03*
X697539D03*
X701279D03*
Y1200491D03*
X697539D03*
X693799D03*
X701279Y1193011D03*
X697539D03*
X693799D03*
Y1207972D03*
Y1211712D03*
X682579Y1170570D03*
Y1159350D03*
X675098Y1170570D03*
X678839Y1166830D03*
X671358D03*
X675098Y1159350D03*
X686319Y1166830D03*
X682579D03*
X678838Y1170570D03*
X671358D03*
X675098Y1166830D03*
X671358Y1159350D03*
X678838D03*
X686319Y1170570D03*
Y1159350D03*
X675098Y1181791D03*
X671358D03*
X678838Y1189271D03*
X675098D03*
X671358D03*
X686319Y1181791D03*
Y1189271D03*
X682579Y1181791D03*
Y1189271D03*
X678838Y1181791D03*
X671358Y1174310D03*
X678838D03*
X686319D03*
X682579D03*
X675098D03*
X682579Y1196751D03*
Y1204232D03*
X678838D03*
Y1196751D03*
X675098D03*
X671358D03*
Y1204232D03*
X675098D03*
X686319Y1196751D03*
Y1204232D03*
Y1200491D03*
X675098D03*
X671358D03*
X678838D03*
X682579D03*
Y1193011D03*
X678838D03*
X675098D03*
X671358D03*
X686319D03*
X682579Y1207972D03*
X675098Y1211712D03*
X678838Y1207972D03*
X675098D03*
X671358D03*
X686319D03*
Y1211712D03*
Y1215452D03*
X682579Y1211712D03*
X678839D03*
Y1215452D03*
X671358Y1211712D03*
Y1215452D03*
X675098D03*
X682579Y1118208D03*
Y1121948D03*
X671358Y1114468D03*
Y1118208D03*
X675098D03*
X678838D03*
X675098Y1121948D03*
X678838D03*
X671358D03*
X686319D03*
Y1118208D03*
Y1114468D03*
X682579D03*
X678839D03*
X675098D03*
X682579Y1133169D03*
Y1140649D03*
Y1125688D03*
X671358Y1140649D03*
X675098D03*
X678838D03*
X675098Y1125688D03*
X671358D03*
X678838D03*
Y1133169D03*
X675098D03*
X671358D03*
X686319Y1140649D03*
Y1125688D03*
Y1129429D03*
X675098D03*
X671358D03*
X678838D03*
X682579D03*
Y1136909D03*
X678838D03*
X675098D03*
X671358D03*
X686319D03*
Y1148129D03*
X682579D03*
X678838D03*
X675098D03*
X671358D03*
X686319Y1155610D03*
X671358D03*
X678838D03*
X682579D03*
X675098D03*
X663878Y1170570D03*
X660138Y1166830D03*
X656398Y1170570D03*
X663878Y1159350D03*
X656398D03*
X667618Y1166830D03*
X663878Y1181791D03*
X660138D03*
X656398D03*
X663878Y1189271D03*
X660138D03*
X656398D03*
X667618Y1181791D03*
Y1189271D03*
X656398Y1174310D03*
X663878D03*
X667618D03*
X660138D03*
X663878Y1196751D03*
X660138D03*
X656398D03*
Y1204232D03*
X660138D03*
X663878D03*
X667618Y1196751D03*
Y1204232D03*
Y1200491D03*
X656398D03*
X663878D03*
X660138D03*
X663878Y1193011D03*
X660138D03*
X656398D03*
X667618D03*
X663878Y1207972D03*
X660138D03*
X656398D03*
X667618D03*
Y1211712D03*
X663878D03*
X656398D03*
X660138Y1215452D03*
X656398D03*
X663878D03*
X667618D03*
X660138Y1211712D03*
X656398Y1118208D03*
Y1121948D03*
X663878Y1118208D03*
X660138D03*
Y1121948D03*
X663878D03*
X667618Y1118208D03*
Y1121948D03*
X660138Y1114468D03*
X656398D03*
X663878D03*
X667618D03*
X656398Y1140649D03*
X660138D03*
X663878D03*
X656398Y1125688D03*
X660138D03*
X663878D03*
Y1133169D03*
X660138D03*
X656398D03*
X667618D03*
Y1140649D03*
Y1125688D03*
Y1129429D03*
X660138D03*
X656398D03*
X663878D03*
Y1136909D03*
X660138D03*
X656398D03*
X667618D03*
Y1148129D03*
X660138D03*
X656398D03*
X663878D03*
X656398Y1155610D03*
X663878D03*
X660138D03*
X667618D03*
X663878Y1166830D03*
X660138Y1159350D03*
X656398Y1166830D03*
X660138Y1170570D03*
X667618Y1159350D03*
Y1170570D03*
X652657Y1211712D03*
X641437D03*
X652657Y1215452D03*
X641437D03*
X648917D03*
X645177D03*
X641437Y1133169D03*
X637697D03*
X648917Y1136909D03*
X652657Y1140649D03*
X648917Y1133169D03*
Y1129429D03*
Y1155610D03*
X652657Y1151869D03*
Y1144389D03*
Y1148129D03*
Y1155610D03*
X648917Y1151869D03*
Y1166830D03*
X652657Y1159350D03*
Y1170570D03*
X648917Y1159350D03*
Y1170570D03*
X652657Y1166830D03*
X645177D03*
X652657Y1174310D03*
Y1204232D03*
X641437D03*
X645177D03*
X648917D03*
X652657Y1200491D03*
X645177Y1211712D03*
X648917D03*
Y1207972D03*
X645177D03*
X641437D03*
X652657D03*
X637697Y1114468D03*
X648917Y1118208D03*
X645177D03*
X641437D03*
X637697D03*
X648917Y1121948D03*
X645177D03*
X641437D03*
X637697D03*
X652657Y1118208D03*
Y1121948D03*
X645177Y1114468D03*
X641437D03*
X648917D03*
X652657D03*
Y1133169D03*
Y1129429D03*
Y1125688D03*
Y1136909D03*
X648917Y1125688D03*
X645177D03*
X641437D03*
X637697D03*
X645177Y1129429D03*
X641437D03*
X637697D03*
X645177Y1133169D03*
X622736Y1077066D03*
X626476Y1084547D03*
X622736Y1092027D03*
Y1099507D03*
Y1103247D03*
X626476Y1106988D03*
X622736D03*
Y1095767D03*
X626476Y1103247D03*
Y1110728D03*
X622736Y1114468D03*
X630216Y1118208D03*
X626476D03*
Y1121948D03*
X633957Y1114468D03*
Y1118208D03*
Y1121948D03*
X622736Y1118208D03*
X626476Y1114468D03*
X622736Y1110728D03*
X630216Y1114468D03*
X633957Y1125688D03*
Y1129429D03*
Y1133169D03*
X630216Y1129428D03*
X626476D03*
X622736Y1073326D03*
Y1080807D03*
Y1084547D03*
Y1088287D03*
X611516Y1106988D03*
X607776D03*
X611516Y1095767D03*
X615256Y1099507D03*
X607776D03*
X615256Y1103247D03*
X607776D03*
X615256Y1106988D03*
X618996Y1095767D03*
X607776D03*
X615256D03*
X618996Y1103247D03*
X611516D03*
X618996Y1099507D03*
X611516D03*
X615256Y1110728D03*
Y1114468D03*
X611516D03*
X615256Y1118208D03*
X618996Y1114468D03*
Y1118208D03*
Y1121948D03*
X611516Y1110728D03*
X618996D03*
X607776D03*
X611516Y1073326D03*
X618996D03*
X615256D03*
X607776D03*
X618996Y1088287D03*
Y1092027D03*
X607775Y1077066D03*
X611516D03*
X615256Y1080807D03*
X607776D03*
X615256Y1084547D03*
X607776D03*
X615256Y1088287D03*
X611516D03*
X607776D03*
X611516Y1092027D03*
X618996Y1077066D03*
Y1084547D03*
Y1080807D03*
X615256Y1077066D03*
X611516Y1080807D03*
Y1084547D03*
X607776Y1092027D03*
X615256D03*
X618996Y1106988D03*
X680709Y1090157D03*
X676968Y1105117D03*
X684449Y1101377D03*
Y1105117D03*
X688189Y1093897D03*
X600295Y1084547D03*
Y1092027D03*
X604035Y1077066D03*
Y1080806D03*
Y1084547D03*
Y1092027D03*
X600295Y1088287D03*
X604035D03*
Y1103247D03*
X600295D03*
Y1095767D03*
X604035D03*
X600295Y1099507D03*
X604035D03*
X600295Y1106988D03*
X604035D03*
X600295Y1110728D03*
X604035D03*
X662008Y1078936D03*
X676968Y1090157D03*
X658268Y1082677D03*
X639566Y1071455D03*
X632085D03*
X703149Y1108858D03*
X665748Y1090157D03*
X699409Y1105117D03*
X688189Y1108858D03*
X710630D03*
X684449D03*
X691929D03*
X635827Y1217322D03*
X721850Y1108858D03*
X635827Y1213582D03*
Y1209842D03*
Y1206102D03*
Y1202362D03*
X643307Y1108858D03*
X647047D03*
X650787D03*
X654527D03*
X658268D03*
X662008D03*
X665748D03*
X669488D03*
X673228D03*
X676968D03*
X680709D03*
X695669D03*
X658268Y1086417D03*
X721850Y1101377D03*
X669488Y1093897D03*
X639567D03*
X635827Y1101376D03*
X639567Y1101377D03*
X635827Y1105117D03*
X639567Y1097637D03*
X635827Y1093897D03*
X643307Y1075196D03*
X632086D03*
X635827D03*
X639567D03*
X669488Y1097637D03*
X639567Y1105117D03*
X598424Y1206103D03*
X721850Y1105117D03*
X650787Y1078936D03*
X691929Y1101377D03*
X650787Y1082677D03*
Y1101376D03*
X647047Y1097637D03*
X643307Y1090157D03*
X635827Y1082677D03*
Y1090157D03*
X639567D03*
X654527Y1082677D03*
Y1086417D03*
Y1090157D03*
X647047Y1075196D03*
X654527D03*
X650787D03*
X669488D03*
X647047Y1105117D03*
Y1101377D03*
X654527Y1105117D03*
Y1101377D03*
X650787Y1097637D03*
X643307D03*
Y1101376D03*
Y1105117D03*
X647047Y1082677D03*
Y1086417D03*
Y1078936D03*
X654527D03*
X643307D03*
Y1082677D03*
Y1086417D03*
Y1093897D03*
X635827Y1078936D03*
X650787Y1105117D03*
Y1093897D03*
Y1090157D03*
X647047D03*
X650787Y1086417D03*
X632086Y1090157D03*
X639567Y1078936D03*
Y1086417D03*
Y1082677D03*
X635827Y1086417D03*
X680709Y1075196D03*
X602165Y1243503D03*
X680709Y1093897D03*
X662008D03*
X635827Y1097637D03*
X662008D03*
X658268Y1105117D03*
X632086Y1082677D03*
X676968Y1075196D03*
X632086Y1093897D03*
Y1086417D03*
Y1078936D03*
X602165Y1228543D03*
X617126Y1243503D03*
Y1239763D03*
X620866D03*
X613386D03*
X609646Y1243503D03*
Y1239763D03*
X620866Y1254724D03*
Y1250984D03*
X617126Y1247243D03*
X609646D03*
X613386Y1254724D03*
Y1250984D03*
Y1243503D03*
Y1247243D03*
X609646Y1250984D03*
Y1254724D03*
X617126D03*
Y1250984D03*
X620866Y1247243D03*
Y1243503D03*
X632086Y1228543D03*
Y1224803D03*
X624606D03*
Y1228543D03*
X628346Y1236023D03*
X665748Y1105117D03*
X613386Y1202362D03*
X609646D03*
X613386Y1221062D03*
X609646D03*
Y1213582D03*
X613386D03*
Y1217322D03*
X609646D03*
Y1209842D03*
X613386D03*
X617126Y1202362D03*
X620866Y1206102D03*
X617126D03*
X620866Y1202362D03*
X617126Y1213582D03*
Y1209842D03*
X620866Y1213582D03*
Y1209842D03*
X632086Y1202362D03*
X628346D03*
X624606Y1206102D03*
X632086D03*
X628346D03*
X624606Y1202362D03*
Y1213582D03*
X632086Y1209842D03*
X628346D03*
X632086Y1213582D03*
X628346D03*
X624606Y1209842D03*
X620866Y1221062D03*
X617126D03*
Y1217322D03*
X620866D03*
X628346D03*
Y1221062D03*
X624606D03*
Y1217322D03*
X632086Y1221062D03*
Y1217322D03*
X673228Y1075196D03*
X676968Y1101377D03*
X680709Y1097637D03*
X658268Y1075196D03*
X662008D03*
X665748D03*
X647047Y1093897D03*
X654527Y1097637D03*
Y1093897D03*
X669488Y1078936D03*
X602165Y1239763D03*
X662008Y1105117D03*
X658268Y1090157D03*
X662008Y1082677D03*
Y1086417D03*
Y1090157D03*
X718110Y1101376D03*
X602165Y1250984D03*
X706890Y1101377D03*
Y1105117D03*
X714370D03*
Y1101377D03*
X680709Y1086417D03*
Y1082677D03*
X676968Y1078936D03*
X673228Y1082677D03*
Y1086417D03*
Y1090157D03*
Y1078936D03*
X703149Y1105117D03*
X680709Y1078936D03*
X699409Y1101377D03*
X676968Y1082677D03*
Y1086417D03*
X691929Y1105117D03*
X695669Y1101376D03*
Y1105117D03*
X703149Y1101376D03*
X710630Y1105117D03*
Y1101376D03*
X718110Y1105117D03*
X684449Y1097637D03*
Y1093897D03*
X676968Y1097637D03*
Y1093897D03*
X688189Y1105117D03*
Y1101376D03*
X680708Y1105117D03*
Y1101376D03*
X673228Y1105117D03*
Y1101376D03*
Y1097637D03*
Y1093897D03*
X658268Y1097637D03*
X725590Y1105117D03*
X669488Y1101377D03*
Y1105117D03*
X725590Y1101376D03*
X665748Y1082677D03*
Y1086417D03*
Y1097637D03*
X691929Y1221062D03*
X613386Y1206102D03*
X635827Y1221062D03*
X658268D03*
X662008D03*
X665748D03*
X669488D03*
X673228D03*
X684449D03*
X688189D03*
X658268Y1078936D03*
X605905Y1224803D03*
Y1232283D03*
Y1236023D03*
Y1228543D03*
Y1243503D03*
Y1254724D03*
Y1250984D03*
Y1239763D03*
Y1247243D03*
X620866Y1236023D03*
Y1232283D03*
X617126Y1228543D03*
Y1224803D03*
X609646D03*
Y1228543D03*
X613386Y1232283D03*
Y1236023D03*
X617126Y1232283D03*
Y1236023D03*
X609646D03*
Y1232283D03*
X620866Y1228543D03*
Y1224803D03*
X613386Y1228543D03*
Y1224803D03*
X628346Y1232283D03*
X635827Y1236023D03*
Y1232283D03*
X639567Y1224803D03*
Y1228543D03*
Y1236023D03*
Y1232283D03*
X632086Y1236023D03*
Y1232283D03*
X635827Y1228543D03*
Y1224803D03*
X628346Y1228543D03*
Y1224803D03*
X624606Y1236023D03*
Y1232283D03*
X632086Y1247243D03*
Y1243503D03*
X635827Y1239763D03*
X632086D03*
X628346D03*
Y1250984D03*
X624606Y1243503D03*
Y1239763D03*
X635827Y1254724D03*
Y1250984D03*
X628346Y1254724D03*
X624606Y1247243D03*
X628346Y1243503D03*
Y1247243D03*
X624606Y1250984D03*
Y1254724D03*
X632086D03*
Y1250984D03*
X635827Y1247243D03*
Y1243503D03*
X647047Y1228543D03*
Y1224803D03*
X654527D03*
Y1228543D03*
X650787Y1224803D03*
Y1228543D03*
X643307D03*
Y1224803D03*
X662008Y1228543D03*
Y1224803D03*
X669488Y1228543D03*
Y1224803D03*
X665748D03*
Y1228543D03*
X658268D03*
Y1224803D03*
X676968D03*
Y1228543D03*
X684449Y1224803D03*
Y1228543D03*
X688189Y1232283D03*
Y1228543D03*
Y1224803D03*
X680709D03*
Y1228543D03*
X673228D03*
Y1224803D03*
X691929D03*
Y1228543D03*
X602165Y1202362D03*
X605905D03*
X602165Y1206102D03*
X605905D03*
Y1217322D03*
X602165D03*
X605905Y1209842D03*
X602165D03*
Y1221062D03*
X605905D03*
Y1213582D03*
X602165D03*
Y1224803D03*
Y1236023D03*
Y1232283D03*
X609646Y1206102D03*
X602165Y1247243D03*
X714370Y1108858D03*
X706890D03*
X676967Y1071455D03*
X632087Y1258465D03*
X598424Y1213583D03*
Y1228542D03*
X598423Y1239762D03*
X669487Y1071455D03*
X617126Y1258465D03*
X624606D03*
X647046Y1071455D03*
X598424Y1221063D03*
X598423Y1247242D03*
X662007Y1071455D03*
X609646Y1258465D03*
X654526Y1071455D03*
X725590Y1108858D03*
X699409D03*
X783563Y1140649D03*
Y1155610D03*
Y1148129D03*
X776083D03*
Y1151869D03*
X772342D03*
X776083Y1155610D03*
X772342Y1144389D03*
X768602Y1151869D03*
Y1144389D03*
X776083D03*
X779823Y1155610D03*
Y1148129D03*
X772342D03*
Y1155610D03*
X783563Y1151870D03*
X779823D03*
Y1144389D03*
X783563D03*
X768602Y1155610D03*
Y1148129D03*
Y1159350D03*
X776083D03*
X772342D03*
X779823D03*
X783563D03*
X776083Y1140649D03*
X779823D03*
X757382D03*
X761122D03*
X764862D03*
Y1155610D03*
Y1148129D03*
X753642Y1144389D03*
X757382D03*
Y1148129D03*
Y1151869D03*
Y1155610D03*
X761122Y1148129D03*
Y1155610D03*
X753642Y1151869D03*
X761122Y1144389D03*
Y1151869D03*
X753642Y1155610D03*
X764862Y1151869D03*
Y1144389D03*
Y1159350D03*
X757382D03*
X753642D03*
X761122D03*
X738681Y1155610D03*
Y1148129D03*
X749901Y1144389D03*
Y1151869D03*
X742421Y1155610D03*
X746161Y1148129D03*
X738681Y1144389D03*
X742421Y1148129D03*
Y1144389D03*
X749902Y1155610D03*
Y1148129D03*
X738681Y1166830D03*
X746161D03*
X738681Y1159350D03*
X749901Y1166830D03*
Y1159350D03*
X746161D03*
X742421D03*
Y1166830D03*
X738681Y1114468D03*
X742421D03*
X738681Y1136909D03*
Y1140649D03*
X742421D03*
Y1136909D03*
X746161Y1144389D03*
Y1155610D03*
Y1151869D03*
X742421D03*
X738681D03*
X734941Y1121948D03*
Y1118208D03*
Y1114468D03*
Y1129429D03*
Y1125688D03*
Y1140649D03*
Y1133169D03*
Y1136909D03*
Y1151870D03*
Y1148129D03*
Y1144389D03*
Y1155610D03*
Y1159350D03*
Y1166830D03*
X748031Y1120078D03*
Y1135039D03*
Y1131299D03*
Y1127558D03*
Y1116338D03*
X755512Y1131299D03*
Y1127558D03*
Y1135039D03*
Y1116338D03*
Y1123818D03*
Y1120078D03*
X751771Y1131299D03*
X751772Y1127558D03*
Y1135039D03*
X751771Y1116338D03*
Y1123818D03*
Y1112598D03*
Y1120078D03*
X748031Y1123818D03*
Y1112598D03*
X1072342Y1077066D03*
Y1073326D03*
X1068602Y1084547D03*
Y1080807D03*
X1064862Y1073326D03*
X1083562Y1084547D03*
X1079822Y1077066D03*
X1083562Y1080807D03*
X1079822Y1073326D03*
X1076082Y1084547D03*
Y1080807D03*
X1089172Y1075196D03*
Y1078936D03*
X1092913Y1086417D03*
Y1082677D03*
X1104133Y1075196D03*
X1096653D03*
X1104133Y1078936D03*
X1107873Y1082677D03*
Y1086417D03*
X1100393D03*
Y1082677D03*
X1096653Y1078936D03*
X1126574Y1075196D03*
X1119094D03*
X1111613D03*
X1126574Y1078936D03*
X1122834Y1086417D03*
Y1082677D03*
X1119094Y1078936D03*
X1115354Y1086417D03*
Y1082677D03*
X1111613Y1078936D03*
X1134054Y1075196D03*
X1141535Y1078936D03*
X1137795Y1086417D03*
Y1082677D03*
X1134054Y1078936D03*
X1130314Y1082677D03*
Y1086417D03*
X1072342Y1174310D03*
Y1099507D03*
Y1095767D03*
Y1106988D03*
Y1103247D03*
Y1121948D03*
Y1118208D03*
Y1114468D03*
Y1110728D03*
Y1140649D03*
Y1129429D03*
Y1125688D03*
Y1155610D03*
Y1151869D03*
Y1166830D03*
X1061121Y1125688D03*
X1057381Y1140649D03*
Y1133169D03*
Y1125688D03*
X1064862D03*
X1068602D03*
X1057381Y1129429D03*
X1061121D03*
X1057381Y1136909D03*
X1064862Y1133169D03*
X1061121Y1136909D03*
X1064862Y1155610D03*
X1068602D03*
X1061121Y1151870D03*
X1064862D03*
Y1148129D03*
X1068602Y1151869D03*
X1061121Y1144389D03*
X1064862D03*
X1057381Y1151870D03*
Y1144389D03*
X1061121Y1148129D03*
X1057381D03*
X1064861Y1170570D03*
X1068602D03*
X1064861Y1166830D03*
X1068602D03*
X1061121Y1159350D03*
X1064862D03*
X1061122Y1166830D03*
X1057381Y1159350D03*
X1068602Y1174310D03*
X1061120D03*
X1064861D03*
X1061121Y1095767D03*
X1068602D03*
X1064862Y1106988D03*
X1068602D03*
X1061121Y1103247D03*
X1064862D03*
Y1099507D03*
X1057381Y1095767D03*
Y1103247D03*
X1068602Y1099507D03*
X1057381Y1106988D03*
X1061121D03*
X1057381Y1099507D03*
X1068602Y1103247D03*
X1064862Y1095767D03*
X1061121Y1099507D03*
X1064862Y1121948D03*
X1068602D03*
X1061121Y1118208D03*
X1064862Y1114468D03*
X1068602D03*
X1061121Y1110728D03*
X1057381Y1118208D03*
Y1110728D03*
Y1114468D03*
X1061121D03*
X1068602Y1110728D03*
Y1118208D03*
X1064862Y1110728D03*
Y1118208D03*
X1057381Y1121948D03*
X1061121D03*
Y1140649D03*
X1064862D03*
X1068602D03*
X1064862Y1136909D03*
X1061121Y1133169D03*
X1064862Y1129429D03*
X1068602D03*
X1141535Y1221062D03*
X1137795Y1108858D03*
X1205117Y1123818D03*
X1092913Y1206102D03*
Y1209842D03*
X1190157Y1108858D03*
X1152755D03*
X1236909Y1140649D03*
X1233169D03*
X1225688D03*
X1229428D03*
X1236909Y1148129D03*
Y1155610D03*
X1233169Y1144389D03*
X1225688D03*
Y1151869D03*
X1229428Y1144389D03*
X1233169Y1155610D03*
X1229428Y1151869D03*
X1233169D03*
Y1148129D03*
X1236909Y1151870D03*
X1225688Y1148129D03*
X1229428D03*
X1225688Y1155610D03*
X1236909Y1144389D03*
X1229428Y1155610D03*
X1236909Y1166830D03*
X1225688D03*
X1229428Y1159350D03*
X1233169D03*
X1225688D03*
X1229428Y1166830D03*
X1233169D03*
X1236909Y1159350D03*
X1221948Y1140649D03*
X1206988D03*
X1221948Y1155610D03*
X1210728Y1151869D03*
X1206987D03*
X1218208Y1155610D03*
Y1148129D03*
X1214468Y1155610D03*
Y1151869D03*
Y1148129D03*
Y1144389D03*
X1206987D03*
X1210728D03*
X1221948Y1148129D03*
X1218208Y1144389D03*
Y1151869D03*
X1206988Y1155610D03*
Y1148129D03*
X1210728Y1155610D03*
X1221948Y1151869D03*
Y1144389D03*
X1206987Y1159350D03*
X1210728D03*
X1214468D03*
X1210728Y1166830D03*
X1206987D03*
X1214468D03*
X1221948Y1159350D03*
X1218208Y1166830D03*
Y1159350D03*
X1221948Y1166830D03*
X1218208Y1140649D03*
X1214468D03*
X1192027Y1181791D03*
Y1178051D03*
X1195767Y1189271D03*
Y1185531D03*
Y1178051D03*
Y1174310D03*
X1192027D03*
X1195767Y1193011D03*
X1192027Y1204232D03*
X1195767Y1140649D03*
X1192027Y1133169D03*
X1195767Y1136909D03*
X1192027Y1125688D03*
Y1129429D03*
X1199507Y1140649D03*
Y1136909D03*
X1203247Y1140649D03*
X1195767Y1148129D03*
Y1155610D03*
Y1151869D03*
X1199507D03*
X1203247D03*
Y1155610D03*
Y1144389D03*
X1199507Y1155610D03*
X1203247Y1148129D03*
X1195767Y1144389D03*
X1199507Y1148129D03*
Y1144389D03*
X1195767Y1170570D03*
Y1159350D03*
X1203247Y1166830D03*
Y1159350D03*
X1195767Y1166830D03*
X1199507D03*
Y1159350D03*
X1192027Y1118208D03*
Y1121948D03*
X1199507Y1118208D03*
X1195767D03*
Y1114468D03*
X1192027D03*
X1199507D03*
X1188287Y1174310D03*
Y1178051D03*
X1184546Y1204232D03*
X1177066D03*
X1180806D03*
X1184546Y1200491D03*
X1188287Y1204232D03*
X1180806Y1200491D03*
X1177066D03*
X1092913Y1217322D03*
X1188287Y1125688D03*
X1184546D03*
Y1129429D03*
X1177066Y1125688D03*
X1180806D03*
Y1129429D03*
X1177066D03*
X1188287Y1118208D03*
Y1121948D03*
X1184546Y1118208D03*
X1180806Y1121948D03*
X1177066D03*
X1184546D03*
X1188287Y1114468D03*
X1177066D03*
Y1118208D03*
X1184546Y1114468D03*
X1158365Y1207972D03*
X1092913Y1213582D03*
X1162106Y1204232D03*
X1158365D03*
X1169586D03*
X1165846D03*
X1173326D03*
Y1200491D03*
X1165846D03*
X1162106D03*
X1158365D03*
X1169586D03*
X1158365Y1125688D03*
X1162106D03*
X1165846D03*
X1169586D03*
X1173326D03*
X1169586Y1129429D03*
X1165846D03*
X1162106D03*
X1158365D03*
X1173326D03*
X1169586Y1121948D03*
X1165846D03*
X1162106D03*
X1158365D03*
X1173326D03*
X1162106Y1114468D03*
X1169586D03*
X1162106Y1118208D03*
X1173326Y1114468D03*
X1158365Y1118208D03*
X1173326D03*
X1165846Y1114468D03*
X1158365D03*
X1169586Y1118208D03*
X1165846D03*
X1154625Y1204232D03*
X1150885D03*
X1143405D03*
Y1200491D03*
X1154625D03*
X1150885D03*
Y1207972D03*
X1154625D03*
Y1211712D03*
X1143405Y1207972D03*
Y1211712D03*
Y1215452D03*
X1150885Y1211712D03*
Y1121948D03*
X1143405D03*
Y1118208D03*
Y1114468D03*
X1154625Y1121948D03*
Y1118208D03*
X1150885D03*
X1154625Y1114468D03*
X1150885D03*
X1154625Y1125688D03*
X1143503Y1132677D03*
X1143405Y1125688D03*
X1150885D03*
X1154625Y1129429D03*
X1150885D03*
X1143405D03*
X1139665Y1204232D03*
X1135924D03*
X1128444D03*
X1132184D03*
Y1200491D03*
X1128444D03*
X1135924D03*
X1139665D03*
Y1207972D03*
X1132184Y1211712D03*
X1135924Y1207972D03*
X1132184D03*
X1128444D03*
X1139665Y1211712D03*
X1135925D03*
X1128444Y1215452D03*
Y1211712D03*
X1139665Y1125688D03*
X1132184D03*
X1128444D03*
X1135924D03*
X1132184Y1129429D03*
X1128444D03*
X1135924D03*
X1139665D03*
Y1121948D03*
X1128444Y1118208D03*
X1132184D03*
X1135924D03*
X1132184Y1121948D03*
X1135924D03*
X1128444D03*
X1139665Y1118208D03*
Y1114468D03*
X1135925D03*
X1124704Y1204232D03*
X1120964D03*
X1117224D03*
X1113484D03*
X1109743D03*
Y1200491D03*
X1117224D03*
X1120964D03*
X1113484D03*
X1124704D03*
X1113484Y1207972D03*
X1117224D03*
X1120964D03*
X1109743Y1211712D03*
Y1207972D03*
X1124704Y1211712D03*
Y1207972D03*
Y1215452D03*
X1120964D03*
Y1211712D03*
X1113484D03*
X1117224D03*
Y1121948D03*
Y1118208D03*
X1120964D03*
X1109743Y1121948D03*
X1113484D03*
X1109743Y1118208D03*
X1113484D03*
X1124704Y1121948D03*
Y1118208D03*
X1120964Y1121948D03*
X1117224Y1114468D03*
X1113484D03*
X1120964D03*
X1124704D03*
X1109743D03*
X1124704Y1125688D03*
X1109743D03*
X1120964D03*
X1117224D03*
X1113484D03*
X1109743Y1129429D03*
Y1133169D03*
X1120964Y1129429D03*
X1113484D03*
X1117224D03*
X1124704D03*
X1098523Y1207972D03*
X1102263D03*
X1106003D03*
Y1211712D03*
X1102263D03*
X1098523D03*
X1106003Y1215452D03*
X1098523D03*
X1102263D03*
X1098523Y1196751D03*
X1106003Y1200491D03*
Y1196751D03*
Y1204232D03*
X1102263D03*
X1098523D03*
Y1200491D03*
X1102263D03*
Y1196751D03*
X1094783Y1133169D03*
X1098523D03*
X1102263D03*
X1094783Y1129429D03*
X1098523D03*
X1102263D03*
X1094783Y1125688D03*
X1098523D03*
X1102263D03*
X1106003D03*
Y1133169D03*
Y1129429D03*
X1094783Y1121948D03*
X1098523D03*
X1102263D03*
X1106003D03*
X1094783Y1118208D03*
X1098523D03*
X1102263D03*
X1106003D03*
X1094783Y1114468D03*
X1102263D03*
X1098523D03*
X1106003D03*
X1079822Y1170570D03*
Y1166830D03*
Y1174310D03*
X1087302Y1178051D03*
Y1174310D03*
X1083562Y1121948D03*
Y1118208D03*
X1087302D03*
X1079822Y1114468D03*
X1083562Y1110728D03*
X1091043Y1121948D03*
Y1118208D03*
Y1114468D03*
X1079822Y1118208D03*
Y1110728D03*
X1083562Y1114468D03*
X1087302D03*
X1091043Y1125688D03*
X1079822Y1129429D03*
X1083562Y1129428D03*
X1087302D03*
X1079822Y1140649D03*
X1091043Y1133169D03*
Y1129429D03*
X1079822Y1144389D03*
Y1148129D03*
Y1155610D03*
X1083562Y1099507D03*
Y1095767D03*
X1079822Y1106988D03*
X1083562D03*
X1079822Y1103247D03*
Y1099507D03*
Y1095767D03*
X1083562Y1103247D03*
X1076082Y1106988D03*
Y1095767D03*
Y1103247D03*
Y1099507D03*
Y1114468D03*
Y1121948D03*
Y1118208D03*
Y1110728D03*
Y1133169D03*
Y1129429D03*
Y1125688D03*
Y1140649D03*
Y1155610D03*
Y1151870D03*
Y1148129D03*
Y1144389D03*
Y1159350D03*
Y1178051D03*
Y1174310D03*
X1130314Y1108858D03*
X1160235D03*
X1175196D03*
X1205117Y1127558D03*
X1182676Y1108858D03*
X1156495Y1221062D03*
X1163976Y1108858D03*
X1201377D03*
X1197637D03*
X1089172Y1191141D03*
X1085432D03*
Y1198621D03*
X1089172D03*
X1085432Y1194881D03*
X1089172D03*
X1085432Y1206102D03*
X1089172D03*
X1085432Y1202362D03*
X1089172D03*
X1085432Y1209842D03*
X1089172D03*
Y1217322D03*
Y1221062D03*
X1081692D03*
X1085432D03*
Y1217322D03*
Y1213582D03*
X1089172D03*
X1085432Y1224803D03*
Y1228543D03*
X1081692D03*
Y1224803D03*
X1089172D03*
Y1228543D03*
X1092913Y1224803D03*
Y1228543D03*
X1100393Y1224803D03*
Y1228543D03*
X1107873D03*
Y1224803D03*
X1104133D03*
Y1228543D03*
X1096653D03*
Y1224803D03*
X1115354D03*
Y1228543D03*
X1119094Y1236023D03*
Y1232283D03*
X1122834Y1228543D03*
Y1224803D03*
X1126574Y1232283D03*
Y1236023D03*
Y1224803D03*
Y1228543D03*
X1122834Y1232283D03*
Y1236023D03*
X1119094Y1224803D03*
Y1228543D03*
X1115354Y1232283D03*
Y1236023D03*
X1111613Y1228543D03*
Y1224803D03*
X1130314D03*
Y1228543D03*
X1134054Y1236023D03*
Y1232283D03*
X1137795Y1228543D03*
Y1224803D03*
X1141535Y1228543D03*
Y1224803D03*
X1134054Y1228543D03*
Y1224803D03*
X1130314Y1232283D03*
Y1236023D03*
X1152755Y1224803D03*
X1156495Y1228543D03*
Y1224803D03*
X1149015Y1228543D03*
X1152755D03*
X1149015Y1224803D03*
X1145275D03*
Y1228543D03*
Y1232283D03*
X1092913Y1101376D03*
X1089172Y1101377D03*
X1107873Y1101376D03*
X1104133Y1101377D03*
X1100393Y1101376D03*
X1096653Y1101377D03*
X1115354Y1101376D03*
X1122834D03*
X1119094Y1101377D03*
X1126574D03*
X1111613D03*
X1137794Y1101376D03*
X1130314D03*
X1134054Y1101377D03*
X1141535D03*
X1152755Y1101376D03*
X1149015Y1101377D03*
X1156495D03*
X1145275Y1101376D03*
Y1097637D03*
X1175196Y1101376D03*
X1167716D03*
X1163976Y1101377D03*
X1171456D03*
X1160235Y1101376D03*
X1190157D03*
X1182676D03*
X1178936Y1101377D03*
X1186417D03*
X1205117Y1101376D03*
X1197637D03*
X1201377Y1101377D03*
X1193897D03*
X1212598Y1101376D03*
X1216338Y1101377D03*
X1208857D03*
X1092913Y1105117D03*
X1107873D03*
X1104133D03*
X1100393D03*
X1096653D03*
X1115354D03*
X1122834D03*
X1119094D03*
X1126574D03*
X1111613D03*
X1137794D03*
X1130314D03*
X1134054D03*
X1141535D03*
X1152755D03*
X1149015D03*
X1156495D03*
X1145275D03*
X1175196D03*
X1167716D03*
X1163976D03*
X1171456D03*
X1160235D03*
X1190157D03*
X1182676D03*
X1178936D03*
X1186417D03*
X1205117D03*
X1197637D03*
X1201377D03*
X1193897D03*
X1212598D03*
X1216338D03*
X1208858D03*
X1212598Y1108858D03*
X1216338D03*
X1212598Y1116338D03*
Y1123818D03*
Y1120078D03*
X1208857Y1116338D03*
Y1123818D03*
Y1112598D03*
Y1120078D03*
X1212598Y1131299D03*
Y1127558D03*
X1208857Y1131299D03*
X1208858Y1127558D03*
X1212598Y1135039D03*
X1149015Y1221062D03*
X1085432Y1187401D03*
X1122834Y1221062D03*
X1126574Y1108858D03*
X1186417D03*
X1119094Y1221062D03*
X1130314D03*
X1115354D03*
X1208858Y1108858D03*
X1111613Y1221062D03*
X1137795D03*
X1152755D03*
X1122834Y1108858D03*
X1149015D03*
X1178936D03*
X1205117Y1120078D03*
X1145275Y1108858D03*
Y1221062D03*
X1134054D03*
X1115354Y1108858D03*
X1104133D03*
X1134054D03*
X1119094D03*
X1205117Y1131299D03*
X1126574Y1221062D03*
X1193897Y1108858D03*
X1092913Y1194881D03*
Y1191141D03*
Y1198621D03*
X1205117Y1108858D03*
X1092913Y1221062D03*
X1205117Y1116338D03*
X1111613Y1108858D03*
X1141535D03*
X1107873D03*
X1092913Y1202362D03*
X1100393Y1108858D03*
X1156495D03*
X1167716D03*
X1171456D03*
X1167716Y1228543D03*
Y1224803D03*
X1175196D03*
Y1228543D03*
X1171456Y1232283D03*
Y1236023D03*
X1178936D03*
Y1232283D03*
X1182676Y1224803D03*
Y1228543D03*
X1186417Y1236023D03*
Y1232283D03*
X1190157Y1228543D03*
Y1224803D03*
X1197637D03*
Y1228543D03*
X1201377Y1232283D03*
Y1236023D03*
X1205117Y1228543D03*
Y1224803D03*
X1193897Y1236023D03*
Y1232283D03*
X1205117Y1243503D03*
X1212598Y1224803D03*
Y1228543D03*
X1220078Y1224803D03*
Y1228543D03*
X1216338Y1232283D03*
Y1236023D03*
X1223818D03*
Y1232283D03*
X1208858Y1236023D03*
Y1232283D03*
X1220078Y1243503D03*
Y1247243D03*
X1223818Y1250984D03*
Y1254724D03*
X1216338D03*
Y1250984D03*
X1212598Y1247243D03*
Y1243503D03*
X1227558Y1224803D03*
Y1228543D03*
X1235039D03*
X1238779D03*
X1231298Y1232283D03*
Y1236023D03*
X1238779Y1239763D03*
X1235039D03*
X1238779Y1247243D03*
X1235039D03*
X1231298Y1250984D03*
Y1254724D03*
X1227558Y1247243D03*
Y1243503D03*
X1238779Y1198621D03*
X1235039D03*
X1231298Y1202362D03*
X1235039Y1206102D03*
X1238779D03*
Y1213582D03*
X1235039D03*
X1238779Y1221062D03*
X1235039D03*
X1231298Y1217322D03*
Y1209842D03*
X1591141Y1108858D03*
X1617322Y1101376D03*
X1636023Y1101377D03*
X1639763Y1101376D03*
X1609842Y1108858D03*
X1628543D03*
X1606102Y1221062D03*
X1628543Y1101377D03*
X1630413Y1166830D03*
X1634153Y1189271D03*
X1637893D03*
X1641633Y1178051D03*
X1634153Y1174310D03*
X1641633Y1185531D03*
X1630413Y1181791D03*
X1634153D03*
X1637893D03*
X1641633Y1189271D03*
X1630413D03*
X1641633Y1174310D03*
Y1181791D03*
X1637893Y1174310D03*
X1630413D03*
Y1196751D03*
X1634153D03*
X1637893D03*
X1634153Y1193011D03*
X1637893D03*
X1630413D03*
Y1200491D03*
X1637893D03*
X1634153D03*
X1641633Y1118208D03*
X1637893Y1121948D03*
X1634153D03*
X1630413D03*
X1641633D03*
X1637893Y1118208D03*
Y1114468D03*
X1634153D03*
X1630413D03*
X1641633D03*
X1634153Y1118208D03*
X1630413D03*
X1641633Y1136909D03*
X1630413Y1133169D03*
X1634153D03*
X1637893D03*
X1641633D03*
X1634153Y1140649D03*
X1637893D03*
X1641633Y1125688D03*
Y1129429D03*
X1630413Y1125688D03*
X1634153D03*
X1637893D03*
X1641633Y1140649D03*
X1630413D03*
Y1136909D03*
X1637893D03*
X1634153D03*
X1630413Y1129429D03*
X1637893D03*
X1634153D03*
X1630413Y1148129D03*
X1634153D03*
X1637893D03*
X1641633Y1144389D03*
Y1148129D03*
Y1151869D03*
X1634153Y1155610D03*
X1641633D03*
X1637893D03*
X1630413D03*
X1634153Y1166830D03*
X1630413Y1159350D03*
Y1170570D03*
X1622933Y1174310D03*
X1615452D03*
Y1196751D03*
X1619193D03*
X1622933D03*
X1626673D03*
X1622933Y1193011D03*
X1626673D03*
X1615452D03*
X1619193D03*
X1622933Y1200491D03*
X1619193D03*
X1615452D03*
X1626673D03*
Y1121948D03*
X1622933D03*
X1619193D03*
X1615452D03*
Y1118208D03*
X1619193D03*
X1615452Y1114468D03*
X1619193D03*
X1622933D03*
X1626673D03*
Y1118208D03*
X1622933D03*
X1615452Y1133169D03*
X1619193D03*
X1622933D03*
X1626673D03*
X1615452Y1140649D03*
X1619193D03*
X1622933D03*
X1626673D03*
X1615452Y1125688D03*
X1619193D03*
X1622933D03*
X1626673D03*
Y1136909D03*
X1622933D03*
X1615452D03*
X1619193D03*
X1626673Y1129429D03*
X1622933D03*
X1619193D03*
X1615452D03*
Y1148129D03*
X1619193D03*
X1622933D03*
X1626673D03*
X1619193Y1155610D03*
X1626673D03*
X1622933D03*
X1615452D03*
Y1170570D03*
X1622933D03*
X1626673Y1166830D03*
X1615452Y1159350D03*
X1619193Y1166830D03*
X1622933Y1159350D03*
X1615452Y1166830D03*
X1619193Y1170570D03*
X1626673Y1159350D03*
X1619193D03*
X1622933Y1166830D03*
X1626673Y1170570D03*
X1615452Y1181791D03*
X1619193D03*
X1622933D03*
X1626673D03*
X1615452Y1189271D03*
X1619193D03*
X1622933D03*
X1626673D03*
Y1174310D03*
X1619193D03*
X1607972Y1125688D03*
X1611712D03*
X1600492Y1136909D03*
X1596752D03*
X1611712D03*
X1607972D03*
X1611712Y1129429D03*
X1607972D03*
X1600492D03*
X1596752D03*
X1600492Y1148129D03*
X1596752D03*
X1607972D03*
X1611712D03*
X1600492Y1155610D03*
X1611712D03*
X1596752D03*
X1607972D03*
X1596752Y1170570D03*
Y1159350D03*
X1611712Y1166830D03*
X1607972Y1170570D03*
X1600492Y1166830D03*
X1607972Y1159350D03*
Y1166830D03*
X1611712Y1170570D03*
X1600492D03*
X1596752Y1166830D03*
X1611712Y1159350D03*
X1600492D03*
Y1181791D03*
X1611712D03*
X1607972D03*
Y1189271D03*
X1611712D03*
X1596752Y1181791D03*
X1600492Y1189271D03*
X1596752D03*
X1600492Y1174310D03*
X1611712D03*
X1607972D03*
X1596752D03*
X1607972Y1204232D03*
Y1196751D03*
X1611712D03*
X1600492D03*
X1596752D03*
Y1204232D03*
X1600492D03*
X1607972Y1193011D03*
X1611712D03*
X1600492D03*
X1596752D03*
X1600492Y1200491D03*
X1596752D03*
X1611712D03*
X1607972D03*
X1596752Y1207972D03*
X1607972D03*
X1600492D03*
Y1211712D03*
Y1215452D03*
X1596752Y1211712D03*
X1607972D03*
X1596752Y1121948D03*
X1600492Y1118208D03*
Y1114468D03*
X1611712Y1121948D03*
X1607972D03*
X1596752Y1118208D03*
X1600492Y1121948D03*
X1596752Y1114468D03*
X1607972D03*
X1611712Y1118208D03*
X1607972D03*
X1611712Y1114468D03*
X1607972Y1133464D03*
X1611712Y1133169D03*
X1600590Y1132677D03*
X1596752Y1133169D03*
Y1140649D03*
X1600492D03*
Y1125688D03*
X1596752D03*
X1607972Y1140649D03*
X1611712D03*
X1593011Y1207972D03*
X1589271D03*
X1585531D03*
X1593012Y1211712D03*
X1581791Y1215452D03*
X1585531D03*
Y1211712D03*
X1581791Y1121948D03*
X1585531Y1118208D03*
X1589271D03*
X1593011D03*
X1589271Y1121948D03*
X1593011D03*
X1585531D03*
X1593012Y1114468D03*
X1581791D03*
Y1133169D03*
Y1140649D03*
X1585531D03*
X1589271D03*
X1593011D03*
X1589271Y1125688D03*
X1585531D03*
X1581791D03*
X1593011D03*
Y1133169D03*
X1589271D03*
X1585531D03*
X1593011Y1136909D03*
X1589271D03*
X1585531D03*
X1581791D03*
X1589271Y1129429D03*
X1585531D03*
X1581791D03*
X1593011D03*
Y1148129D03*
X1589271D03*
X1585531D03*
X1581791D03*
X1593011Y1155610D03*
X1585531D03*
X1581791D03*
X1589271D03*
Y1170570D03*
X1593012Y1166830D03*
X1585531D03*
X1581791Y1159350D03*
X1589271D03*
X1581791Y1170570D03*
X1593011D03*
X1585531D03*
X1589271Y1166830D03*
X1581791D03*
X1585531Y1159350D03*
X1593011D03*
Y1181791D03*
X1589271D03*
X1585531D03*
X1581791D03*
X1593011Y1189271D03*
X1589271D03*
X1585531D03*
X1581791D03*
X1585531Y1174310D03*
X1593011D03*
X1589271D03*
X1581791D03*
X1593011Y1204232D03*
Y1196751D03*
X1589271D03*
X1585531D03*
X1581791D03*
Y1204232D03*
X1585531D03*
X1589271D03*
X1585531Y1193011D03*
X1589271D03*
X1593011D03*
X1581791D03*
X1589271Y1200491D03*
X1585531D03*
X1581791D03*
X1593011D03*
X1589271Y1211712D03*
X1581791Y1207972D03*
Y1211712D03*
Y1118208D03*
X1574311Y1204232D03*
X1578051D03*
X1570571Y1193011D03*
X1574311D03*
X1578051D03*
X1570571Y1200491D03*
X1578051D03*
X1574311D03*
X1566830Y1207972D03*
X1617322Y1108858D03*
X1566830Y1211712D03*
X1578051Y1207972D03*
X1574311D03*
X1570571D03*
X1578051Y1215452D03*
X1566830D03*
X1570571Y1211712D03*
X1574311Y1215452D03*
X1570571D03*
X1578051Y1211712D03*
X1574311D03*
X1566830Y1121948D03*
X1578051Y1118208D03*
X1574311D03*
Y1121948D03*
X1578051D03*
X1574311Y1114468D03*
X1570571D03*
X1578051D03*
X1566830D03*
Y1133169D03*
Y1129429D03*
X1570571Y1140649D03*
X1574311D03*
X1578051D03*
X1570571Y1125688D03*
X1574311D03*
X1578051D03*
X1566830D03*
X1578051Y1133169D03*
X1574311D03*
X1570571D03*
X1566830Y1136909D03*
X1578051D03*
X1574311D03*
X1570571D03*
X1574311Y1129429D03*
X1570571D03*
X1578051D03*
X1566830Y1140649D03*
X1574311Y1148129D03*
X1570571D03*
X1578051D03*
X1570571Y1155610D03*
X1566830Y1151869D03*
X1578051Y1155610D03*
X1566830Y1144389D03*
X1574311Y1155610D03*
X1566830Y1148129D03*
Y1155610D03*
Y1159350D03*
X1578051Y1166830D03*
X1574311Y1159350D03*
X1570571Y1166830D03*
X1566830Y1170570D03*
X1574311D03*
X1578051D03*
X1574311Y1166830D03*
X1570571Y1170570D03*
X1566830Y1166830D03*
X1578051Y1159350D03*
X1570571D03*
X1578051Y1181791D03*
X1574311D03*
X1570571D03*
X1578051Y1189271D03*
X1574311D03*
X1570571D03*
Y1174310D03*
X1578051D03*
X1574311D03*
X1566830D03*
X1578051Y1196751D03*
X1574311D03*
X1570571D03*
X1566830Y1200491D03*
Y1204232D03*
X1570571D03*
Y1118208D03*
X1566830D03*
X1570571Y1121948D03*
X1555610Y1204232D03*
X1559350D03*
X1563090D03*
X1555610Y1211712D03*
X1559350D03*
X1563090D03*
Y1207972D03*
X1559350D03*
X1555610D03*
X1563090Y1215452D03*
X1559350D03*
Y1114468D03*
X1555610D03*
X1563090D03*
Y1125688D03*
X1559350D03*
X1555610D03*
X1551870D03*
X1548130D03*
X1559350Y1129429D03*
X1555610D03*
X1551870D03*
X1548130D03*
X1559350Y1133169D03*
X1555610D03*
X1551870D03*
X1548130D03*
X1563090Y1136909D03*
Y1133169D03*
Y1129429D03*
Y1155610D03*
Y1151869D03*
Y1166830D03*
Y1159350D03*
Y1170570D03*
X1559350Y1166830D03*
X1551870Y1114468D03*
X1548130D03*
X1563090Y1118208D03*
X1559350D03*
X1555610D03*
X1551870D03*
X1548130D03*
X1563090Y1121948D03*
X1559350D03*
X1555610D03*
X1551870D03*
X1548130D03*
X1544389Y1118208D03*
X1540649D03*
Y1121948D03*
X1536909Y1118208D03*
X1533169D03*
Y1121948D03*
X1544389Y1114468D03*
X1536909Y1110728D03*
X1533169D03*
X1540649Y1114468D03*
X1544389Y1129428D03*
X1540649D03*
X1533169Y1073326D03*
X1540649D03*
X1536909D03*
X1540649Y1088287D03*
X1533169Y1077066D03*
X1536909Y1080807D03*
Y1084547D03*
Y1088287D03*
X1533169D03*
Y1092027D03*
X1540649Y1077066D03*
Y1092027D03*
X1533169Y1080807D03*
Y1084547D03*
X1540649Y1080807D03*
X1536909Y1077066D03*
X1540649Y1084547D03*
X1536909Y1092027D03*
X1533169Y1095767D03*
X1536909Y1099507D03*
Y1103247D03*
X1540649Y1106988D03*
X1536909D03*
X1533169D03*
X1540649Y1095767D03*
Y1099507D03*
X1536909Y1095767D03*
X1533169Y1099507D03*
X1540649Y1103247D03*
X1533169D03*
X1544389Y1110728D03*
X1540649D03*
X1536909Y1114468D03*
X1533169D03*
X1521949Y1103247D03*
X1518208Y1099507D03*
X1525689D03*
X1529429Y1095767D03*
X1525689Y1103247D03*
X1518208Y1106988D03*
X1521949Y1095767D03*
X1529429Y1110728D03*
X1518208D03*
X1529429Y1114468D03*
X1525689D03*
X1529429Y1118208D03*
X1521949Y1110728D03*
X1525689D03*
Y1073326D03*
X1521949D03*
X1529429D03*
X1521948Y1077066D03*
X1525689D03*
X1518208D03*
Y1080806D03*
X1529429Y1080807D03*
X1521949D03*
X1529429Y1084547D03*
X1521949D03*
X1518208D03*
X1529429Y1088287D03*
X1525689D03*
X1521949D03*
X1525689Y1092027D03*
X1518208D03*
X1529429Y1077066D03*
X1525689Y1084547D03*
X1529429Y1092027D03*
X1521949D03*
X1518208Y1088287D03*
X1525689Y1080807D03*
X1518208Y1103247D03*
X1529429Y1106988D03*
X1525689D03*
X1521949D03*
X1525689Y1095767D03*
X1518208D03*
X1529429Y1099507D03*
X1521949D03*
X1529429Y1103247D03*
X1514468Y1084547D03*
Y1092027D03*
Y1088287D03*
Y1095767D03*
Y1103247D03*
Y1099507D03*
Y1106988D03*
Y1110728D03*
X1621063Y1101377D03*
X1632283Y1101376D03*
X1624803D03*
X1602362Y1108858D03*
X1598622D03*
X1546258Y1071455D03*
X1561220Y1108858D03*
X1594882D03*
X1606102D03*
X1624803Y1105117D03*
X1621063D03*
X1628543D03*
X1550000D03*
X1564960D03*
X1561220D03*
X1557480D03*
X1553740D03*
X1572441D03*
X1579921D03*
X1576181D03*
X1583661D03*
X1568700D03*
X1594881D03*
X1587401D03*
X1591141D03*
X1598622D03*
X1609842D03*
X1606102D03*
X1613582D03*
X1602362D03*
X1587401Y1221062D03*
X1550000D03*
X1553740D03*
X1557480D03*
X1516338Y1206102D03*
Y1202362D03*
Y1213582D03*
Y1209842D03*
Y1217322D03*
X1535039Y1202362D03*
X1531299Y1206102D03*
X1535039D03*
X1531299Y1202362D03*
X1523819D03*
X1527559D03*
X1523819Y1206102D03*
X1527559D03*
X1520078D03*
Y1202362D03*
X1535039Y1217322D03*
X1531299D03*
X1535039Y1209842D03*
Y1213582D03*
X1531299Y1209842D03*
Y1213582D03*
X1527559Y1209842D03*
X1523819D03*
Y1217322D03*
X1527559D03*
Y1213582D03*
X1523819D03*
X1520078D03*
Y1209842D03*
Y1217322D03*
X1538779Y1202362D03*
Y1206102D03*
Y1217322D03*
Y1209842D03*
Y1213582D03*
X1542519Y1206102D03*
X1546259D03*
X1542519Y1202362D03*
X1546259D03*
X1542519Y1209842D03*
X1546259D03*
X1632283Y1108858D03*
X1516338Y1221062D03*
Y1228543D03*
Y1232283D03*
Y1236023D03*
Y1224803D03*
Y1243503D03*
Y1250984D03*
X1531299Y1221062D03*
X1535039D03*
X1523819D03*
X1527559Y1224803D03*
X1520078Y1221062D03*
X1527559D03*
X1516338Y1239763D03*
X1587401Y1108858D03*
X1632283Y1105117D03*
X1617322D03*
X1639763D03*
X1636023D03*
X1572441Y1221062D03*
X1576181D03*
X1579921D03*
X1583661D03*
X1561220Y1086417D03*
Y1090157D03*
Y1082677D03*
X1564960Y1090157D03*
Y1078936D03*
X1557480Y1086417D03*
Y1082677D03*
Y1078936D03*
Y1090157D03*
X1553740Y1082677D03*
Y1086417D03*
Y1078936D03*
Y1090157D03*
X1561220Y1093897D03*
Y1097637D03*
X1564960Y1101376D03*
Y1093897D03*
Y1097637D03*
X1561220Y1101377D03*
X1557480Y1101376D03*
Y1097637D03*
Y1093897D03*
X1553740Y1097637D03*
Y1093897D03*
Y1101377D03*
X1583661Y1075196D03*
X1576181D03*
X1572441D03*
X1579921D03*
X1568700D03*
X1583661Y1078936D03*
X1579921Y1086417D03*
Y1082677D03*
X1576181Y1078936D03*
X1572441Y1086417D03*
Y1082677D03*
Y1090157D03*
Y1078936D03*
X1576181Y1082677D03*
Y1086417D03*
Y1090157D03*
X1579921D03*
X1583661D03*
Y1086417D03*
Y1082677D03*
X1579921Y1078936D03*
X1568700D03*
Y1082677D03*
Y1086417D03*
Y1090157D03*
X1583661Y1093897D03*
Y1097637D03*
X1576181Y1093897D03*
Y1097637D03*
X1572441Y1101376D03*
X1579921D03*
Y1093897D03*
X1572441D03*
X1579921Y1097637D03*
X1572441D03*
X1576181Y1101377D03*
X1583661D03*
X1568700Y1097637D03*
Y1093897D03*
Y1101377D03*
X1591141Y1075196D03*
X1587401D03*
X1594882D03*
Y1086417D03*
Y1082677D03*
X1591141Y1078936D03*
X1587401Y1082677D03*
Y1086417D03*
Y1090157D03*
Y1078936D03*
X1591141Y1082677D03*
Y1086417D03*
Y1090157D03*
X1594882D03*
Y1078936D03*
X1598622Y1097637D03*
Y1093897D03*
X1591141Y1097637D03*
Y1093897D03*
X1594881Y1101376D03*
X1587401D03*
Y1097637D03*
Y1093897D03*
X1594882D03*
Y1097637D03*
X1591141Y1101377D03*
X1598622D03*
X1609842Y1101376D03*
X1606102Y1101377D03*
X1613582D03*
X1602362Y1101376D03*
Y1093897D03*
Y1097637D03*
X1546259Y1082677D03*
Y1086417D03*
Y1078936D03*
X1550000Y1086417D03*
Y1082677D03*
Y1078936D03*
X1546259Y1090157D03*
X1550000D03*
X1546259Y1093897D03*
X1550000Y1101376D03*
Y1093897D03*
Y1097637D03*
X1561220Y1075196D03*
X1564960D03*
X1557480D03*
X1553740D03*
X1561220Y1078936D03*
X1564960Y1082677D03*
Y1086417D03*
X1546259Y1075196D03*
X1550000D03*
X1527559Y1228543D03*
X1535039Y1224803D03*
Y1228543D03*
X1523819Y1232283D03*
Y1236023D03*
X1531299D03*
Y1232283D03*
X1527559Y1236023D03*
Y1232283D03*
X1523819Y1228543D03*
Y1224803D03*
X1531299D03*
Y1228543D03*
X1535039Y1232283D03*
Y1236023D03*
X1520078Y1228543D03*
Y1236023D03*
Y1232283D03*
Y1224803D03*
X1535039Y1243503D03*
Y1247243D03*
X1531299Y1250984D03*
Y1254724D03*
X1523819D03*
Y1250984D03*
X1527559Y1247243D03*
Y1243503D03*
Y1250984D03*
Y1254724D03*
X1523819Y1247243D03*
X1531299D03*
X1535039Y1250984D03*
Y1254724D03*
X1523819Y1239763D03*
Y1243503D03*
X1527559Y1239763D03*
X1535039D03*
X1531299D03*
Y1243503D03*
X1520078Y1247243D03*
Y1239763D03*
Y1250984D03*
Y1254724D03*
Y1243503D03*
X1546259Y1217322D03*
Y1221062D03*
X1538779D03*
X1542519D03*
Y1217322D03*
Y1213582D03*
X1546259D03*
X1538779Y1232283D03*
Y1236023D03*
X1542519Y1224803D03*
Y1228543D03*
X1546259Y1232283D03*
Y1236023D03*
X1542519Y1232283D03*
Y1236023D03*
X1538779Y1228543D03*
Y1224803D03*
X1546259D03*
Y1228543D03*
Y1250984D03*
Y1254724D03*
X1538779D03*
Y1250984D03*
X1542519Y1247243D03*
Y1243503D03*
X1538779Y1247243D03*
X1542519Y1254724D03*
X1538779Y1239763D03*
Y1243503D03*
X1542519Y1250984D03*
Y1239763D03*
X1546259D03*
Y1243503D03*
Y1247243D03*
X1550000Y1224803D03*
Y1228543D03*
Y1232283D03*
Y1236023D03*
Y1243503D03*
Y1247243D03*
Y1250984D03*
Y1254724D03*
Y1239763D03*
X1557480Y1224803D03*
Y1228543D03*
X1564960D03*
Y1224803D03*
X1561220D03*
Y1228543D03*
X1553740Y1232283D03*
Y1236023D03*
Y1228543D03*
Y1224803D03*
X1572441D03*
Y1228543D03*
X1579921D03*
Y1224803D03*
X1583661D03*
Y1228543D03*
X1576181Y1224803D03*
Y1228543D03*
X1568700D03*
Y1224803D03*
X1587401D03*
Y1228543D03*
X1594882D03*
Y1224803D03*
X1598622Y1228543D03*
Y1224803D03*
X1591141Y1228543D03*
Y1224803D03*
X1606102Y1228543D03*
Y1224803D03*
X1602362D03*
Y1228543D03*
Y1232283D03*
Y1221062D03*
X1516338Y1247243D03*
X1538779Y1258465D03*
X1561219Y1071455D03*
X1591140D03*
X1583660D03*
X1512597Y1206103D03*
Y1213583D03*
Y1221063D03*
X1512596Y1239762D03*
X1568699Y1071455D03*
X1512596Y1247242D03*
X1576180Y1071455D03*
X1523819Y1258465D03*
X1531299D03*
X1546260D03*
X1512597Y1228542D03*
X1553739Y1071455D03*
X1576181Y1108858D03*
X1550000Y1206102D03*
Y1202362D03*
X1624803Y1108858D03*
X1621063D03*
X1568700D03*
X1636023D03*
X1639763D03*
X1550000Y1217322D03*
Y1209842D03*
X1557480Y1108858D03*
X1572441D03*
X1564960D03*
X1550000Y1213582D03*
X1579921Y1108858D03*
X1583661D03*
X1613582D03*
X1662204Y1135039D03*
X1697736Y1140649D03*
X1693996D03*
X1697736Y1148129D03*
X1693996D03*
X1697736Y1155610D03*
X1693996D03*
Y1151870D03*
X1697736D03*
X1693996Y1144389D03*
X1697736D03*
X1693996Y1166830D03*
X1697736D03*
Y1159350D03*
X1693996D03*
X1690256Y1140649D03*
X1679035D03*
X1686515D03*
X1682775D03*
X1690256Y1144389D03*
X1682775D03*
X1679035Y1148129D03*
X1682775Y1151869D03*
X1679035Y1155610D03*
X1686515Y1144389D03*
X1690256Y1155610D03*
X1686515Y1151869D03*
X1690256D03*
Y1148129D03*
X1679035Y1151869D03*
Y1144389D03*
X1682775Y1148129D03*
X1686515Y1155610D03*
Y1148129D03*
X1682775Y1155610D03*
Y1166830D03*
X1686515Y1159350D03*
X1690256D03*
X1682775D03*
X1679035D03*
X1686515Y1166830D03*
X1690256D03*
X1679035D03*
X1675295Y1140649D03*
X1671555D03*
X1667815Y1151869D03*
X1664074D03*
X1675295Y1155610D03*
Y1148129D03*
X1671555Y1155610D03*
Y1151869D03*
Y1148129D03*
Y1144389D03*
X1664074D03*
X1667815D03*
Y1155610D03*
X1664075Y1148129D03*
Y1155610D03*
X1675295Y1144389D03*
Y1151869D03*
X1664074Y1159350D03*
X1667815D03*
X1671555D03*
X1667815Y1166830D03*
X1664074D03*
X1671555D03*
X1675295D03*
Y1159350D03*
X1649114Y1133169D03*
Y1140649D03*
X1652854Y1136909D03*
X1649114Y1125688D03*
X1656594Y1133169D03*
Y1140649D03*
Y1136909D03*
X1652854Y1148129D03*
X1649114Y1144389D03*
X1652854Y1155610D03*
X1649114Y1148129D03*
X1652854Y1151869D03*
X1656594D03*
X1660334D03*
Y1155610D03*
Y1144389D03*
X1649114Y1151870D03*
Y1155610D03*
X1656594D03*
X1660334Y1148129D03*
X1652854Y1144389D03*
X1656594Y1148129D03*
Y1144389D03*
X1652854Y1159350D03*
X1660334Y1166830D03*
Y1159350D03*
X1652854Y1166830D03*
X1649114Y1159350D03*
Y1166830D03*
X1656594D03*
Y1159350D03*
X1649114Y1118208D03*
Y1121948D03*
X1652854Y1114468D03*
X1649114D03*
X1656594D03*
X1649114Y1129429D03*
Y1136909D03*
X1652854Y1140649D03*
X1662204Y1120078D03*
Y1116338D03*
Y1131299D03*
Y1123818D03*
Y1127558D03*
X1669685Y1116338D03*
Y1123818D03*
Y1112598D03*
Y1120078D03*
X1665944Y1116338D03*
Y1123818D03*
Y1112598D03*
Y1120078D03*
X1669685Y1131299D03*
Y1127558D03*
X1665944Y1131299D03*
X1665945Y1127558D03*
Y1135039D03*
G54D58*
X922313Y842143D03*
X919163D03*
X916014D03*
X912864Y848442D03*
Y845293D03*
Y842143D03*
X909714Y845293D03*
Y842143D03*
Y848442D03*
X906565Y851592D03*
Y848442D03*
Y842143D03*
X919163Y838994D03*
Y835844D03*
X916014Y845293D03*
X928612Y835844D03*
X906565Y845293D03*
Y838994D03*
X909714D03*
Y851592D03*
X912864D03*
G54D51*
X165649Y1159350D03*
Y1151870D03*
X1079822D03*
Y1159350D03*
G54D40*
X743337Y374862D03*
G54D53*
X473662Y1622402D03*
X456339D03*
X490985D03*
X534292Y1585788D03*
X525630Y1591693D03*
X534292Y1580670D03*
X508307Y1622402D03*
X525630Y1576339D03*
Y1581457D03*
X534292Y1601142D03*
X525630Y1607048D03*
Y1612166D03*
X534292Y1611378D03*
Y1616496D03*
X525630Y1622402D03*
Y1596811D03*
X534292Y1596024D03*
Y1570434D03*
X283110Y1622402D03*
X317756D03*
X300433D03*
X335078D03*
X361063Y1585788D03*
X352401Y1591693D03*
Y1596811D03*
Y1607048D03*
Y1612166D03*
Y1622402D03*
X361063Y1580670D03*
X187835Y1452717D03*
Y1493662D03*
Y1498780D03*
Y1580670D03*
Y1585788D03*
X707520Y1462953D03*
Y1468071D03*
Y1478308D03*
Y1483426D03*
Y1493662D03*
Y1498780D03*
Y1509016D03*
Y1514134D03*
Y1565315D03*
Y1570434D03*
Y1580670D03*
Y1585788D03*
Y1596024D03*
Y1601142D03*
X698858Y1607048D03*
Y1612166D03*
X707520Y1611378D03*
Y1616496D03*
X698858Y1622402D03*
X681535D03*
X664213D03*
X646890D03*
X629567D03*
X1729488Y1493662D03*
Y1498780D03*
Y1509016D03*
Y1452717D03*
Y1462953D03*
Y1468071D03*
Y1478308D03*
Y1483426D03*
Y1514134D03*
Y1565315D03*
Y1570434D03*
Y1580670D03*
Y1585788D03*
Y1596024D03*
Y1601142D03*
X1720826Y1607048D03*
Y1612166D03*
X1729488Y1611378D03*
Y1616496D03*
X1720826Y1622402D03*
X1703503D03*
X1686181D03*
X1668858D03*
X1651535D03*
X1209803Y1452717D03*
Y1462953D03*
Y1468071D03*
Y1478308D03*
Y1483426D03*
Y1493662D03*
Y1498780D03*
Y1509016D03*
Y1514134D03*
Y1565315D03*
Y1570434D03*
Y1580670D03*
Y1585788D03*
Y1596024D03*
Y1601142D03*
Y1611378D03*
Y1616496D03*
X1201141Y1622402D03*
X1556260Y1570434D03*
X1547598Y1576339D03*
Y1581457D03*
X1556260Y1580670D03*
Y1585788D03*
X1547598Y1591693D03*
Y1596811D03*
X1556260Y1596024D03*
Y1601142D03*
X1547598Y1607048D03*
Y1612166D03*
X1556260Y1611378D03*
Y1616496D03*
X1547598Y1622402D03*
X1530275D03*
X1512953D03*
X1495630D03*
X1478307D03*
X1383032Y1580670D03*
Y1585788D03*
X1374370Y1591693D03*
Y1596811D03*
X1383032Y1596024D03*
Y1601142D03*
X1374370Y1607048D03*
Y1612166D03*
X1383032Y1611378D03*
Y1616496D03*
X1374370Y1622402D03*
X1357047D03*
X1339725D03*
X1322402D03*
X1305079D03*
G54D57*
X515504Y701351D03*
G54D41*
X1729390Y144095D03*
X1627028D03*
X1169941D03*
X1067579D03*
X965217D03*
X815217D03*
G54D42*
X1657510Y374862D03*
X1200423D03*
X286250D03*
G54D49*
X68743Y1583498D03*
G54D46*
X153405Y144095D03*
X160295Y66811D03*
X255767Y144095D03*
X262657Y66811D03*
X358129Y144095D03*
X365019Y66811D03*
X508130Y144095D03*
X515020Y66811D03*
X610492Y144095D03*
X617382Y66811D03*
X712854Y144095D03*
X719744Y66811D03*
X822106D03*
X972106D03*
X1074468D03*
X1176830D03*
X1272302Y144095D03*
X1279192Y66811D03*
X1422303Y144095D03*
X1429193Y66811D03*
X1524665Y144095D03*
X1531555Y66811D03*
X1633917D03*
X1736279D03*
X51043Y144095D03*
G54D43*
X1561585Y374862D03*
X1104498D03*
X190325D03*
G54D37*
X1817323Y56693D03*
G54D38*
X937000Y313983D03*
X917882Y326517D03*
X130750Y134215D03*
Y120042D03*
X138290Y413987D03*
X148692Y406874D03*
X140690Y399813D03*
X148692Y392701D03*
X138050Y127128D03*
Y112955D03*
X233112Y134215D03*
X240412Y127128D03*
Y112955D03*
X233112Y120042D03*
X335474Y134215D03*
X342774Y127128D03*
Y112955D03*
X335474Y120042D03*
X533092Y127096D03*
X543494Y134209D03*
Y120035D03*
X635454Y127096D03*
X645856Y134209D03*
Y120035D03*
X748218Y134209D03*
X737816Y127096D03*
X748218Y120035D03*
X778080Y469006D03*
X840178Y127096D03*
X850580Y134209D03*
Y120035D03*
X899352Y310261D03*
X990178Y127096D03*
Y112923D03*
X1000580Y134209D03*
Y120035D03*
X1092540Y112923D03*
Y127096D03*
X1102942Y134209D03*
Y120035D03*
X1205304Y134209D03*
X1194902Y127096D03*
X1205304Y120035D03*
X1194902Y112923D03*
X1297264Y127096D03*
Y112923D03*
X1307666Y134209D03*
Y120035D03*
X1399648Y134215D03*
Y120042D03*
X1406948Y127128D03*
Y112955D03*
X1509310Y127128D03*
X1502010Y134215D03*
X1509310Y112955D03*
X1502010Y120042D03*
X1509550Y413987D03*
X1511950Y399813D03*
X1519952Y406874D03*
Y392701D03*
X1604372Y134215D03*
X1611672Y127128D03*
X1604372Y120042D03*
X1611672Y112955D03*
X1706734Y134215D03*
Y120042D03*
X1714034Y127128D03*
Y112955D03*
X788482Y476118D03*
X778080Y483179D03*
X788482Y490291D03*
X1754906Y822634D03*
X35688Y112955D03*
X28388Y120042D03*
G54D52*
X213969Y1460153D03*
Y1449153D03*
X227249Y1460153D03*
Y1449153D03*
G54D59*
X1817323Y1567323D03*
G54D39*
X940997Y333613D03*
X178367Y127096D03*
X188769Y134209D03*
Y120035D03*
X280729Y127096D03*
X291131Y134209D03*
Y120035D03*
X393493Y134209D03*
X383091Y127096D03*
X393493Y120035D03*
X485475Y134215D03*
Y120042D03*
X492775Y127128D03*
Y112955D03*
X587837Y134215D03*
Y120042D03*
X595377Y413987D03*
X597777Y399813D03*
X595137Y127128D03*
Y112955D03*
X605779Y392701D03*
Y406874D03*
X690199Y120042D03*
X697499Y112955D03*
X690199Y134215D03*
X697499Y127128D03*
X792561Y134215D03*
X799861Y127128D03*
X792561Y120042D03*
X799861Y112955D03*
X942561Y134215D03*
Y120042D03*
X949861Y127128D03*
Y112955D03*
X1044923Y134215D03*
X1052223Y127128D03*
X1044923Y120042D03*
X1052223Y112955D03*
X1052463Y413987D03*
X1054863Y399813D03*
X1062865Y406874D03*
Y392701D03*
X1147285Y134215D03*
Y120042D03*
X1154585Y112955D03*
Y127128D03*
X1249647Y120042D03*
X1256947Y112955D03*
X1249647Y134215D03*
X1256947Y127128D03*
X1366535Y353200D03*
Y337452D03*
X1363535Y345326D03*
Y329578D03*
X1447265Y127096D03*
Y112923D03*
X1457667Y134209D03*
Y120035D03*
X1549627Y127096D03*
X1560029Y134209D03*
X1549627Y112923D03*
X1560029Y120035D03*
X1651989Y127096D03*
Y112923D03*
X1662391Y134209D03*
Y120035D03*
X1666271Y461919D03*
X1692253Y469006D03*
X1754351Y127096D03*
Y112923D03*
X1764753Y120035D03*
Y134209D03*
X1702655Y476118D03*
X1692253Y483179D03*
X1702655Y490291D03*
X76005Y127096D03*
X86407Y134209D03*
Y120035D03*
X217907Y1428752D03*
X415203Y1497818D03*
X397267Y1516347D03*
G54D45*
X820079Y388583D03*
X1020866D03*
G54D44*
X1809883Y120792D03*
X184851Y334492D03*
X26789Y1373669D03*
G54D47*
X792973Y81595D03*
X28819Y81575D03*
X942973Y81595D03*
X1250060D03*
X690611D03*
X233543Y81575D03*
X1502441D03*
X1147697Y81595D03*
X1045335D03*
X588248Y81594D03*
X131181Y81575D03*
X335906D03*
X1604784Y81595D03*
X1400060D03*
X1707146D03*
X485886D03*
G54D56*
X573818Y1263386D03*
X1267125D03*
X1487991D03*
G54D54*
X352952D03*
%LPD*%
G75*
G36*
G01X69340Y1583498D02*
G03I-597J0D01*
G37*
G36*
G01X176468Y115401D02*
G03I-597J0D01*
G37*
G36*
G01Y110445D02*
G03I-597J0D01*
G37*
G36*
G01X181460Y115401D02*
G03I-597J0D01*
G37*
G36*
G01Y110445D02*
G03I-597J0D01*
G37*
G36*
G01X186870Y117557D02*
G03I-597J0D01*
G37*
G36*
G01X191862D02*
G03I-597J0D01*
G37*
G36*
G01X186870Y122513D02*
G03I-597J0D01*
G37*
G36*
G01X191862D02*
G03I-597J0D01*
G37*
G36*
G01X223832Y1506770D02*
G03I-597J0D01*
G37*
G36*
G01X223505Y1502028D02*
G03I-597J0D01*
G37*
G36*
G01X278830Y115401D02*
G03I-597J0D01*
G37*
G36*
G01Y110445D02*
G03I-597J0D01*
G37*
G36*
G01Y124618D02*
G03I-597J0D01*
G37*
G36*
G01Y129574D02*
G03I-597J0D01*
G37*
G36*
G01X283822Y115401D02*
G03I-597J0D01*
G37*
G36*
G01Y110445D02*
G03I-597J0D01*
G37*
G36*
G01X289232Y117557D02*
G03I-597J0D01*
G37*
G36*
G01X294224Y122513D02*
G03I-597J0D01*
G37*
G36*
G01X283822Y124618D02*
G03I-597J0D01*
G37*
G36*
G01Y129574D02*
G03I-597J0D01*
G37*
G36*
G01X289232Y131731D02*
G03I-597J0D01*
G37*
G36*
G01X294224D02*
G03I-597J0D01*
G37*
G36*
G01X289232Y122513D02*
G03I-597J0D01*
G37*
G36*
G01X294224Y117557D02*
G03I-597J0D01*
G37*
G36*
G01Y136687D02*
G03I-597J0D01*
G37*
G36*
G01X289232D02*
G03I-597J0D01*
G37*
G36*
G01X386184Y110445D02*
G03I-597J0D01*
G37*
G36*
G01Y115401D02*
G03I-597J0D01*
G37*
G36*
G01X381192Y110445D02*
G03I-597J0D01*
G37*
G36*
G01Y115401D02*
G03I-597J0D01*
G37*
G36*
G01X391594Y117557D02*
G03I-597J0D01*
G37*
G36*
G01Y122513D02*
G03I-597J0D01*
G37*
G36*
G01X386184Y124618D02*
G03I-597J0D01*
G37*
G36*
G01Y129574D02*
G03I-597J0D01*
G37*
G36*
G01X381192Y124618D02*
G03I-597J0D01*
G37*
G36*
G01Y129574D02*
G03I-597J0D01*
G37*
G36*
G01X391594Y131731D02*
G03I-597J0D01*
G37*
G36*
G01Y136687D02*
G03I-597J0D01*
G37*
G36*
G01X396586Y122513D02*
G03I-597J0D01*
G37*
G36*
G01Y117557D02*
G03I-597J0D01*
G37*
G36*
G01Y131731D02*
G03I-597J0D01*
G37*
G36*
G01Y136687D02*
G03I-597J0D01*
G37*
G36*
G01X521488Y704864D02*
X527509D01*
G02X527651Y704805I0J-200D01*
G01X527942Y704514D01*
G02X528001Y704372I-141J-142D01*
G01Y694482D01*
G02X527942Y694340I-200J0D01*
G01X527574Y693972D01*
G02X527432Y693913I-142J141D01*
G01X517562D01*
G02X517420Y693972I0J200D01*
G01X517067Y694325D01*
G02X517008Y694467I141J142D01*
G01Y695264D01*
X517017Y695292D01*
G03Y696222I-1532J465D01*
G01X517008Y696250D01*
Y700800D01*
X517019Y700831D01*
G03X517106Y701351I-1515J521D01*
G03X517019Y701871I-1602J-1D01*
G01X517008Y701902D01*
Y703474D01*
G02X517067Y703616I200J0D01*
G01X518256Y704805D01*
G02X518398Y704864I142J-141D01*
G01X520780D01*
X520800Y704860D01*
G03X521134Y704824I338J1566D01*
G03X521468Y704860I-4J1602D01*
G01X521488Y704864D01*
G37*
G36*
G01X536185Y110445D02*
G03I-597J0D01*
G37*
G36*
G01Y115401D02*
G03I-597J0D01*
G37*
G36*
G01X531193Y110445D02*
G03I-597J0D01*
G37*
G36*
G01Y115401D02*
G03I-597J0D01*
G37*
G36*
G01Y129574D02*
G03I-597J0D01*
G37*
G36*
G01Y124618D02*
G03I-597J0D01*
G37*
G36*
G01X536185Y129574D02*
G03I-597J0D01*
G37*
G36*
G01Y124618D02*
G03I-597J0D01*
G37*
G36*
G01X546587Y117557D02*
G03I-597J0D01*
G37*
G36*
G01X541595D02*
G03I-597J0D01*
G37*
G36*
G01X546587Y122513D02*
G03I-597J0D01*
G37*
G36*
G01Y131731D02*
G03I-597J0D01*
G37*
G36*
G01X541595Y122513D02*
G03I-597J0D01*
G37*
G36*
G01Y131731D02*
G03I-597J0D01*
G37*
G36*
G01X546587Y136687D02*
G03I-597J0D01*
G37*
G36*
G01X541595D02*
G03I-597J0D01*
G37*
G36*
G01X637147Y1198800D02*
X648817D01*
G02X648959Y1198741I0J-200D01*
G01X649070Y1198630D01*
G02X649116Y1198420I-142J-141D01*
G01X648970Y1198024D01*
X648878Y1197954D01*
X648819Y1197949D01*
G03X647715Y1196751I98J-1198D01*
G03X648917Y1195549I1202J0D01*
G03X649505Y1195702I1J1202D01*
G01X649551Y1195729D01*
X649657Y1195728D01*
X650001Y1195526D01*
G02X650100Y1195353I-101J-173D01*
G01Y1194409D01*
G02X650001Y1194236I-200J0D01*
G01X649657Y1194034D01*
X649551Y1194033D01*
X649505Y1194060D01*
G03X648917Y1194213I-587J-1049D01*
G03Y1191809I0J-1202D01*
G03X649505Y1191962I1J1202D01*
G01X649551Y1191989D01*
X649657Y1191988D01*
X650001Y1191786D01*
G02X650100Y1191613I-101J-173D01*
G01Y1186929D01*
G02X650001Y1186756I-200J0D01*
G01X649657Y1186554D01*
X649551Y1186553D01*
X649505Y1186580D01*
G03X648917Y1186733I-587J-1049D01*
G03Y1184329I0J-1202D01*
G03X649505Y1184482I1J1202D01*
G01X649551Y1184509D01*
X649657Y1184508D01*
X650001Y1184306D01*
G02X650100Y1184133I-101J-173D01*
G01Y1183189D01*
G02X650001Y1183016I-200J0D01*
G01X649657Y1182814D01*
X649551Y1182813D01*
X649505Y1182840D01*
G03X648917Y1182993I-587J-1049D01*
G03Y1180589I0J-1202D01*
G03X649505Y1180742I1J1202D01*
G01X649551Y1180769D01*
X649657Y1180768D01*
X650001Y1180566D01*
G02X650100Y1180393I-101J-173D01*
G01Y1179449D01*
G02X650001Y1179276I-200J0D01*
G01X649657Y1179074D01*
X649551Y1179073D01*
X649505Y1179100D01*
G03X648917Y1179253I-587J-1049D01*
G03Y1176849I0J-1202D01*
G03X649505Y1177002I1J1202D01*
G01X649551Y1177029D01*
X649657Y1177028D01*
X650001Y1176826D01*
G02X650100Y1176653I-101J-173D01*
G01Y1176383D01*
G02X650041Y1176241I-200J0D01*
G01X649459Y1175659D01*
G02X649317Y1175600I-142J141D01*
G01X643483D01*
G02X643341Y1175659I0J200D01*
G01X643280Y1175720D01*
X643249Y1175805D01*
X643254Y1175850D01*
G03X643260Y1175972I-1195J120D01*
G01Y1180143D01*
G03X642951Y1180947I-1201J0D01*
G02X642900Y1181081I149J133D01*
G01Y1182501D01*
G02X642951Y1182635I200J1D01*
G03X643260Y1183439I-892J804D01*
G01Y1183930D01*
G03X643025Y1184644I-1201J0D01*
G03X642928Y1184760I-968J-711D01*
G01X642614Y1185074D01*
X642587Y1185176D01*
X642600Y1185228D01*
G03X642639Y1185531I-1163J304D01*
G03X641437Y1186733I-1202J0D01*
G03X640253Y1185738I0J-1202D01*
G01X640240Y1185666D01*
X640129Y1185572D01*
X639005D01*
X638894Y1185666D01*
X638881Y1185738D01*
G03X637697Y1186733I-1184J-207D01*
G03X637475Y1186712I2J-1202D01*
G01X637426Y1186703D01*
X637333Y1186732D01*
X637028Y1187037D01*
X636999Y1187130D01*
X637008Y1187179D01*
G03X637029Y1187401I-1181J224D01*
G03X637008Y1187623I-1202J-2D01*
G01X636999Y1187672D01*
X637028Y1187765D01*
X637333Y1188070D01*
X637426Y1188099D01*
X637475Y1188090D01*
G03X637697Y1188069I224J1181D01*
G03Y1190473I0J1202D01*
G03X637475Y1190452I2J-1202D01*
G01X637426Y1190443D01*
X637333Y1190472D01*
X637028Y1190777D01*
X636999Y1190870D01*
X637008Y1190919D01*
G03X637029Y1191141I-1181J224D01*
G03X637008Y1191363I-1202J-2D01*
G01X636999Y1191412D01*
X637028Y1191505D01*
X637333Y1191810D01*
X637426Y1191839D01*
X637475Y1191830D01*
G03X637697Y1191809I224J1181D01*
G03Y1194213I0J1202D01*
G03X637475Y1194192I2J-1202D01*
G01X637426Y1194183D01*
X637333Y1194212D01*
X637028Y1194517D01*
X636999Y1194610D01*
X637008Y1194659D01*
G03X637029Y1194881I-1181J224D01*
G03X635827Y1193679I-1202J0D01*
G03X636049Y1193700I-2J1202D01*
G01X636098Y1193709D01*
X636191Y1193680D01*
X636496Y1193375D01*
X636525Y1193282D01*
X636516Y1193233D01*
G03X636495Y1193011I1181J-224D01*
G03X636516Y1192789I1202J2D01*
G01X636525Y1192740D01*
X636496Y1192647D01*
X636191Y1192342D01*
X636098Y1192313D01*
X636049Y1192322D01*
G03X635827Y1192343I-224J-1181D01*
G03Y1189939I0J-1202D01*
G03X636049Y1189960I-2J1202D01*
G01X636098Y1189969D01*
X636191Y1189940D01*
X636496Y1189635D01*
X636525Y1189542D01*
X636516Y1189493D01*
G03X636495Y1189271I1181J-224D01*
G03X636516Y1189049I1202J2D01*
G01X636525Y1189000D01*
X636496Y1188907D01*
X636191Y1188602D01*
X636098Y1188573D01*
X636049Y1188582D01*
G03X635827Y1188603I-224J-1181D01*
G03X634625Y1187401I0J-1202D01*
G03X634646Y1187179I1202J2D01*
G01X634655Y1187130D01*
X634626Y1187037D01*
X634321Y1186732D01*
X634228Y1186703D01*
X634179Y1186712D01*
G03X633957Y1186733I-224J-1181D01*
G03X633734Y1186712I1J-1202D01*
G01X633686Y1186703D01*
X633591Y1186732D01*
X633287Y1187036D01*
X633258Y1187130D01*
X633267Y1187179D01*
G03X633288Y1187401I-1181J224D01*
G03X632086Y1186199I-1202J0D01*
G03X632309Y1186220I-1J1202D01*
G01X632357Y1186229D01*
X632452Y1186200D01*
X632756Y1185896D01*
X632785Y1185802D01*
X632776Y1185753D01*
G03X632773Y1185738I1177J-243D01*
G01X632760Y1185666D01*
X632649Y1185572D01*
X581787D01*
G03X581646Y1185513I1J-200D01*
G01X580174Y1184041D01*
G03X580115Y1183900I141J-142D01*
G01Y1176393D01*
G03X580174Y1176252I200J1D01*
G01X581535Y1174891D01*
X581537Y1174889D01*
G03X581551Y1174874I885J812D01*
G01X581705Y1174721D01*
G03X581709Y1174717I851J847D01*
G01X581711Y1174715D01*
X581979Y1174447D01*
G03X582105Y1174388I143J141D01*
G01X582141Y1174386D01*
X582204Y1174357D01*
X582250Y1174312D01*
G02X582252Y1174310I-140J-142D01*
G03X582394Y1174251I142J141D01*
G01X586847D01*
G02X586989Y1174192I0J-200D01*
G01X588234Y1172947D01*
G02X588293Y1172805I-141J-142D01*
G01Y1167128D01*
G02X588234Y1166986I-200J0D01*
G01X587407Y1166159D01*
G02X587265Y1166100I-142J141D01*
G01X583211D01*
G02X583070Y1166158I0J200D01*
G03X580954I-1058J-1066D01*
G02X580813Y1166100I-141J142D01*
G01X570755D01*
G02X570683Y1166113I-1J200D01*
G01X570586Y1166151D01*
X570557Y1166178D01*
G03X570457Y1166265I-1035J-1089D01*
G03X570371Y1166329I-939J-1172D01*
G03X570202Y1166429I-848J-1240D01*
G01X570174Y1166444D01*
X569347Y1167271D01*
X569346Y1167272D01*
G03X569329Y1167289I-858J-841D01*
G01X569328Y1167290D01*
X569281Y1167337D01*
X569186Y1167433D01*
G02X569128Y1167574I142J141D01*
G01Y1175790D01*
G02X569187Y1175932I200J0D01*
G01X569254Y1175999D01*
X569384Y1176130D01*
G02X569483Y1176184I141J-141D01*
G01X569505Y1176189D01*
G03X569526Y1179193I15J1502D01*
G02X569483Y1179198I1J200D01*
G02X569384Y1179252I42J195D01*
G01X569254Y1179383D01*
X569187Y1179450D01*
G02X569128Y1179592I141J142D01*
G01Y1190845D01*
G02X569187Y1190987I200J0D01*
G01X576941Y1198741D01*
G02X577083Y1198800I142J-141D01*
G01X597105D01*
X597221Y1198686D01*
X597222Y1198603D01*
G03X599626I1202J19D01*
G01X599627Y1198686D01*
X599743Y1198800D01*
X600845D01*
X600962Y1198685D01*
X600963Y1198603D01*
G03X603367I1202J18D01*
G01X603368Y1198685D01*
X603485Y1198800D01*
X604585D01*
X604702Y1198685D01*
X604703Y1198603D01*
G03X607107I1202J18D01*
G01X607108Y1198685D01*
X607225Y1198800D01*
X608326D01*
X608443Y1198685D01*
X608444Y1198603D01*
G03X610848I1202J18D01*
G01X610849Y1198685D01*
X610966Y1198800D01*
X612066D01*
X612183Y1198685D01*
X612184Y1198603D01*
G03X614588I1202J18D01*
G01X614589Y1198685D01*
X614706Y1198800D01*
X615806D01*
X615923Y1198685D01*
X615924Y1198603D01*
G03X618328I1202J18D01*
G01X618329Y1198685D01*
X618446Y1198800D01*
X619546D01*
X619663Y1198685D01*
X619664Y1198603D01*
G03X622068I1202J18D01*
G01X622069Y1198685D01*
X622186Y1198800D01*
X623286D01*
X623403Y1198685D01*
X623404Y1198603D01*
G03X625808I1202J18D01*
G01X625809Y1198685D01*
X625926Y1198800D01*
X627026D01*
X627143Y1198685D01*
X627144Y1198603D01*
G03X629548I1202J18D01*
G01X629549Y1198685D01*
X629666Y1198800D01*
X630766D01*
X630883Y1198685D01*
X630884Y1198603D01*
G03X633288I1202J18D01*
G01X633289Y1198685D01*
X633406Y1198800D01*
X634507D01*
X634624Y1198685D01*
X634625Y1198603D01*
G03X637029I1202J18D01*
G01X637030Y1198685D01*
X637147Y1198800D01*
G37*
G36*
G01X569946Y1541947D02*
G03I-597J0D01*
G37*
G36*
G01X561232Y1543531D02*
G03I-597J0D01*
G37*
G36*
G01X644093Y1149508D02*
X646373D01*
G02X646515Y1149449I0J-200D01*
G01X646866Y1149098D01*
G02X646925Y1148956I-141J-142D01*
G01Y1141220D01*
G02X646866Y1141078I-200J0D01*
G01X646750Y1140962D01*
G02X646467I-141J141D01*
G01X646450Y1140979D01*
X646425Y1141019D01*
X646418Y1141043D01*
G03X645177Y1141951I-1241J-394D01*
G03X643875Y1140649I0J-1302D01*
G03X644561Y1139502I1302J0D01*
G01X644603Y1139479D01*
X644657Y1139402D01*
X644711Y1139037D01*
G02X644655Y1138867I-198J-29D01*
G01X644174Y1138386D01*
G02X644032Y1138327I-142J141D01*
G01X628392D01*
G03X628250Y1138268I0J-200D01*
G01X627885Y1137903D01*
G02X627749Y1137844I-142J141D01*
G01X627438Y1137834D01*
X627366Y1137860D01*
X627337Y1137885D01*
G03X626476Y1138211I-862J-976D01*
G03X625174Y1136909I0J-1302D01*
G03X625500Y1136048I1302J1D01*
G01X625525Y1136019D01*
X625551Y1135947D01*
X625541Y1135636D01*
G02X625482Y1135500I-200J6D01*
G01X620405Y1130423D01*
G02X620269Y1130364I-142J141D01*
G01X619958Y1130354D01*
X619886Y1130380D01*
X619857Y1130405D01*
G03X618996Y1130731I-862J-976D01*
G03X617694Y1129429I0J-1302D01*
G03X618020Y1128568I1302J1D01*
G01X618045Y1128539D01*
X618071Y1128467D01*
X618061Y1128156D01*
G02X618002Y1128020I-200J6D01*
G01X616664Y1126682D01*
G02X616529Y1126624I-141J142D01*
G01X616217Y1126614D01*
X616145Y1126640D01*
X616117Y1126665D01*
G03X615256Y1126990I-861J-978D01*
G03X613954Y1125688I0J-1302D01*
G03X614279Y1124827I1303J0D01*
G01X614304Y1124799D01*
X614330Y1124727D01*
X614320Y1124415D01*
G02X614262Y1124280I-200J6D01*
G01X612924Y1122942D01*
G02X612789Y1122884I-141J142D01*
G01X612477Y1122874D01*
X612405Y1122900D01*
X612377Y1122925D01*
G03X611516Y1123250I-861J-978D01*
G03X610214Y1121948I0J-1302D01*
G03X610539Y1121087I1303J0D01*
G01X610564Y1121059D01*
X610590Y1120987D01*
X610580Y1120675D01*
G02X610522Y1120540I-200J6D01*
G01X609184Y1119202D01*
G02X609049Y1119144I-141J142D01*
G01X608737Y1119134D01*
X608665Y1119160D01*
X608637Y1119185D01*
G03X607776Y1119510I-861J-978D01*
G03X606474Y1118208I0J-1302D01*
G03X606799Y1117347I1303J0D01*
G01X606824Y1117319D01*
X606850Y1117247D01*
X606840Y1116935D01*
G02X606782Y1116800I-200J6D01*
G01X605654Y1115672D01*
G02X605512Y1115613I-142J141D01*
G01X604680D01*
X604636Y1115623D01*
X604615Y1115634D01*
G03X604035Y1115770I-579J-1166D01*
G03X603455Y1115634I-1J-1302D01*
G01X603434Y1115623D01*
X603390Y1115613D01*
X600940D01*
X600896Y1115623D01*
X600875Y1115634D01*
G03X600295Y1115770I-579J-1166D01*
G03X599715Y1115634I-1J-1302D01*
G01X599694Y1115623D01*
X599650Y1115613D01*
X583292D01*
G02X583141Y1115681I-1J200D01*
G03X581641Y1116146I-1129J-989D01*
G01X580813Y1116974D01*
Y1124705D01*
X581901Y1125793D01*
G03X583442Y1126831I111J1498D01*
G01X583462Y1126894D01*
X583567Y1126970D01*
X598839D01*
G02X599014Y1126868I1J-200D01*
G01X599212Y1126517D01*
X599210Y1126410D01*
X599181Y1126363D01*
G03X598993Y1125688I1114J-674D01*
G03X601597I1302J0D01*
G03X600916Y1126832I-1301J0D01*
G01X600873Y1126855D01*
X600820Y1126932D01*
X600767Y1127297D01*
G02X600824Y1127467I198J28D01*
G01X601198Y1127841D01*
G02X601339Y1127900I142J-141D01*
G01X601362D01*
G03X601503Y1127958I0J200D01*
G01X602327Y1128782D01*
G02X602489Y1128839I141J-142D01*
G01X602843Y1128802D01*
X602920Y1128755D01*
X602945Y1128717D01*
G03X604035Y1128127I1090J712D01*
G03X605337Y1129429I0J1302D01*
G03X604747Y1130519I-1302J0D01*
G01X604709Y1130544D01*
X604662Y1130621D01*
X604625Y1130975D01*
G02X604682Y1131137I199J21D01*
G01X606068Y1132522D01*
G02X606230Y1132580I142J-141D01*
G01X606584Y1132543D01*
X606661Y1132496D01*
X606685Y1132458D01*
G03X607776Y1131867I1091J712D01*
G03X609078Y1133169I0J1302D01*
G03X608487Y1134260I-1303J0D01*
G01X608449Y1134284D01*
X608402Y1134361D01*
X608365Y1134715D01*
G02X608423Y1134877I199J20D01*
G01X609808Y1136262D01*
G02X609970Y1136320I142J-141D01*
G01X610324Y1136283D01*
X610401Y1136236D01*
X610425Y1136198D01*
G03X611516Y1135607I1091J712D01*
G03X612818Y1136909I0J1302D01*
G03X612227Y1138000I-1303J0D01*
G01X612189Y1138024D01*
X612142Y1138101D01*
X612105Y1138455D01*
G02X612163Y1138617I199J20D01*
G01X613548Y1140002D01*
G02X613710Y1140060I142J-141D01*
G01X614064Y1140023D01*
X614141Y1139976D01*
X614165Y1139938D01*
G03X615256Y1139347I1091J712D01*
G03X616558Y1140649I0J1302D01*
G03X615967Y1141740I-1303J0D01*
G01X615929Y1141764D01*
X615882Y1141841D01*
X615845Y1142195D01*
G02X615903Y1142357I199J20D01*
G01X617288Y1143742D01*
G02X617450Y1143800I142J-141D01*
G01X617804Y1143763D01*
X617881Y1143716D01*
X617905Y1143678D01*
G03X618996Y1143087I1091J712D01*
G03X620298Y1144389I0J1302D01*
G03X619707Y1145480I-1303J0D01*
G01X619669Y1145504D01*
X619622Y1145581D01*
X619585Y1145935D01*
G02X619643Y1146097I199J20D01*
G01X621028Y1147482D01*
G02X621190Y1147540I142J-141D01*
G01X621544Y1147503D01*
X621621Y1147456D01*
X621645Y1147418D01*
G03X622736Y1146827I1091J712D01*
G03X623955Y1147673I0J1301D01*
G01X623977Y1147731D01*
X624080Y1147802D01*
X625132D01*
X625235Y1147731D01*
X625257Y1147673D01*
G03X627695I1219J455D01*
G01X627717Y1147731D01*
X627820Y1147802D01*
X628872D01*
X628975Y1147731D01*
X628997Y1147673D01*
G03X631435I1219J455D01*
G01X631457Y1147731D01*
X631560Y1147802D01*
X632613D01*
X632716Y1147731D01*
X632738Y1147673D01*
G03X635176I1219J455D01*
G01X635198Y1147731D01*
X635301Y1147802D01*
X636353D01*
X636456Y1147731D01*
X636478Y1147673D01*
G03X638916I1219J455D01*
G01X638938Y1147731D01*
X639041Y1147802D01*
X640093D01*
X640196Y1147731D01*
X640218Y1147673D01*
G03X641437Y1146827I1219J455D01*
G03X642739Y1148129I0J1302D01*
G01Y1148150D01*
X642738Y1148191D01*
X642769Y1148266D01*
X643952Y1149449D01*
G02X644093Y1149508I142J-141D01*
G37*
G36*
G01X639117Y1155790D02*
X640017D01*
X640134Y1155675D01*
X640135Y1155592D01*
G03X641437Y1154308I1302J18D01*
G03X642439Y1154779I0J1301D01*
G01X642466Y1154811D01*
X642541Y1154849D01*
X642879Y1154865D01*
G02X643030Y1154806I9J-200D01*
G01X643060Y1154776D01*
G02X643119Y1154634I-141J-142D01*
G01Y1150116D01*
G02X643060Y1149974I-200J0D01*
G01X642358Y1149272D01*
G02X642112Y1149242I-142J141D01*
G03X641437Y1149431I-676J-1113D01*
G03X640379Y1148887I0J-1301D01*
G02X640216Y1148804I-162J117D01*
G01X638918D01*
G02X638755Y1148887I-1J200D01*
G03X636639I-1058J-757D01*
G02X636476Y1148804I-162J117D01*
G01X635178D01*
G02X635015Y1148887I-1J200D01*
G03X632899I-1058J-757D01*
G02X632736Y1148804I-162J117D01*
G01X631437D01*
G02X631274Y1148887I-1J200D01*
G03X629158I-1058J-757D01*
G02X628995Y1148804I-162J117D01*
G01X627697D01*
G02X627534Y1148887I-1J200D01*
G03X625418I-1058J-757D01*
G02X625255Y1148804I-162J117D01*
G01X623957D01*
G02X623794Y1148887I-1J200D01*
G03X621678I-1058J-757D01*
G02X621515Y1148804I-162J117D01*
G01X621016D01*
G03X620874Y1148745I0J-200D01*
G01X620779Y1148650D01*
G02X620608Y1148594I-141J142D01*
G01X620244Y1148648D01*
X620166Y1148702D01*
X620144Y1148744D01*
G03X618996Y1149431I-1148J-616D01*
G03X617694Y1148129I0J-1302D01*
G03X618381Y1146981I1303J0D01*
G01X618423Y1146959D01*
X618477Y1146881D01*
X618531Y1146517D01*
G02X618475Y1146346I-198J-30D01*
G01X613299Y1141170D01*
G02X613128Y1141114I-141J142D01*
G01X612764Y1141168D01*
X612686Y1141222D01*
X612664Y1141264D01*
G03X611516Y1141951I-1148J-616D01*
G03X610214Y1140649I0J-1302D01*
G03X610901Y1139501I1303J0D01*
G01X610943Y1139479D01*
X610997Y1139401D01*
X611051Y1139037D01*
G02X610995Y1138866I-198J-30D01*
G01X609559Y1137430D01*
G02X609388Y1137374I-141J142D01*
G01X609024Y1137428D01*
X608946Y1137482D01*
X608924Y1137524D01*
G03X607776Y1138211I-1148J-616D01*
G03X606474Y1136909I0J-1302D01*
G03X607161Y1135761I1303J0D01*
G01X607203Y1135739D01*
X607257Y1135661D01*
X607311Y1135297D01*
G02X607255Y1135126I-198J-30D01*
G01X605818Y1133689D01*
G02X605648Y1133633I-141J142D01*
G01X605283Y1133687D01*
X605205Y1133741D01*
X605183Y1133783D01*
G03X604035Y1134471I-1148J-614D01*
G03X602733Y1133169I0J-1302D01*
G03X603421Y1132021I1302J0D01*
G01X603463Y1131999D01*
X603517Y1131921D01*
X603571Y1131556D01*
G02X603515Y1131386I-198J-29D01*
G01X602078Y1129949D01*
G02X601908Y1129893I-141J142D01*
G01X601543Y1129947D01*
X601465Y1130001D01*
X601443Y1130043D01*
G03X600295Y1130731I-1148J-614D01*
G03X598993Y1129429I0J-1302D01*
G03X598997Y1129331I1302J4D01*
G01X599000Y1129289D01*
X598973Y1129211D01*
X598744Y1128965D01*
G02X598598Y1128901I-147J136D01*
G01X592581D01*
G02X592407Y1129003I0J200D01*
G01X592209Y1129355D01*
X592211Y1129462D01*
X592239Y1129509D01*
G03X592459Y1130291I-1282J783D01*
G03X589455I-1502J0D01*
G03X589675Y1129509I1502J1D01*
G01X589703Y1129462D01*
X589705Y1129355D01*
X589507Y1129003D01*
G02X589333Y1128901I-174J98D01*
G01X581008D01*
X580674Y1129235D01*
Y1135723D01*
Y1136950D01*
X581477Y1137753D01*
X597822D01*
X599550Y1139481D01*
X599674Y1139503D01*
X599733Y1139475D01*
G03X600295Y1139347I563J1174D01*
G03X601597Y1140649I0J1302D01*
G03X601469Y1141211I-1302J-1D01*
G01X601441Y1141270D01*
X601463Y1141394D01*
X603290Y1143221D01*
X603414Y1143243D01*
X603473Y1143215D01*
G03X604035Y1143087I563J1174D01*
G03X605337Y1144389I0J1302D01*
G03X605209Y1144951I-1302J-1D01*
G01X605181Y1145010D01*
X605203Y1145134D01*
X607030Y1146961D01*
X607156Y1146983D01*
X607213Y1146955D01*
G03X607776Y1146827I563J1174D01*
G03X609078Y1148129I0J1302D01*
G03X608950Y1148692I-1302J0D01*
G01X608922Y1148749D01*
X608944Y1148875D01*
X610770Y1150701D01*
X610896Y1150723D01*
X610953Y1150695D01*
G03X611516Y1150567I563J1174D01*
G03X612818Y1151869I0J1302D01*
G03X612690Y1152432I-1302J0D01*
G01X612662Y1152489D01*
X612684Y1152615D01*
X614511Y1154442D01*
X614635Y1154464D01*
X614694Y1154436D01*
G03X615256Y1154308I563J1174D01*
G03X616558Y1155592I0J1302D01*
G01X616559Y1155675D01*
X616676Y1155790D01*
X617576D01*
X617693Y1155675D01*
X617694Y1155592D01*
G03X620298I1302J18D01*
G01X620299Y1155675D01*
X620416Y1155790D01*
X621316D01*
X621433Y1155675D01*
X621434Y1155592D01*
G03X624038I1302J18D01*
G01X624039Y1155675D01*
X624156Y1155790D01*
X624857D01*
X624973Y1155675D01*
X624974Y1155592D01*
G03X627978I1502J18D01*
G01X627979Y1155675D01*
X628095Y1155790D01*
X628796D01*
X628913Y1155675D01*
X628914Y1155592D01*
G03X631518I1302J18D01*
G01X631519Y1155675D01*
X631636Y1155790D01*
X636277D01*
X636394Y1155675D01*
X636395Y1155592D01*
G03X638999I1302J18D01*
G01X639000Y1155675D01*
X639117Y1155790D01*
G37*
G36*
G01X639858Y1164911D02*
X641709D01*
G02X641851Y1164852I0J-200D01*
G01X642790Y1163913D01*
G02X642849Y1163771I-141J-142D01*
G01Y1157461D01*
G02X642790Y1157319I-200J0D01*
G01X642272Y1156801D01*
G02X642039Y1156765I-141J141D01*
G01X642038D01*
G03X641437Y1156912I-601J-1155D01*
G01X641436D01*
G03X640735Y1156707I0J-1302D01*
G01X640676Y1156669D01*
X640537Y1156683D01*
X640457Y1156762D01*
X640385Y1156792D01*
X640354D01*
X638789D01*
X638749D01*
X638677Y1156762D01*
X638597Y1156683D01*
X638458Y1156669D01*
X638399Y1156707D01*
G03X637698Y1156912I-701J-1097D01*
G01X637696D01*
G03X636995Y1156707I0J-1302D01*
G01X636936Y1156669D01*
X636797Y1156683D01*
X636717Y1156762D01*
X636645Y1156792D01*
X636614D01*
X631308D01*
X631268D01*
X631196Y1156762D01*
X631116Y1156683D01*
X630977Y1156669D01*
X630918Y1156707D01*
G03X630217Y1156912I-701J-1097D01*
G01X630215D01*
G03X629514Y1156707I0J-1302D01*
G01X629455Y1156669D01*
X629316Y1156683D01*
X629236Y1156762D01*
X629164Y1156792D01*
X629133D01*
X627500D01*
G02X627439Y1156801I-2J200D01*
G01X627354Y1156829D01*
X627329Y1156846D01*
G03X626476Y1157112I-853J-1236D01*
G03X625623Y1156846I0J-1502D01*
G01X625598Y1156829D01*
X625513Y1156801D01*
G02X625452Y1156792I-59J191D01*
G01X623828D01*
X623788D01*
X623716Y1156762D01*
X623636Y1156683D01*
X623497Y1156669D01*
X623438Y1156707D01*
G03X622737Y1156912I-701J-1097D01*
G01X622735D01*
G03X622034Y1156707I0J-1302D01*
G01X621975Y1156669D01*
X621836Y1156683D01*
X621756Y1156762D01*
X621684Y1156792D01*
X621653D01*
X620088D01*
X620048D01*
X619976Y1156762D01*
X619896Y1156683D01*
X619757Y1156669D01*
X619698Y1156707D01*
G03X618997Y1156912I-701J-1097D01*
G01X618995D01*
G03X618294Y1156707I0J-1302D01*
G01X618235Y1156669D01*
X618096Y1156683D01*
X618016Y1156762D01*
X617944Y1156792D01*
X617913D01*
X616348D01*
X616308D01*
X616236Y1156762D01*
X616156Y1156683D01*
X616017Y1156669D01*
X615958Y1156707D01*
G03X615257Y1156912I-701J-1097D01*
G01X615256D01*
G03X614156Y1156307I0J-1303D01*
G02X614128Y1156272I-169J107D01*
G01X613476Y1155620D01*
X613436Y1155580D01*
X613328Y1155553D01*
X612882Y1155694D01*
X612809Y1155777D01*
X612799Y1155833D01*
G03X611516Y1156912I-1283J-223D01*
G03X610214Y1155610I0J-1302D01*
G03X611293Y1154327I1302J0D01*
G01X611349Y1154317D01*
X611432Y1154244D01*
X611556Y1153852D01*
G02X611506Y1153650I-191J-60D01*
G01X610858Y1153002D01*
G02X610841Y1152987I-141J142D01*
G01X610816Y1152967D01*
X610808Y1152962D01*
G03X610423Y1152577I708J-1093D01*
G01X610418Y1152569D01*
X610398Y1152544D01*
G02X610383Y1152527I-157J124D01*
G01X609736Y1151880D01*
X609696Y1151840D01*
X609588Y1151813D01*
X609142Y1151954D01*
X609069Y1152037D01*
X609059Y1152093D01*
G03X607776Y1153172I-1283J-223D01*
G03X606474Y1151870I0J-1302D01*
G03X607553Y1150587I1302J0D01*
G01X607609Y1150577D01*
X607692Y1150504D01*
X607816Y1150112D01*
G02X607766Y1149910I-191J-60D01*
G01X607118Y1149262D01*
G02X607101Y1149247I-141J142D01*
G01X607076Y1149227D01*
X607068Y1149222D01*
G03X606683Y1148837I708J-1093D01*
G01X606678Y1148829D01*
X606658Y1148804D01*
G02X606643Y1148787I-157J124D01*
G01X605995Y1148139D01*
X605955Y1148099D01*
X605847Y1148072D01*
X605401Y1148213D01*
X605328Y1148296D01*
X605318Y1148352D01*
G03X604035Y1149431I-1283J-223D01*
G03X602733Y1148129I0J-1302D01*
G03X603812Y1146846I1302J0D01*
G01X603868Y1146836D01*
X603951Y1146763D01*
X604075Y1146371D01*
G02X604025Y1146169I-191J-60D01*
G01X603357Y1145501D01*
X603338Y1145489D01*
G03X602935Y1145086I697J-1100D01*
G01X602923Y1145067D01*
X602255Y1144399D01*
X602215Y1144359D01*
X602107Y1144332D01*
X601661Y1144473D01*
X601588Y1144556D01*
X601578Y1144612D01*
G03X600295Y1145691I-1283J-223D01*
G03X598993Y1144389I0J-1302D01*
G03X600072Y1143106I1302J0D01*
G01X600128Y1143096D01*
X600211Y1143023D01*
X600335Y1142631D01*
G02X600285Y1142429I-191J-60D01*
G01X599617Y1141761D01*
X599598Y1141749D01*
G03X599200Y1141354I697J-1100D01*
G01X599195Y1141346D01*
X599175Y1141321D01*
G02X599160Y1141304I-157J124D01*
G01X596669Y1138813D01*
G02X596528Y1138754I-142J141D01*
G01X583766D01*
G02X583599Y1138844I0J200D01*
G01X583415Y1139121D01*
G02X583397Y1139309I166J111D01*
G01Y1139310D01*
G03X583514Y1139887I-1385J581D01*
G01Y1139909D01*
G03X582012Y1141393I-1502J-18D01*
G03X580830Y1140818I0J-1502D01*
G01X580790Y1140767D01*
X580668Y1140731D01*
X580250Y1140875D01*
G02X580115Y1141064I65J189D01*
G01Y1150272D01*
G02X580174Y1150414I200J0D01*
G01X580445Y1150685D01*
G02X580587Y1150744I142J-141D01*
G01X591771D01*
G03X591913Y1150803I0J200D01*
G01X599390Y1158280D01*
X599529Y1158295D01*
X599589Y1158256D01*
G03X600295Y1158048I706J1094D01*
G03X601597Y1159350I0J1302D01*
G03X601389Y1160056I-1302J0D01*
G01X601350Y1160116D01*
X601365Y1160255D01*
X604813Y1163703D01*
G03X604870Y1163816I-141J142D01*
G01X604875Y1163848D01*
X604904Y1163906D01*
X605850Y1164852D01*
G02X605991Y1164910I141J-142D01*
G01X606178D01*
G03X606192Y1164911I-79J1198D01*
G01X609358D01*
G03X609372Y1164910I93J1197D01*
G01X609919D01*
G03X609933Y1164911I-79J1198D01*
G01X613099D01*
G03X613113Y1164910I93J1197D01*
G01X613659D01*
G03X613673Y1164911I-79J1198D01*
G01X616839D01*
G03X616853Y1164910I93J1197D01*
G01X621139D01*
G03X621153Y1164911I-79J1198D01*
G01X624319D01*
G03X624333Y1164910I93J1197D01*
G01X628619D01*
G03X628633Y1164911I-79J1198D01*
G01X631799D01*
G03X631813Y1164910I93J1197D01*
G01X632360D01*
G03X632374Y1164911I-79J1198D01*
G01X635540D01*
G03X635554Y1164910I93J1197D01*
G01X636100D01*
G03X636114Y1164911I-79J1198D01*
G01X639280D01*
G03X639294Y1164910I93J1197D01*
G01X639840D01*
G03X639854Y1164911I-79J1198D01*
G01X639858D01*
G37*
G36*
G01X639116Y1174388D02*
X640018D01*
X640133Y1174282D01*
X640139Y1174204D01*
G03X641437Y1173008I1298J106D01*
G03X642100Y1173190I-1J1302D01*
G01X642147Y1173217D01*
X642254Y1173218D01*
X642603Y1173019D01*
G02X642704Y1172845I-99J-174D01*
G01Y1168295D01*
G02X642603Y1168121I-200J0D01*
G01X642254Y1167922D01*
X642146Y1167923D01*
X642100Y1167950D01*
G03X641437Y1168132I-664J-1120D01*
G03X640135Y1166830I0J-1302D01*
G03X640197Y1166435I1302J2D01*
G01X640212Y1166389D01*
X640197Y1166295D01*
X639977Y1165995D01*
G02X639825Y1165912I-163J117D01*
G01X639319D01*
X639309D01*
G02X639157Y1165995I11J200D01*
G01X638976Y1166243D01*
G02X638937Y1166361I161J119D01*
G01Y1166434D01*
X638945Y1166462D01*
G03X638999Y1166830I-1248J371D01*
G03X636395I-1302J0D01*
G03X636457Y1166435I1302J2D01*
G01X636472Y1166389D01*
X636457Y1166295D01*
X636237Y1165995D01*
G02X636085Y1165912I-163J117D01*
G01X635579D01*
X635569D01*
G02X635417Y1165995I11J200D01*
G01X635236Y1166243D01*
G02X635197Y1166361I161J119D01*
G01Y1166434D01*
X635205Y1166462D01*
G03X635259Y1166830I-1248J371D01*
G03X632655I-1302J0D01*
G03X632717Y1166435I1302J2D01*
G01X632732Y1166389D01*
X632717Y1166295D01*
X632497Y1165995D01*
G02X632345Y1165912I-163J117D01*
G01X631838D01*
X631828D01*
G02X631676Y1165995I11J200D01*
G01X631495Y1166243D01*
G02X631456Y1166361I161J119D01*
G01Y1166434D01*
X631464Y1166462D01*
G03X631518Y1166830I-1248J371D01*
G03X628914I-1302J0D01*
G03X628976Y1166435I1302J2D01*
G01X628991Y1166389D01*
X628976Y1166295D01*
X628756Y1165995D01*
G02X628604Y1165912I-163J117D01*
G01X624358D01*
X624348D01*
G02X624196Y1165995I11J200D01*
G01X624015Y1166243D01*
G02X623976Y1166361I161J119D01*
G01Y1166434D01*
X623984Y1166462D01*
G03X624038Y1166830I-1248J371D01*
G03X621434I-1302J0D01*
G03X621496Y1166435I1302J2D01*
G01X621511Y1166389D01*
X621496Y1166295D01*
X621276Y1165995D01*
G02X621124Y1165912I-163J117D01*
G01X616878D01*
X616868D01*
G02X616716Y1165995I11J200D01*
G01X616535Y1166243D01*
G02X616496Y1166361I161J119D01*
G01Y1166434D01*
X616504Y1166462D01*
G03X616558Y1166830I-1248J371D01*
G03X613954I-1302J0D01*
G03X614016Y1166435I1302J2D01*
G01X614031Y1166389D01*
X614016Y1166295D01*
X613796Y1165995D01*
G02X613644Y1165912I-163J117D01*
G01X613138D01*
X613128D01*
G02X612976Y1165995I11J200D01*
G01X612795Y1166243D01*
G02X612756Y1166361I161J119D01*
G01Y1166434D01*
X612764Y1166462D01*
G03X612818Y1166830I-1248J371D01*
G03X610214I-1302J0D01*
G03X610276Y1166435I1302J2D01*
G01X610291Y1166389D01*
X610276Y1166295D01*
X610056Y1165995D01*
G02X609904Y1165912I-163J117D01*
G01X609397D01*
X609387D01*
G02X609235Y1165995I11J200D01*
G01X609054Y1166243D01*
G02X609015Y1166361I161J119D01*
G01Y1166434D01*
X609023Y1166462D01*
G03X609077Y1166830I-1248J371D01*
G03X606473I-1302J0D01*
G03X606535Y1166435I1302J2D01*
G01X606550Y1166389D01*
X606535Y1166295D01*
X606315Y1165995D01*
G02X606163Y1165912I-163J117D01*
G01X605576D01*
G03X605493Y1165894I0J-200D01*
G01X605440Y1165869D01*
X605326Y1165885D01*
X605229Y1165966D01*
G02X605182Y1166214I129J153D01*
G03X605337Y1166830I-1147J616D01*
G03X602733I-1302J0D01*
G03X603991Y1165529I1302J0D01*
G01X604051Y1165527D01*
X604148Y1165459D01*
X604305Y1165061D01*
G02X604282Y1164872I-186J-73D01*
G01X604271Y1164857D01*
X600062Y1160648D01*
X600015Y1160622D01*
X599988Y1160615D01*
G03X599022Y1159625I307J-1265D01*
G01X599016Y1159596D01*
X598989Y1159546D01*
X591358Y1151916D01*
G02X591216Y1151857I-142J141D01*
G01X583900D01*
G02X583751Y1151924I0J200D01*
G01X583552Y1152148D01*
G02X583503Y1152305I150J133D01*
G03X583514Y1152491I-1491J182D01*
G03X582012Y1153993I-1502J0D01*
G03X581445Y1153882I0J-1502D01*
G01X581398Y1153863D01*
X581300Y1153873D01*
X581044Y1154045D01*
X581027Y1154043D01*
X580961Y1154102D01*
G02X580894Y1154251I133J149D01*
G01Y1162233D01*
G02X580953Y1162375I200J0D01*
G01X581614Y1163036D01*
G02X581756Y1163095I142J-141D01*
G01X587820D01*
G03X587962Y1163154I0J200D01*
G01X589179Y1164371D01*
G03X589238Y1164513I-141J142D01*
G01Y1166492D01*
G02X589253Y1166569I200J1D01*
G01X589280Y1166633D01*
G03X589294Y1166688I-185J76D01*
G01X589300Y1166742D01*
X589361Y1166828D01*
X589745Y1167001D01*
G02X589960Y1166968I82J-183D01*
G03X590957Y1166589I997J1122D01*
G03Y1169593I0J1502D01*
G03X589960Y1169214I0J-1501D01*
G01X589915Y1169175D01*
X589799Y1169157D01*
X589413Y1169331D01*
G02X589295Y1169513I82J182D01*
G01Y1173219D01*
G03X589279Y1173297I-200J0D01*
G01X589253Y1173358D01*
G02X589238Y1173435I185J76D01*
G01Y1173694D01*
G02X589297Y1173836I200J0D01*
G01X589790Y1174329D01*
G02X589792Y1174331I142J-140D01*
G02X589932Y1174388I140J-143D01*
G01X598977D01*
X599091Y1174283D01*
X599097Y1174205D01*
G03X601493I1198J105D01*
G01X601499Y1174283D01*
X601613Y1174388D01*
X602615D01*
X602730Y1174282D01*
X602736Y1174204D01*
G03X605332I1298J106D01*
G01X605338Y1174282D01*
X605453Y1174388D01*
X606356D01*
X606471Y1174282D01*
X606477Y1174204D01*
G03X609073I1298J106D01*
G01X609079Y1174282D01*
X609194Y1174388D01*
X610097D01*
X610212Y1174282D01*
X610218Y1174204D01*
G03X612814I1298J106D01*
G01X612820Y1174282D01*
X612935Y1174388D01*
X613837D01*
X613952Y1174282D01*
X613958Y1174204D01*
G03X616554I1298J106D01*
G01X616560Y1174282D01*
X616675Y1174388D01*
X617577D01*
X617692Y1174282D01*
X617698Y1174204D01*
G03X620294I1298J106D01*
G01X620300Y1174282D01*
X620415Y1174388D01*
X621317D01*
X621432Y1174282D01*
X621438Y1174204D01*
G03X624034I1298J106D01*
G01X624040Y1174282D01*
X624155Y1174388D01*
X625158D01*
X625272Y1174283D01*
X625279Y1174205D01*
G03X627673I1197J105D01*
G01X627680Y1174283D01*
X627794Y1174388D01*
X628797D01*
X628912Y1174282D01*
X628918Y1174204D01*
G03X631514I1298J106D01*
G01X631520Y1174282D01*
X631635Y1174388D01*
X632538D01*
X632653Y1174282D01*
X632659Y1174204D01*
G03X635255I1298J106D01*
G01X635261Y1174282D01*
X635376Y1174388D01*
X636278D01*
X636393Y1174282D01*
X636399Y1174204D01*
G03X638995I1298J106D01*
G01X639001Y1174282D01*
X639116Y1174388D01*
G37*
G36*
G01X638650Y1184570D02*
X640484D01*
G02X640584Y1184543I0J-200D01*
G01X640603Y1184532D01*
X640616Y1184522D01*
G03X641437Y1184229I823J1009D01*
G03X641829Y1184290I-2J1302D01*
G01X641830D01*
G02X642031Y1184241I60J-191D01*
G01X642200Y1184072D01*
G02X642259Y1183930I-141J-142D01*
G01Y1183440D01*
G02X642182Y1183282I-200J0D01*
G01X641932Y1183088D01*
G02X641820Y1183046I-123J158D01*
G01X641787Y1183045D01*
G03X641437Y1183093I-350J-1254D01*
G03Y1180489I0J-1302D01*
G03X641759Y1180530I-2J1302D01*
G02X641819Y1180536I50J-194D01*
G01X641820D01*
G02X641932Y1180494I-11J-200D01*
G01X642182Y1180300D01*
G02X642259Y1180142I-123J-158D01*
G01Y1175974D01*
G02X642200Y1175832I-200J0D01*
G01X641944Y1175576D01*
X641841Y1175549D01*
X641788Y1175564D01*
G03X641438Y1175612I-350J-1254D01*
G01X641436D01*
G03X640777Y1175433I0J-1302D01*
G01X640755Y1175420D01*
X640677Y1175398D01*
G02X640622Y1175390I-56J192D01*
G01X638512D01*
G02X638457Y1175398I1J200D01*
G01X638379Y1175420D01*
X638357Y1175433D01*
G03X637698Y1175612I-659J-1123D01*
G01X637696D01*
G03X637037Y1175433I0J-1302D01*
G01X637015Y1175420D01*
X636937Y1175398D01*
G02X636882Y1175390I-56J192D01*
G01X634772D01*
G02X634717Y1175398I1J200D01*
G01X634639Y1175420D01*
X634617Y1175433D01*
G03X633958Y1175612I-659J-1123D01*
G01X633956D01*
G03X633297Y1175433I0J-1302D01*
G01X633275Y1175420D01*
X633197Y1175398D01*
G02X633142Y1175390I-56J192D01*
G01X631031D01*
G02X630976Y1175398I1J200D01*
G01X630898Y1175420D01*
X630876Y1175433D01*
G03X630217Y1175612I-659J-1123D01*
G01X630215D01*
G03X629556Y1175433I0J-1302D01*
G01X629534Y1175420D01*
X629456Y1175398D01*
G02X629401Y1175390I-56J192D01*
G01X623551D01*
G02X623496Y1175398I1J200D01*
G01X623418Y1175420D01*
X623396Y1175433D01*
G03X622737Y1175612I-659J-1123D01*
G01X622735D01*
G03X622076Y1175433I0J-1302D01*
G01X622054Y1175420D01*
X621976Y1175398D01*
G02X621921Y1175390I-56J192D01*
G01X619811D01*
G02X619756Y1175398I1J200D01*
G01X619678Y1175420D01*
X619656Y1175433D01*
G03X618997Y1175612I-659J-1123D01*
G01X618995D01*
G03X618336Y1175433I0J-1302D01*
G01X618314Y1175420D01*
X618236Y1175398D01*
G02X618181Y1175390I-56J192D01*
G01X616071D01*
G02X616016Y1175398I1J200D01*
G01X615938Y1175420D01*
X615916Y1175433D01*
G03X615257Y1175612I-659J-1123D01*
G01X615255D01*
G03X614596Y1175433I0J-1302D01*
G01X614574Y1175420D01*
X614496Y1175398D01*
G02X614441Y1175390I-56J192D01*
G01X612331D01*
G02X612276Y1175398I1J200D01*
G01X612198Y1175420D01*
X612176Y1175433D01*
G03X611517Y1175612I-659J-1123D01*
G01X611515D01*
G03X610856Y1175433I0J-1302D01*
G01X610834Y1175420D01*
X610756Y1175398D01*
G02X610701Y1175390I-56J192D01*
G01X608590D01*
G02X608535Y1175398I1J200D01*
G01X608457Y1175420D01*
X608435Y1175433D01*
G03X607776Y1175612I-659J-1123D01*
G01X607774D01*
G03X607115Y1175433I0J-1302D01*
G01X607093Y1175420D01*
X607015Y1175398D01*
G02X606960Y1175390I-56J192D01*
G01X604849D01*
G02X604794Y1175398I1J200D01*
G01X604716Y1175420D01*
X604694Y1175433D01*
G03X604035Y1175612I-659J-1123D01*
G01X604033D01*
G03X603374Y1175433I0J-1302D01*
G01X603352Y1175420D01*
X603274Y1175398D01*
G02X603219Y1175390I-56J192D01*
G01X582535D01*
G02X582393Y1175449I0J200D01*
G01X582260Y1175582D01*
G02X582208Y1175773I142J141D01*
G01X582307Y1176158D01*
X582380Y1176234D01*
X582431Y1176249D01*
G03X583514Y1177691I-419J1442D01*
G03X582012Y1179193I-1502J0D01*
G03X581631Y1179144I0J-1502D01*
G01X581619Y1179141D01*
X581594Y1179137D01*
G02X581446Y1179177I-26J198D01*
G01X581195Y1179369D01*
G02X581117Y1179527I122J158D01*
G01Y1183484D01*
G02X581176Y1183626I200J0D01*
G01X582061Y1184511D01*
G02X582203Y1184570I142J-141D01*
G01X599342D01*
G02X599442Y1184543I0J-200D01*
G01X599461Y1184532D01*
X599474Y1184522D01*
G03X600295Y1184229I823J1009D01*
G03X600508Y1184247I-3J1302D01*
G01X600556Y1184255D01*
X600645Y1184227D01*
X600946Y1183940D01*
X600977Y1183852D01*
X600972Y1183805D01*
G03X600963Y1183661I1193J-147D01*
G03X603367I1202J0D01*
G03X603358Y1183805I-1202J-3D01*
G01X603353Y1183852D01*
X603384Y1183940D01*
X603685Y1184227D01*
X603774Y1184255D01*
X603822Y1184247D01*
G03X604035Y1184229I216J1284D01*
G03X604248Y1184247I-3J1302D01*
G01X604296Y1184255D01*
X604385Y1184227D01*
X604686Y1183940D01*
X604717Y1183852D01*
X604712Y1183805D01*
G03X604703Y1183661I1193J-147D01*
G03X607107I1202J0D01*
G03X607098Y1183805I-1202J-3D01*
G01X607093Y1183853D01*
X607124Y1183941D01*
X607425Y1184228D01*
X607514Y1184256D01*
X607561Y1184248D01*
G03X607775Y1184230I216J1284D01*
G01X608053D01*
G02X608202Y1184164I0J-200D01*
G01X608429Y1183911D01*
X608455Y1183831D01*
X608451Y1183788D01*
G03X608444Y1183661I1195J-130D01*
G03X610848I1202J0D01*
G03X610841Y1183788I-1202J-3D01*
G01X610837Y1183831D01*
X610863Y1183911D01*
X611090Y1184164D01*
G02X611239Y1184230I149J-134D01*
G01X611517D01*
G03X611730Y1184248I-3J1302D01*
G01X611777Y1184255D01*
X611866Y1184228D01*
X612167Y1183940D01*
X612198Y1183853D01*
X612193Y1183805D01*
G03X612184Y1183661I1193J-147D01*
G03X614588I1202J0D01*
G03X614579Y1183805I-1202J-3D01*
G01X614574Y1183852D01*
X614605Y1183940D01*
X614906Y1184227D01*
X614995Y1184255D01*
X615043Y1184247D01*
G03X615256Y1184229I216J1284D01*
G03X615469Y1184247I-3J1302D01*
G01X615517Y1184255D01*
X615606Y1184227D01*
X615907Y1183940D01*
X615938Y1183852D01*
X615933Y1183805D01*
G03X615924Y1183661I1193J-147D01*
G03X618328I1202J0D01*
G03X618319Y1183804I-1202J-4D01*
G01X618314Y1183851D01*
X618345Y1183939D01*
X618646Y1184226D01*
X618735Y1184254D01*
X618782Y1184246D01*
G03X618996Y1184228I216J1285D01*
G01X619273D01*
G02X619421Y1184162I0J-200D01*
G01X619649Y1183909D01*
X619675Y1183829D01*
X619671Y1183786D01*
G03X619664Y1183661I1195J-130D01*
G03X622068I1202J0D01*
G03X622061Y1183786I-1202J-5D01*
G01X622057Y1183829D01*
X622083Y1183909D01*
X622311Y1184162D01*
G02X622459Y1184228I148J-134D01*
G01X622736D01*
G03X622950Y1184246I-2J1303D01*
G01X622997Y1184254D01*
X623086Y1184226D01*
X623387Y1183939D01*
X623418Y1183851D01*
X623413Y1183804D01*
G03X623404Y1183661I1193J-147D01*
G03X625808I1202J0D01*
G03X625799Y1183805I-1202J-3D01*
G01X625794Y1183852D01*
X625825Y1183940D01*
X626126Y1184227D01*
X626215Y1184255D01*
X626263Y1184247D01*
G03X626476Y1184229I216J1284D01*
G03X626689Y1184247I-3J1302D01*
G01X626737Y1184255D01*
X626826Y1184227D01*
X627127Y1183940D01*
X627158Y1183852D01*
X627153Y1183805D01*
G03X627144Y1183661I1193J-147D01*
G03X628346Y1182459I1202J0D01*
G03X628568Y1182480I-2J1202D01*
G01X628617Y1182489D01*
X628710Y1182460D01*
X629015Y1182155D01*
X629044Y1182062D01*
X629035Y1182013D01*
G03X629014Y1181791I1181J-224D01*
G03X630216Y1182993I1202J0D01*
G03X629994Y1182972I2J-1202D01*
G01X629945Y1182963D01*
X629852Y1182992D01*
X629547Y1183297D01*
X629518Y1183390D01*
X629527Y1183439D01*
G03X629548Y1183661I-1181J224D01*
G03X629539Y1183805I-1202J-3D01*
G01X629534Y1183852D01*
X629565Y1183940D01*
X629866Y1184227D01*
X629955Y1184255D01*
X630003Y1184247D01*
G03X630216Y1184229I216J1284D01*
G03X631037Y1184522I-2J1302D01*
G01X631051Y1184533D01*
X631071Y1184544D01*
G02X631169Y1184570I99J-174D01*
G01X633004D01*
G02X633104Y1184543I0J-200D01*
G01X633123Y1184532D01*
X633136Y1184522D01*
G03X633957Y1184229I823J1009D01*
G03X634778Y1184522I-2J1302D01*
G01X634792Y1184533D01*
X634812Y1184544D01*
G02X634910Y1184570I99J-174D01*
G01X636744D01*
G02X636844Y1184543I0J-200D01*
G01X636863Y1184532D01*
X636876Y1184522D01*
G03X637697Y1184229I823J1009D01*
G03X638518Y1184522I-2J1302D01*
G01X638532Y1184533D01*
X638552Y1184544D01*
G02X638650Y1184570I99J-174D01*
G37*
G36*
G01X584258Y1529142D02*
G03I-597J0D01*
G37*
G36*
G01X574381Y1530646D02*
G03I-597J0D01*
G37*
G36*
G01X578242Y1540982D02*
G03I-597J0D01*
G37*
G36*
G01X633555Y110445D02*
G03I-597J0D01*
G37*
G36*
G01Y115401D02*
G03I-597J0D01*
G37*
G36*
G01Y124618D02*
G03I-597J0D01*
G37*
G36*
G01Y129574D02*
G03I-597J0D01*
G37*
G36*
G01X638547Y110445D02*
G03I-597J0D01*
G37*
G36*
G01Y115401D02*
G03I-597J0D01*
G37*
G36*
G01Y124618D02*
G03I-597J0D01*
G37*
G36*
G01Y129574D02*
G03I-597J0D01*
G37*
G36*
G01X643957Y117557D02*
G03I-597J0D01*
G37*
G36*
G01X648949D02*
G03I-597J0D01*
G37*
G36*
G01Y122513D02*
G03I-597J0D01*
G37*
G36*
G01X643957D02*
G03I-597J0D01*
G37*
G36*
G01Y131731D02*
G03I-597J0D01*
G37*
G36*
G01X648949D02*
G03I-597J0D01*
G37*
G36*
G01Y136687D02*
G03I-597J0D01*
G37*
G36*
G01X643957D02*
G03I-597J0D01*
G37*
G36*
G01X735917Y110445D02*
G03I-597J0D01*
G37*
G36*
G01X740909D02*
G03I-597J0D01*
G37*
G36*
G01Y115401D02*
G03I-597J0D01*
G37*
G36*
G01X735917D02*
G03I-597J0D01*
G37*
G36*
G01X746319Y117557D02*
G03I-597J0D01*
G37*
G36*
G01Y122513D02*
G03I-597J0D01*
G37*
G36*
G01X735917Y124618D02*
G03I-597J0D01*
G37*
G36*
G01X740909D02*
G03I-597J0D01*
G37*
G36*
G01Y129574D02*
G03I-597J0D01*
G37*
G36*
G01X735917D02*
G03I-597J0D01*
G37*
G36*
G01X746319Y131731D02*
G03I-597J0D01*
G37*
G36*
G01Y136687D02*
G03I-597J0D01*
G37*
G36*
G01X751311Y117557D02*
G03I-597J0D01*
G37*
G36*
G01Y122513D02*
G03I-597J0D01*
G37*
G36*
G01Y131731D02*
G03I-597J0D01*
G37*
G36*
G01Y136687D02*
G03I-597J0D01*
G37*
G36*
G01X838279Y110445D02*
G03I-597J0D01*
G37*
G36*
G01X843271D02*
G03I-597J0D01*
G37*
G36*
G01Y115401D02*
G03I-597J0D01*
G37*
G36*
G01X838279D02*
G03I-597J0D01*
G37*
G36*
G01Y124618D02*
G03I-597J0D01*
G37*
G36*
G01X843271D02*
G03I-597J0D01*
G37*
G36*
G01Y129574D02*
G03I-597J0D01*
G37*
G36*
G01X838279D02*
G03I-597J0D01*
G37*
G36*
G01X848681Y117557D02*
G03I-597J0D01*
G37*
G36*
G01X853673D02*
G03I-597J0D01*
G37*
G36*
G01Y122513D02*
G03I-597J0D01*
G37*
G36*
G01X848681D02*
G03I-597J0D01*
G37*
G36*
G01Y131731D02*
G03I-597J0D01*
G37*
G36*
G01X853673D02*
G03I-597J0D01*
G37*
G36*
G01Y136687D02*
G03I-597J0D01*
G37*
G36*
G01X848681D02*
G03I-597J0D01*
G37*
G36*
G01X872061Y373971D02*
G03I-679J0D01*
G37*
G36*
G01X884131Y602056D02*
X905340D01*
G02X905482Y601997I0J-200D01*
G01X906536Y600943D01*
G02X906595Y600801I-141J-142D01*
G01Y592841D01*
G02X906536Y592699I-200J0D01*
G01X906288Y592451D01*
X906260Y592422D01*
X906186Y592392D01*
X892183D01*
G03X892041Y592333I0J-200D01*
G01X888645Y588937D01*
G03X888586Y588795I141J-142D01*
G01Y569342D01*
G03X888645Y569200I200J0D01*
G01X892334Y565511D01*
G02X892393Y565369I-141J-142D01*
G01Y554554D01*
G02X892334Y554412I-200J0D01*
G01X889671Y551749D01*
X889643Y551720D01*
X889569Y551690D01*
X886326D01*
G02X886184Y551749I0J200D01*
G01X882753Y555180D01*
G02X882708Y555394I141J141D01*
G01X882862Y555791D01*
X882957Y555860D01*
X883018Y555863D01*
G03X884451Y557363I-69J1500D01*
G03X882949Y558865I-1502J0D01*
G03X881449Y557432I0J-1502D01*
G01X881446Y557371D01*
X881377Y557276D01*
X880980Y557122D01*
G02X880766Y557167I-73J186D01*
G01X875761Y562172D01*
X875732Y562200D01*
X875702Y562274D01*
Y569716D01*
G02X875796Y569886I200J0D01*
G01X876085Y570065D01*
G02X876278Y570075I106J-170D01*
G01X876280Y570074D01*
X876281D01*
G03X876949Y569917I669J1345D01*
G01X876970D01*
G03X878451Y571419I-21J1502D01*
G03X876949Y572921I-1502J0D01*
G03X876281Y572764I1J-1502D01*
G01X876280D01*
X876278Y572763D01*
G02X876085Y572773I-87J180D01*
G01X875796Y572952D01*
G02X875702Y573122I106J170D01*
G01Y577177D01*
X875772Y577279D01*
X875830Y577301D01*
G03Y580105I-541J1402D01*
G01X875772Y580127D01*
X875702Y580229D01*
Y593627D01*
G02X875761Y593769I200J0D01*
G01X883989Y601997D01*
G02X884131Y602056I142J-141D01*
G37*
G36*
G01X942462Y278968D02*
G03I-617J0D01*
G37*
G36*
G01X988279Y110445D02*
G03I-597J0D01*
G37*
G36*
G01X993271D02*
G03I-597J0D01*
G37*
G36*
G01Y115401D02*
G03I-597J0D01*
G37*
G36*
G01X988279D02*
G03I-597J0D01*
G37*
G36*
G01Y124618D02*
G03I-597J0D01*
G37*
G36*
G01X993271D02*
G03I-597J0D01*
G37*
G36*
G01Y129574D02*
G03I-597J0D01*
G37*
G36*
G01X988279D02*
G03I-597J0D01*
G37*
G36*
G01X1003673Y131731D02*
G03I-597J0D01*
G37*
G36*
G01X998681Y122513D02*
G03I-597J0D01*
G37*
G36*
G01Y117557D02*
G03I-597J0D01*
G37*
G36*
G01X1003673Y136687D02*
G03I-597J0D01*
G37*
G36*
G01X1030801Y288709D02*
G03I-617J0D01*
G37*
G36*
G01X1038685Y298789D02*
G03I-617J0D01*
G37*
G36*
G01X1033725D02*
G03I-613J0D01*
G37*
G36*
G01X1090641Y115401D02*
G03I-597J0D01*
G37*
G36*
G01Y110445D02*
G03I-597J0D01*
G37*
G36*
G01Y124618D02*
G03I-597J0D01*
G37*
G36*
G01Y129574D02*
G03I-597J0D01*
G37*
G36*
G01X1186048Y1197968D02*
X1186794D01*
G02X1186966Y1197870I0J-200D01*
G01X1187169Y1197528D01*
X1187171Y1197423D01*
X1187145Y1197376D01*
G03X1186985Y1196751I1141J-625D01*
G03X1188287Y1195449I1302J0D01*
G03X1189129Y1195758I0J1302D01*
G01X1189174Y1195796D01*
X1189289Y1195812D01*
X1189672Y1195635D01*
G02X1189788Y1195453I-84J-182D01*
G01Y1184953D01*
G02X1189729Y1184811I-200J0D01*
G01X1188455Y1183537D01*
G02X1188313Y1183478I-142J141D01*
G01X1183122D01*
G03X1182980Y1183419I0J-200D01*
G01X1182893Y1183332D01*
G03X1182834Y1183190I141J-142D01*
G01Y1170910D01*
G03X1182893Y1170768I200J0D01*
G01X1183230Y1170431D01*
X1183258Y1170377D01*
X1183263Y1170346D01*
G03X1184546Y1169268I1283J224D01*
G03X1185803Y1170231I0J1302D01*
G01X1185821Y1170297D01*
X1185928Y1170379D01*
X1186905D01*
X1187012Y1170297D01*
X1187030Y1170231D01*
G03X1189544I1257J339D01*
G01X1189562Y1170297D01*
X1189669Y1170379D01*
X1190645D01*
X1190752Y1170297D01*
X1190770Y1170231D01*
G03X1191869Y1169278I1257J339D01*
G01X1191945Y1169268D01*
X1192045Y1169155D01*
Y1168245D01*
X1191945Y1168132D01*
X1191869Y1168122D01*
G03Y1165538I158J-1292D01*
G01X1191945Y1165528D01*
X1192045Y1165415D01*
Y1160765D01*
X1191945Y1160652D01*
X1191869Y1160642D01*
G03Y1158058I158J-1292D01*
G01X1191945Y1158048D01*
X1192045Y1157935D01*
Y1157025D01*
X1191945Y1156912D01*
X1191869Y1156902D01*
G03Y1154318I158J-1292D01*
G01X1191945Y1154308D01*
X1192045Y1154195D01*
Y1153285D01*
X1191945Y1153172D01*
X1191869Y1153162D01*
G03Y1150578I158J-1292D01*
G01X1191945Y1150568D01*
X1192045Y1150455D01*
Y1149544D01*
X1191945Y1149431D01*
X1191869Y1149421D01*
G03Y1146837I158J-1292D01*
G01X1191945Y1146827D01*
X1192045Y1146714D01*
Y1145804D01*
X1191945Y1145691D01*
X1191869Y1145681D01*
G03Y1143097I158J-1292D01*
G01X1191945Y1143087D01*
X1192045Y1142974D01*
Y1142064D01*
X1191945Y1141951D01*
X1191869Y1141941D01*
G03Y1139357I158J-1292D01*
G01X1191945Y1139347D01*
X1192045Y1139234D01*
Y1138324D01*
X1191945Y1138211D01*
X1191869Y1138201D01*
G03X1190725Y1136922I158J-1292D01*
G01Y1136908D01*
G03X1190779Y1136537I1302J0D01*
G02X1190729Y1136339I-192J-57D01*
G01X1189876Y1135486D01*
X1189848Y1135457D01*
X1189774Y1135427D01*
X1185860D01*
G02X1185679Y1135541I0J200D01*
G01X1185525Y1135868D01*
G02X1185551Y1136081I180J86D01*
G03X1185848Y1136909I-1006J828D01*
G03X1183244I-1302J0D01*
G03X1183259Y1136709I1302J-3D01*
G03X1183541Y1136080I1287J199D01*
G02X1183567Y1135868I-155J-127D01*
G01X1183413Y1135541D01*
G02X1183232Y1135427I-181J86D01*
G01X1182120D01*
G02X1181939Y1135542I0J200D01*
G01X1181759Y1135922D01*
X1181774Y1136036D01*
X1181811Y1136081D01*
G03X1182108Y1136909I-1006J828D01*
G03X1179504I-1302J0D01*
G03X1179801Y1136081I1303J0D01*
G01X1179838Y1136036D01*
X1179853Y1135922D01*
X1179673Y1135542D01*
G02X1179492Y1135427I-181J85D01*
G01X1178380D01*
G02X1178199Y1135542I0J200D01*
G01X1178019Y1135922D01*
X1178034Y1136036D01*
X1178071Y1136081D01*
G03X1178368Y1136909I-1006J828D01*
G03X1175764I-1302J0D01*
G03X1176061Y1136081I1303J0D01*
G01X1176098Y1136036D01*
X1176113Y1135922D01*
X1175933Y1135542D01*
G02X1175752Y1135427I-181J85D01*
G01X1174640D01*
G02X1174459Y1135542I0J200D01*
G01X1174279Y1135922D01*
X1174294Y1136036D01*
X1174331Y1136081D01*
G03X1174628Y1136909I-1006J828D01*
G03X1172024I-1302J0D01*
G03X1172321Y1136081I1303J0D01*
G01X1172358Y1136036D01*
X1172373Y1135922D01*
X1172193Y1135542D01*
G02X1172012Y1135427I-181J85D01*
G01X1170900D01*
G02X1170719Y1135542I0J200D01*
G01X1170539Y1135922D01*
X1170554Y1136036D01*
X1170591Y1136081D01*
G03X1170888Y1136909I-1006J828D01*
G03X1168284I-1302J0D01*
G03X1168581Y1136081I1303J0D01*
G01X1168618Y1136036D01*
X1168633Y1135922D01*
X1168453Y1135542D01*
G02X1168272Y1135427I-181J85D01*
G01X1167160D01*
G02X1166979Y1135542I0J200D01*
G01X1166799Y1135922D01*
X1166814Y1136036D01*
X1166851Y1136081D01*
G03X1167148Y1136909I-1006J828D01*
G03X1164544I-1302J0D01*
G03X1164841Y1136081I1303J0D01*
G01X1164878Y1136036D01*
X1164893Y1135922D01*
X1164713Y1135542D01*
G02X1164532Y1135427I-181J85D01*
G01X1163420D01*
G02X1163239Y1135542I0J200D01*
G01X1163059Y1135922D01*
X1163074Y1136036D01*
X1163111Y1136081D01*
G03X1163408Y1136909I-1006J828D01*
G03X1160804I-1302J0D01*
G03X1161101Y1136081I1303J0D01*
G01X1161138Y1136036D01*
X1161153Y1135922D01*
X1160973Y1135542D01*
G02X1160792Y1135427I-181J85D01*
G01X1159679D01*
G02X1159498Y1135542I0J200D01*
G01X1159318Y1135922D01*
X1159333Y1136036D01*
X1159370Y1136081D01*
G03X1159667Y1136909I-1006J828D01*
G03X1157063I-1302J0D01*
G03X1157360Y1136081I1303J0D01*
G01X1157397Y1136036D01*
X1157412Y1135922D01*
X1157232Y1135542D01*
G02X1157051Y1135427I-181J85D01*
G01X1155939D01*
G02X1155758Y1135542I0J200D01*
G01X1155578Y1135922D01*
X1155593Y1136036D01*
X1155630Y1136081D01*
G03X1155927Y1136909I-1006J828D01*
G03X1153323I-1302J0D01*
G03X1153620Y1136081I1303J0D01*
G01X1153657Y1136036D01*
X1153672Y1135922D01*
X1153492Y1135542D01*
G02X1153311Y1135427I-181J85D01*
G01X1152199D01*
G02X1152018Y1135542I0J200D01*
G01X1151838Y1135922D01*
X1151853Y1136036D01*
X1151890Y1136081D01*
G03X1152187Y1136909I-1006J828D01*
G03X1149583I-1302J0D01*
G03X1149880Y1136081I1303J0D01*
G01X1149917Y1136036D01*
X1149932Y1135922D01*
X1149752Y1135542D01*
G02X1149571Y1135427I-181J85D01*
G01X1144719D01*
G02X1144538Y1135542I0J200D01*
G01X1144358Y1135922D01*
X1144373Y1136036D01*
X1144410Y1136081D01*
G03X1144707Y1136909I-1006J828D01*
G03X1142103I-1302J0D01*
G03X1142400Y1136081I1303J0D01*
G01X1142437Y1136036D01*
X1142452Y1135922D01*
X1142272Y1135542D01*
G02X1142091Y1135427I-181J85D01*
G01X1140979D01*
G02X1140798Y1135542I0J200D01*
G01X1140618Y1135922D01*
X1140633Y1136036D01*
X1140670Y1136081D01*
G03X1140967Y1136909I-1006J828D01*
G03X1138363I-1302J0D01*
G03X1138660Y1136081I1303J0D01*
G01X1138697Y1136036D01*
X1138712Y1135922D01*
X1138532Y1135542D01*
G02X1138351Y1135427I-181J85D01*
G01X1137238D01*
G02X1137057Y1135542I0J200D01*
G01X1136877Y1135922D01*
X1136892Y1136036D01*
X1136929Y1136081D01*
G03X1137226Y1136909I-1006J828D01*
G03X1134622I-1302J0D01*
G03X1134919Y1136081I1303J0D01*
G01X1134956Y1136036D01*
X1134971Y1135922D01*
X1134791Y1135542D01*
G02X1134610Y1135427I-181J85D01*
G01X1133498D01*
G02X1133317Y1135542I0J200D01*
G01X1133137Y1135922D01*
X1133152Y1136036D01*
X1133189Y1136081D01*
G03X1133486Y1136909I-1006J828D01*
G03X1130882I-1302J0D01*
G03X1131179Y1136081I1303J0D01*
G01X1131216Y1136036D01*
X1131231Y1135922D01*
X1131051Y1135542D01*
G02X1130870Y1135427I-181J85D01*
G01X1129758D01*
G02X1129577Y1135542I0J200D01*
G01X1129397Y1135922D01*
X1129412Y1136036D01*
X1129449Y1136081D01*
G03X1129746Y1136909I-1006J828D01*
G03X1127142I-1302J0D01*
G03X1127439Y1136081I1303J0D01*
G01X1127476Y1136036D01*
X1127491Y1135922D01*
X1127311Y1135542D01*
G02X1127130Y1135427I-181J85D01*
G01X1126018D01*
G02X1125837Y1135542I0J200D01*
G01X1125657Y1135922D01*
X1125672Y1136036D01*
X1125709Y1136081D01*
G03X1126006Y1136909I-1006J828D01*
G03X1123402I-1302J0D01*
G03X1123699Y1136081I1303J0D01*
G01X1123736Y1136036D01*
X1123751Y1135922D01*
X1123571Y1135542D01*
G02X1123390Y1135427I-181J85D01*
G01X1122278D01*
G02X1122097Y1135542I0J200D01*
G01X1121917Y1135922D01*
X1121932Y1136036D01*
X1121969Y1136081D01*
G03X1122266Y1136909I-1006J828D01*
G03X1119662I-1302J0D01*
G03X1119959Y1136081I1303J0D01*
G01X1119996Y1136036D01*
X1120011Y1135922D01*
X1119831Y1135542D01*
G02X1119650Y1135427I-181J85D01*
G01X1118538D01*
G02X1118357Y1135542I0J200D01*
G01X1118177Y1135922D01*
X1118192Y1136036D01*
X1118229Y1136081D01*
G03X1118526Y1136909I-1006J828D01*
G03X1115922I-1302J0D01*
G03X1116219Y1136081I1303J0D01*
G01X1116256Y1136036D01*
X1116271Y1135922D01*
X1116091Y1135542D01*
G02X1115910Y1135427I-181J85D01*
G01X1114798D01*
G02X1114617Y1135542I0J200D01*
G01X1114437Y1135922D01*
X1114452Y1136036D01*
X1114489Y1136081D01*
G03X1114786Y1136909I-1006J828D01*
G03X1112182I-1302J0D01*
G03X1112479Y1136081I1303J0D01*
G01X1112516Y1136036D01*
X1112531Y1135922D01*
X1112351Y1135542D01*
G02X1112170Y1135427I-181J85D01*
G01X1111349D01*
G02X1111207Y1135486I0J200D01*
G01X1110760Y1135933D01*
X1110749Y1136079D01*
X1110793Y1136139D01*
G03X1111045Y1136909I-1050J770D01*
G03X1109743Y1138211I-1302J0D01*
G03X1108973Y1137959I0J-1302D01*
G01X1108913Y1137915D01*
X1108767Y1137926D01*
X1107544Y1139149D01*
G03X1107402Y1139208I-142J-141D01*
G01X1107349D01*
G02X1107170Y1139320I1J200D01*
G01X1106986Y1139694D01*
X1106998Y1139807D01*
X1107033Y1139853D01*
G03X1107305Y1140649I-1029J796D01*
G03X1104701I-1302J0D01*
G03X1104973Y1139853I1301J0D01*
G01X1105008Y1139807D01*
X1105020Y1139694D01*
X1104836Y1139320D01*
G02X1104657Y1139208I-180J88D01*
G01X1103609D01*
G02X1103430Y1139320I1J200D01*
G01X1103246Y1139694D01*
X1103258Y1139807D01*
X1103293Y1139853D01*
G03X1103565Y1140649I-1029J796D01*
G03X1100961I-1302J0D01*
G03X1101233Y1139853I1301J0D01*
G01X1101268Y1139807D01*
X1101280Y1139694D01*
X1101096Y1139320D01*
G02X1100917Y1139208I-180J88D01*
G01X1099869D01*
G02X1099690Y1139320I1J200D01*
G01X1099506Y1139694D01*
X1099518Y1139807D01*
X1099553Y1139853D01*
G03X1099825Y1140649I-1029J796D01*
G03X1097221I-1302J0D01*
G03X1097493Y1139853I1301J0D01*
G01X1097528Y1139807D01*
X1097540Y1139694D01*
X1097356Y1139320D01*
G02X1097177Y1139208I-180J88D01*
G01X1096129D01*
G02X1095950Y1139320I1J200D01*
G01X1095766Y1139694D01*
X1095778Y1139807D01*
X1095813Y1139853D01*
G03X1096085Y1140649I-1029J796D01*
G03X1093481I-1302J0D01*
G03X1093753Y1139853I1301J0D01*
G01X1093788Y1139807D01*
X1093800Y1139694D01*
X1093616Y1139320D01*
G02X1093437Y1139208I-180J88D01*
G01X1092389D01*
G02X1092210Y1139320I1J200D01*
G01X1092026Y1139694D01*
X1092038Y1139807D01*
X1092073Y1139853D01*
G03X1092345Y1140649I-1029J796D01*
G03X1089741I-1302J0D01*
G03X1090013Y1139853I1301J0D01*
G01X1090048Y1139807D01*
X1090060Y1139694D01*
X1089876Y1139320D01*
G02X1089697Y1139208I-180J88D01*
G01X1088648D01*
G02X1088469Y1139320I1J200D01*
G01X1088285Y1139694D01*
X1088297Y1139807D01*
X1088332Y1139853D01*
G03X1088604Y1140649I-1029J796D01*
G03X1086000I-1302J0D01*
G03X1086272Y1139853I1301J0D01*
G01X1086307Y1139807D01*
X1086319Y1139694D01*
X1086135Y1139320D01*
G02X1085956Y1139208I-180J88D01*
G01X1084457D01*
G02X1084315Y1139267I0J200D01*
G01X1084295Y1139287D01*
G02Y1139569I142J141D01*
G01X1084307Y1139581D01*
X1084320Y1139591D01*
G03X1084864Y1140649I-757J1058D01*
G03X1084083Y1141842I-1302J0D01*
G01X1084028Y1141866D01*
X1083963Y1141966D01*
Y1142306D01*
G03X1083904Y1142448I-200J0D01*
G01Y1142988D01*
G02X1083939Y1143101I200J0D01*
G01X1083957Y1143127D01*
X1084003Y1143164D01*
X1084032Y1143175D01*
G03Y1145603I-470J1214D01*
G01X1084003Y1145614D01*
X1083957Y1145651D01*
X1083939Y1145677D01*
G02X1083904Y1145790I165J113D01*
G01Y1146728D01*
G02X1083939Y1146841I200J0D01*
G01X1083957Y1146867D01*
X1084003Y1146904D01*
X1084032Y1146915D01*
G03Y1149343I-470J1214D01*
G01X1084003Y1149354D01*
X1083957Y1149391D01*
X1083939Y1149417D01*
G02X1083904Y1149530I165J113D01*
G01Y1150469D01*
G02X1083939Y1150582I200J0D01*
G01X1083957Y1150608D01*
X1084003Y1150645D01*
X1084032Y1150656D01*
G03Y1153084I-470J1214D01*
G01X1084003Y1153095D01*
X1083957Y1153132D01*
X1083939Y1153158D01*
G02X1083904Y1153271I165J113D01*
G01Y1154061D01*
X1083979Y1154165D01*
X1084040Y1154186D01*
G03Y1157034I-478J1424D01*
G01X1083979Y1157055D01*
X1083904Y1157159D01*
Y1157949D01*
G02X1083939Y1158062I200J0D01*
G01X1083957Y1158088D01*
X1084003Y1158125D01*
X1084032Y1158136D01*
G03Y1160564I-470J1214D01*
G01X1084003Y1160575D01*
X1083957Y1160612D01*
X1083939Y1160638D01*
G02X1083904Y1160751I165J113D01*
G01Y1169096D01*
G02X1083961Y1169236I200J0D01*
G01X1083962Y1169237D01*
X1085466Y1170741D01*
G02X1085559Y1170794I142J-141D01*
G01X1085610Y1170806D01*
X1085705Y1170782D01*
X1085743Y1170748D01*
X1085970Y1170543D01*
X1086003Y1170478D01*
X1086006Y1170440D01*
G03X1088598I1296J131D01*
G01X1088601Y1170478D01*
X1088634Y1170543D01*
X1088861Y1170748D01*
G02X1088996Y1170800I135J-148D01*
G01X1089387D01*
X1089456Y1170773D01*
X1089484Y1170748D01*
X1089711Y1170543D01*
X1089744Y1170478D01*
X1089747Y1170440D01*
G03X1092339I1296J131D01*
G01X1092342Y1170478D01*
X1092375Y1170543D01*
X1092602Y1170748D01*
G02X1092737Y1170800I135J-148D01*
G01X1093127D01*
X1093196Y1170773D01*
X1093224Y1170748D01*
X1093451Y1170543D01*
X1093484Y1170478D01*
X1093487Y1170440D01*
G03X1094783Y1169268I1296J131D01*
G03X1096085Y1170570I0J1302D01*
G03X1095065Y1171841I-1302J0D01*
G01X1094996Y1171856D01*
X1094908Y1171966D01*
Y1172914D01*
X1094996Y1173024D01*
X1095065Y1173039D01*
G03Y1175581I-282J1271D01*
G01X1094996Y1175596D01*
X1094908Y1175706D01*
Y1176655D01*
X1094996Y1176765D01*
X1095065Y1176780D01*
G03Y1179322I-282J1271D01*
G01X1094996Y1179337D01*
X1094908Y1179447D01*
Y1180395D01*
X1094996Y1180505D01*
X1095065Y1180520D01*
G03Y1183062I-282J1271D01*
G01X1094996Y1183077D01*
X1094908Y1183187D01*
Y1184135D01*
X1094996Y1184245D01*
X1095065Y1184260D01*
G03Y1186802I-282J1271D01*
G01X1094996Y1186817D01*
X1094908Y1186927D01*
Y1187875D01*
X1094996Y1187985D01*
X1095065Y1188000D01*
G03X1096085Y1189247I-282J1271D01*
G01Y1189250D01*
G02X1096143Y1189385I200J-6D01*
G01X1097075Y1190317D01*
G02X1097077Y1190319I142J-140D01*
G02X1097217Y1190376I140J-143D01*
G01X1107372D01*
G03X1107514Y1190435I0J200D01*
G01X1108627Y1191548D01*
G03X1108686Y1191690I-141J142D01*
G01Y1191713D01*
X1108744Y1191808D01*
X1108898Y1191888D01*
G02X1109091Y1191884I93J-177D01*
G03X1109743Y1191709I652J1127D01*
G03Y1194313I0J1302D01*
G03X1109240Y1194212I0J-1303D01*
G01X1109193Y1194192D01*
X1109095Y1194202D01*
X1108775Y1194415D01*
G02X1108686Y1194581I111J166D01*
G01Y1195181D01*
G02X1108775Y1195347I200J0D01*
G01X1109095Y1195560D01*
X1109193Y1195570D01*
X1109240Y1195550D01*
G03X1109743Y1195449I503J1202D01*
G03X1111045Y1196751I0J1302D01*
G03X1110885Y1197376I-1301J0D01*
G01X1110859Y1197423D01*
X1110861Y1197528D01*
X1111064Y1197870D01*
G02X1111236Y1197968I172J-102D01*
G01X1111991D01*
G02X1112163Y1197870I0J-200D01*
G01X1112366Y1197528D01*
X1112368Y1197423D01*
X1112342Y1197376D01*
G03X1112182Y1196751I1141J-625D01*
G03X1114786I1302J0D01*
G03X1114626Y1197376I-1301J0D01*
G01X1114600Y1197423D01*
X1114602Y1197528D01*
X1114805Y1197870D01*
G02X1114977Y1197968I172J-102D01*
G01X1115731D01*
G02X1115903Y1197870I0J-200D01*
G01X1116106Y1197528D01*
X1116108Y1197423D01*
X1116082Y1197376D01*
G03X1115922Y1196751I1141J-625D01*
G03X1118526I1302J0D01*
G03X1118366Y1197376I-1301J0D01*
G01X1118340Y1197423D01*
X1118342Y1197528D01*
X1118545Y1197870D01*
G02X1118717Y1197968I172J-102D01*
G01X1119471D01*
G02X1119643Y1197870I0J-200D01*
G01X1119846Y1197528D01*
X1119848Y1197423D01*
X1119822Y1197376D01*
G03X1119662Y1196751I1141J-625D01*
G03X1122266I1302J0D01*
G03X1122106Y1197376I-1301J0D01*
G01X1122080Y1197423D01*
X1122082Y1197528D01*
X1122285Y1197870D01*
G02X1122457Y1197968I172J-102D01*
G01X1123211D01*
G02X1123383Y1197870I0J-200D01*
G01X1123586Y1197528D01*
X1123588Y1197423D01*
X1123562Y1197376D01*
G03X1123402Y1196751I1141J-625D01*
G03X1126006I1302J0D01*
G03X1125846Y1197376I-1301J0D01*
G01X1125820Y1197423D01*
X1125822Y1197528D01*
X1126025Y1197870D01*
G02X1126197Y1197968I172J-102D01*
G01X1126951D01*
G02X1127123Y1197870I0J-200D01*
G01X1127326Y1197528D01*
X1127328Y1197423D01*
X1127302Y1197376D01*
G03X1127142Y1196751I1141J-625D01*
G03X1129746I1302J0D01*
G03X1129586Y1197376I-1301J0D01*
G01X1129560Y1197423D01*
X1129562Y1197528D01*
X1129765Y1197870D01*
G02X1129937Y1197968I172J-102D01*
G01X1130691D01*
G02X1130863Y1197870I0J-200D01*
G01X1131066Y1197528D01*
X1131068Y1197423D01*
X1131042Y1197376D01*
G03X1130882Y1196751I1141J-625D01*
G03X1133486I1302J0D01*
G03X1133326Y1197376I-1301J0D01*
G01X1133300Y1197423D01*
X1133302Y1197528D01*
X1133505Y1197870D01*
G02X1133677Y1197968I172J-102D01*
G01X1134431D01*
G02X1134603Y1197870I0J-200D01*
G01X1134806Y1197528D01*
X1134808Y1197423D01*
X1134782Y1197376D01*
G03X1134622Y1196751I1141J-625D01*
G03X1137226I1302J0D01*
G03X1137066Y1197376I-1301J0D01*
G01X1137040Y1197423D01*
X1137042Y1197528D01*
X1137245Y1197870D01*
G02X1137417Y1197968I172J-102D01*
G01X1138172D01*
G02X1138344Y1197870I0J-200D01*
G01X1138547Y1197528D01*
X1138549Y1197423D01*
X1138523Y1197376D01*
G03X1138363Y1196751I1141J-625D01*
G03X1140967I1302J0D01*
G03X1140807Y1197376I-1301J0D01*
G01X1140781Y1197423D01*
X1140783Y1197528D01*
X1140986Y1197870D01*
G02X1141158Y1197968I172J-102D01*
G01X1141912D01*
G02X1142084Y1197870I0J-200D01*
G01X1142287Y1197528D01*
X1142289Y1197423D01*
X1142263Y1197376D01*
G03X1142103Y1196751I1141J-625D01*
G03X1144707I1302J0D01*
G03X1144547Y1197376I-1301J0D01*
G01X1144521Y1197423D01*
X1144523Y1197528D01*
X1144726Y1197870D01*
G02X1144898Y1197968I172J-102D01*
G01X1149392D01*
G02X1149564Y1197870I0J-200D01*
G01X1149767Y1197528D01*
X1149769Y1197423D01*
X1149743Y1197376D01*
G03X1149583Y1196751I1141J-625D01*
G03X1152187I1302J0D01*
G03X1152027Y1197376I-1301J0D01*
G01X1152001Y1197423D01*
X1152003Y1197528D01*
X1152206Y1197870D01*
G02X1152378Y1197968I172J-102D01*
G01X1153132D01*
G02X1153304Y1197870I0J-200D01*
G01X1153507Y1197528D01*
X1153509Y1197423D01*
X1153483Y1197376D01*
G03X1153323Y1196751I1141J-625D01*
G03X1155927I1302J0D01*
G03X1155767Y1197376I-1301J0D01*
G01X1155741Y1197423D01*
X1155743Y1197528D01*
X1155946Y1197870D01*
G02X1156118Y1197968I172J-102D01*
G01X1156872D01*
G02X1157044Y1197870I0J-200D01*
G01X1157247Y1197528D01*
X1157249Y1197423D01*
X1157223Y1197376D01*
G03X1157063Y1196751I1141J-625D01*
G03X1159667I1302J0D01*
G03X1159507Y1197376I-1301J0D01*
G01X1159481Y1197423D01*
X1159483Y1197528D01*
X1159686Y1197870D01*
G02X1159858Y1197968I172J-102D01*
G01X1160613D01*
G02X1160785Y1197870I0J-200D01*
G01X1160988Y1197528D01*
X1160990Y1197423D01*
X1160964Y1197376D01*
G03X1160804Y1196751I1141J-625D01*
G03X1163408I1302J0D01*
G03X1163248Y1197376I-1301J0D01*
G01X1163222Y1197423D01*
X1163224Y1197528D01*
X1163427Y1197870D01*
G02X1163599Y1197968I172J-102D01*
G01X1164353D01*
G02X1164525Y1197870I0J-200D01*
G01X1164728Y1197528D01*
X1164730Y1197423D01*
X1164704Y1197376D01*
G03X1164544Y1196751I1141J-625D01*
G03X1167148I1302J0D01*
G03X1166988Y1197376I-1301J0D01*
G01X1166962Y1197423D01*
X1166964Y1197528D01*
X1167167Y1197870D01*
G02X1167339Y1197968I172J-102D01*
G01X1168093D01*
G02X1168265Y1197870I0J-200D01*
G01X1168468Y1197528D01*
X1168470Y1197423D01*
X1168444Y1197376D01*
G03X1168284Y1196751I1141J-625D01*
G03X1170888I1302J0D01*
G03X1170728Y1197376I-1301J0D01*
G01X1170702Y1197423D01*
X1170704Y1197528D01*
X1170907Y1197870D01*
G02X1171079Y1197968I172J-102D01*
G01X1171833D01*
G02X1172005Y1197870I0J-200D01*
G01X1172208Y1197528D01*
X1172210Y1197423D01*
X1172184Y1197376D01*
G03X1172024Y1196751I1141J-625D01*
G03X1174628I1302J0D01*
G03X1174468Y1197376I-1301J0D01*
G01X1174442Y1197423D01*
X1174444Y1197528D01*
X1174647Y1197870D01*
G02X1174819Y1197968I172J-102D01*
G01X1175573D01*
G02X1175745Y1197870I0J-200D01*
G01X1175948Y1197528D01*
X1175950Y1197423D01*
X1175924Y1197376D01*
G03X1175764Y1196751I1141J-625D01*
G03X1178368I1302J0D01*
G03X1178208Y1197376I-1301J0D01*
G01X1178182Y1197423D01*
X1178184Y1197528D01*
X1178387Y1197870D01*
G02X1178559Y1197968I172J-102D01*
G01X1179313D01*
G02X1179485Y1197870I0J-200D01*
G01X1179688Y1197528D01*
X1179690Y1197423D01*
X1179664Y1197376D01*
G03X1179504Y1196751I1141J-625D01*
G03X1182108I1302J0D01*
G03X1181948Y1197376I-1301J0D01*
G01X1181922Y1197423D01*
X1181924Y1197528D01*
X1182127Y1197870D01*
G02X1182299Y1197968I172J-102D01*
G01X1183084D01*
G02X1183256Y1197869I-1J-200D01*
G01X1183458Y1197524D01*
Y1197418D01*
X1183432Y1197372D01*
G03X1183264Y1196732I1135J-640D01*
G03X1185868I1302J0D01*
G03X1185700Y1197372I-1303J0D01*
G01X1185674Y1197418D01*
Y1197524D01*
X1185876Y1197869D01*
G02X1186048Y1197968I173J-101D01*
G37*
G36*
G01X1095633Y110445D02*
G03I-597J0D01*
G37*
G36*
G01Y115401D02*
G03I-597J0D01*
G37*
G36*
G01X1101043Y117557D02*
G03I-597J0D01*
G37*
G36*
G01X1095633Y124618D02*
G03I-597J0D01*
G37*
G36*
G01Y129574D02*
G03I-597J0D01*
G37*
G36*
G01X1106035Y131731D02*
G03I-597J0D01*
G37*
G36*
G01Y122513D02*
G03I-597J0D01*
G37*
G36*
G01X1101043Y131731D02*
G03I-597J0D01*
G37*
G36*
G01Y122513D02*
G03I-597J0D01*
G37*
G36*
G01Y136687D02*
G03I-597J0D01*
G37*
G36*
G01X1106035D02*
G03I-597J0D01*
G37*
G36*
G01X1197995Y115401D02*
G03I-597J0D01*
G37*
G36*
G01X1193003Y110445D02*
G03I-597J0D01*
G37*
G36*
G01Y115401D02*
G03I-597J0D01*
G37*
G36*
G01X1197995Y110445D02*
G03I-597J0D01*
G37*
G36*
G01X1203405Y117557D02*
G03I-597J0D01*
G37*
G36*
G01X1193003Y124618D02*
G03I-597J0D01*
G37*
G36*
G01Y129574D02*
G03I-597J0D01*
G37*
G36*
G01X1203405Y131731D02*
G03I-597J0D01*
G37*
G36*
G01Y122513D02*
G03I-597J0D01*
G37*
G36*
G01X1197995Y124618D02*
G03I-597J0D01*
G37*
G36*
G01Y129574D02*
G03I-597J0D01*
G37*
G36*
G01X1203405Y136687D02*
G03I-597J0D01*
G37*
G36*
G01X1208397Y117557D02*
G03I-597J0D01*
G37*
G36*
G01Y131731D02*
G03I-597J0D01*
G37*
G36*
G01Y122513D02*
G03I-597J0D01*
G37*
G36*
G01Y136687D02*
G03I-597J0D01*
G37*
G36*
G01X1284923Y1263386D02*
G02I-17798J0D01*
G37*
G36*
G01X1282411Y374839D02*
G03I-577J0D01*
G37*
G36*
G01X1295365Y110445D02*
G03I-597J0D01*
G37*
G36*
G01Y115401D02*
G03I-597J0D01*
G37*
G36*
G01X1300357Y110445D02*
G03I-597J0D01*
G37*
G36*
G01Y115401D02*
G03I-597J0D01*
G37*
G36*
G01X1295365Y124618D02*
G03I-597J0D01*
G37*
G36*
G01X1300357D02*
G03I-597J0D01*
G37*
G36*
G01X1295365Y129574D02*
G03I-597J0D01*
G37*
G36*
G01X1300357D02*
G03I-597J0D01*
G37*
G36*
G01X1300805Y363786D02*
X1346712D01*
G02X1346852Y363729I0J-200D01*
G01X1346853Y363728D01*
X1353815Y356766D01*
G02X1353817Y356764I-140J-142D01*
G02X1353874Y356624I-143J-140D01*
G01Y319715D01*
G02X1353815Y319573I-200J0D01*
G01X1349014Y314772D01*
X1348986Y314743D01*
X1348912Y314713D01*
X1296126D01*
G02X1295984Y314772I0J200D01*
G01X1295382Y315374D01*
X1295353Y315402D01*
X1295323Y315476D01*
Y320125D01*
G02X1295394Y320277I200J-1D01*
G03Y322573I-970J1148D01*
G02X1295323Y322725I129J153D01*
G01Y323264D01*
X1295333Y323308D01*
X1295344Y323329D01*
G03X1295502Y324000I-1344J671D01*
G03X1295344Y324671I-1502J0D01*
G01X1295333Y324692D01*
X1295323Y324736D01*
Y348917D01*
G02X1295353Y349024I200J2D01*
G03X1295582Y349820I-1273J797D01*
G03X1295353Y350616I-1502J-1D01*
G02X1295323Y350723I170J105D01*
G01Y358304D01*
G02X1295380Y358444I200J0D01*
G01X1295381Y358445D01*
X1300663Y363727D01*
G02X1300665Y363729I142J-140D01*
G02X1300805Y363786I140J-143D01*
G37*
G36*
G01X1305767Y131731D02*
G03I-597J0D01*
G37*
G36*
G01X1310759D02*
G03I-597J0D01*
G37*
G36*
G01X1305767Y122513D02*
G03I-597J0D01*
G37*
G36*
G01X1310759D02*
G03I-597J0D01*
G37*
G36*
G01Y117557D02*
G03I-597J0D01*
G37*
G36*
G01X1305767D02*
G03I-597J0D01*
G37*
G36*
G01Y136687D02*
G03I-597J0D01*
G37*
G36*
G01X1310759D02*
G03I-597J0D01*
G37*
G36*
G01X1318161Y313058D02*
G03I-577J0D01*
G37*
G36*
G01X1339473Y1031612D02*
X1347443D01*
G02X1347585Y1031553I0J-200D01*
G01X1348383Y1030755D01*
G02X1348442Y1030613I-141J-142D01*
G01Y1021187D01*
G03X1348501Y1021045I200J0D01*
G01X1351291Y1018255D01*
G03X1351433Y1018196I142J141D01*
G01X1358434D01*
G03X1358576Y1018255I0J200D01*
G01X1359158Y1018837D01*
G03X1359217Y1018979I-141J142D01*
G01Y1019381D01*
X1359223Y1019405D01*
G03X1359267Y1019766I-1459J361D01*
G03X1359249Y1019997I-1502J-1D01*
G01X1359242Y1020045D01*
X1359271Y1020135D01*
X1360074Y1020938D01*
G02X1360216Y1020997I142J-141D01*
G01X1361990D01*
G02X1362132Y1020938I0J-200D01*
G01X1363559Y1019511D01*
G02X1363618Y1019369I-141J-142D01*
G01Y1013651D01*
G02X1363559Y1013509I-200J0D01*
G01X1361845Y1011795D01*
G02X1361703Y1011736I-142J141D01*
G01X1340101D01*
G03X1339959Y1011677I0J-200D01*
G01X1319641Y991359D01*
X1319590Y991331D01*
X1319562Y991325D01*
G03X1318405Y990168I312J-1469D01*
G01X1318399Y990140D01*
X1318371Y990089D01*
X1318284Y990002D01*
G03X1318225Y989860I141J-142D01*
G01Y987520D01*
G02X1318166Y987378I-200J0D01*
G01X1317934Y987146D01*
G02X1317792Y987087I-142J141D01*
G01X1313513D01*
G02X1313371Y987146I0J200D01*
G01X1312627Y987890D01*
G02X1312568Y988032I141J142D01*
G01Y996463D01*
G02X1312627Y996605I200J0D01*
G01X1338092Y1022070D01*
G03X1338151Y1022212I-141J142D01*
G01Y1030290D01*
G02X1338210Y1030432I200J0D01*
G01X1339331Y1031553D01*
G02X1339473Y1031612I142J-141D01*
G37*
G36*
G01X1326035Y310058D02*
G03I-577J0D01*
G37*
G36*
G01X1330991D02*
G03I-577J0D01*
G37*
G36*
G01X1323117Y313058D02*
G03I-577J0D01*
G37*
G36*
G01X1333909D02*
G03I-577J0D01*
G37*
G36*
G01X1333908Y370905D02*
G03I-577J0D01*
G37*
G36*
G01X1338865Y313058D02*
G03I-577J0D01*
G37*
G36*
G01X1338864Y370905D02*
G03I-577J0D01*
G37*
G36*
G01X1361616Y327099D02*
G03I-577J0D01*
G37*
G36*
G01Y342847D02*
G03I-577J0D01*
G37*
G36*
G01X1364616Y339929D02*
G03I-577J0D01*
G37*
G36*
G01Y334973D02*
G03I-577J0D01*
G37*
G36*
G01X1361616Y332055D02*
G03I-577J0D01*
G37*
G36*
G01X1364616Y355677D02*
G03I-577J0D01*
G37*
G36*
G01Y350721D02*
G03I-577J0D01*
G37*
G36*
G01X1361616Y347803D02*
G03I-577J0D01*
G37*
G36*
G01X1374325Y397758D02*
G03I-577J0D01*
G37*
G36*
G01X1375952Y428995D02*
G03I-577J0D01*
G37*
G36*
G01X1386720Y331982D02*
G03I-577J0D01*
G37*
G36*
G01X1386634Y341200D02*
G03I-577J0D01*
G37*
G36*
G01X1386548Y336791D02*
G03I-577J0D01*
G37*
G36*
G01X1384830Y346826D02*
G03I-577J0D01*
G37*
G36*
G01X1386863Y350218D02*
G03I-577J0D01*
G37*
G36*
G01X1445366Y110445D02*
G03I-597J0D01*
G37*
G36*
G01Y115401D02*
G03I-597J0D01*
G37*
G36*
G01Y124618D02*
G03I-597J0D01*
G37*
G36*
G01Y129574D02*
G03I-597J0D01*
G37*
G36*
G01X1450358Y110445D02*
G03I-597J0D01*
G37*
G36*
G01Y115401D02*
G03I-597J0D01*
G37*
G36*
G01X1460760Y117557D02*
G03I-597J0D01*
G37*
G36*
G01X1455768D02*
G03I-597J0D01*
G37*
G36*
G01Y131731D02*
G03I-597J0D01*
G37*
G36*
G01Y122513D02*
G03I-597J0D01*
G37*
G36*
G01X1460760D02*
G03I-597J0D01*
G37*
G36*
G01Y131731D02*
G03I-597J0D01*
G37*
G36*
G01X1450358Y124618D02*
G03I-597J0D01*
G37*
G36*
G01Y129574D02*
G03I-597J0D01*
G37*
G36*
G01X1455768Y136687D02*
G03I-597J0D01*
G37*
G36*
G01X1460760D02*
G03I-597J0D01*
G37*
G36*
G01X1451792Y323193D02*
G03I-577J0D01*
G37*
G36*
G01X1451907Y327588D02*
G03I-577J0D01*
G37*
G36*
G01X1451849Y340971D02*
G03I-577J0D01*
G37*
G36*
G01X1451921Y336620D02*
G03I-577J0D01*
G37*
G36*
G01X1451877Y332225D02*
G03I-577J0D01*
G37*
G36*
G01X1451964Y345609D02*
G03I-577J0D01*
G37*
G36*
G01X1451763Y350447D02*
G03I-577J0D01*
G37*
G36*
G01X1485373Y320359D02*
G03I-577J0D01*
G37*
G36*
G01X1485545Y325025D02*
G03I-577J0D01*
G37*
G36*
G01X1485259Y338394D02*
G03I-577J0D01*
G37*
G36*
G01X1485453Y329377D02*
G03I-577J0D01*
G37*
G36*
G01X1488832Y342921D02*
G03I-577J0D01*
G37*
G36*
G01X1558266Y1149508D02*
X1560546D01*
G02X1560688Y1149449I0J-200D01*
G01X1561039Y1149098D01*
G02X1561098Y1148956I-141J-142D01*
G01Y1141220D01*
G02X1561039Y1141078I-200J0D01*
G01X1560923Y1140962D01*
G02X1560640I-141J141D01*
G01X1560623Y1140979D01*
X1560598Y1141019D01*
X1560591Y1141043D01*
G03X1559350Y1141951I-1241J-394D01*
G03X1558048Y1140649I0J-1302D01*
G03X1558734Y1139502I1302J0D01*
G01X1558776Y1139479D01*
X1558830Y1139402D01*
X1558884Y1139037D01*
G02X1558828Y1138867I-198J-29D01*
G01X1558347Y1138386D01*
G02X1558205Y1138327I-142J141D01*
G01X1542565D01*
G03X1542423Y1138268I0J-200D01*
G01X1542058Y1137903D01*
G02X1541922Y1137844I-142J141D01*
G01X1541611Y1137834D01*
X1541539Y1137860D01*
X1541510Y1137885D01*
G03X1540649Y1138211I-862J-976D01*
G03X1539347Y1136909I0J-1302D01*
G03X1539673Y1136048I1302J1D01*
G01X1539698Y1136019D01*
X1539724Y1135947D01*
X1539714Y1135636D01*
G02X1539655Y1135500I-200J6D01*
G01X1534578Y1130423D01*
G02X1534442Y1130364I-142J141D01*
G01X1534131Y1130354D01*
X1534059Y1130380D01*
X1534030Y1130405D01*
G03X1533169Y1130731I-862J-976D01*
G03X1531867Y1129429I0J-1302D01*
G03X1532193Y1128568I1302J1D01*
G01X1532218Y1128539D01*
X1532244Y1128467D01*
X1532234Y1128156D01*
G02X1532175Y1128020I-200J6D01*
G01X1530837Y1126682D01*
G02X1530702Y1126624I-141J142D01*
G01X1530390Y1126614D01*
X1530318Y1126640D01*
X1530290Y1126665D01*
G03X1529429Y1126990I-861J-978D01*
G03X1528127Y1125688I0J-1302D01*
G03X1528452Y1124827I1303J0D01*
G01X1528477Y1124799D01*
X1528503Y1124727D01*
X1528493Y1124415D01*
G02X1528435Y1124280I-200J6D01*
G01X1527097Y1122942D01*
G02X1526962Y1122884I-141J142D01*
G01X1526650Y1122874D01*
X1526578Y1122900D01*
X1526550Y1122925D01*
G03X1525689Y1123250I-861J-978D01*
G03X1524387Y1121948I0J-1302D01*
G03X1524712Y1121087I1303J0D01*
G01X1524737Y1121059D01*
X1524763Y1120987D01*
X1524753Y1120675D01*
G02X1524695Y1120540I-200J6D01*
G01X1523357Y1119202D01*
G02X1523222Y1119144I-141J142D01*
G01X1522910Y1119134D01*
X1522838Y1119160D01*
X1522810Y1119185D01*
G03X1521949Y1119510I-861J-978D01*
G03X1520647Y1118208I0J-1302D01*
G03X1520972Y1117347I1303J0D01*
G01X1520997Y1117319D01*
X1521023Y1117247D01*
X1521013Y1116935D01*
G02X1520955Y1116800I-200J6D01*
G01X1519827Y1115672D01*
G02X1519685Y1115613I-142J141D01*
G01X1518853D01*
X1518809Y1115623D01*
X1518788Y1115634D01*
G03X1518208Y1115770I-579J-1166D01*
G03X1517628Y1115634I-1J-1302D01*
G01X1517607Y1115623D01*
X1517563Y1115613D01*
X1515113D01*
X1515069Y1115623D01*
X1515048Y1115634D01*
G03X1514468Y1115770I-579J-1166D01*
G03X1513888Y1115634I-1J-1302D01*
G01X1513867Y1115623D01*
X1513823Y1115613D01*
X1497465D01*
G02X1497314Y1115681I-1J200D01*
G03X1495814Y1116146I-1129J-989D01*
G01X1494986Y1116974D01*
Y1124705D01*
X1496074Y1125793D01*
G03X1497615Y1126831I111J1498D01*
G01X1497635Y1126894D01*
X1497740Y1126970D01*
X1513012D01*
G02X1513187Y1126868I1J-200D01*
G01X1513385Y1126517D01*
X1513383Y1126410D01*
X1513354Y1126363D01*
G03X1513166Y1125688I1114J-674D01*
G03X1515770I1302J0D01*
G03X1515089Y1126832I-1301J0D01*
G01X1515046Y1126855D01*
X1514993Y1126932D01*
X1514940Y1127297D01*
G02X1514997Y1127467I198J28D01*
G01X1515371Y1127841D01*
G02X1515512Y1127900I142J-141D01*
G01X1515535D01*
G03X1515676Y1127958I0J200D01*
G01X1516500Y1128782D01*
G02X1516662Y1128839I141J-142D01*
G01X1517016Y1128802D01*
X1517093Y1128755D01*
X1517118Y1128717D01*
G03X1518208Y1128127I1090J712D01*
G03X1519510Y1129429I0J1302D01*
G03X1518920Y1130519I-1302J0D01*
G01X1518882Y1130544D01*
X1518835Y1130621D01*
X1518798Y1130975D01*
G02X1518855Y1131137I199J21D01*
G01X1520241Y1132522D01*
G02X1520403Y1132580I142J-141D01*
G01X1520757Y1132543D01*
X1520834Y1132496D01*
X1520858Y1132458D01*
G03X1521949Y1131867I1091J712D01*
G03X1523251Y1133169I0J1302D01*
G03X1522660Y1134260I-1303J0D01*
G01X1522622Y1134284D01*
X1522575Y1134361D01*
X1522538Y1134715D01*
G02X1522596Y1134877I199J20D01*
G01X1523981Y1136262D01*
G02X1524143Y1136320I142J-141D01*
G01X1524497Y1136283D01*
X1524574Y1136236D01*
X1524598Y1136198D01*
G03X1525689Y1135607I1091J712D01*
G03X1526991Y1136909I0J1302D01*
G03X1526400Y1138000I-1303J0D01*
G01X1526362Y1138024D01*
X1526315Y1138101D01*
X1526278Y1138455D01*
G02X1526336Y1138617I199J20D01*
G01X1527721Y1140002D01*
G02X1527883Y1140060I142J-141D01*
G01X1528237Y1140023D01*
X1528314Y1139976D01*
X1528338Y1139938D01*
G03X1529429Y1139347I1091J712D01*
G03X1530731Y1140649I0J1302D01*
G03X1530140Y1141740I-1303J0D01*
G01X1530102Y1141764D01*
X1530055Y1141841D01*
X1530018Y1142195D01*
G02X1530076Y1142357I199J20D01*
G01X1531461Y1143742D01*
G02X1531623Y1143800I142J-141D01*
G01X1531977Y1143763D01*
X1532054Y1143716D01*
X1532078Y1143678D01*
G03X1533169Y1143087I1091J712D01*
G03X1534471Y1144389I0J1302D01*
G03X1533880Y1145480I-1303J0D01*
G01X1533842Y1145504D01*
X1533795Y1145581D01*
X1533758Y1145935D01*
G02X1533816Y1146097I199J20D01*
G01X1535201Y1147482D01*
G02X1535363Y1147540I142J-141D01*
G01X1535717Y1147503D01*
X1535794Y1147456D01*
X1535818Y1147418D01*
G03X1536909Y1146827I1091J712D01*
G03X1538128Y1147673I0J1301D01*
G01X1538150Y1147731D01*
X1538253Y1147802D01*
X1539305D01*
X1539408Y1147731D01*
X1539430Y1147673D01*
G03X1541868I1219J455D01*
G01X1541890Y1147731D01*
X1541993Y1147802D01*
X1543045D01*
X1543148Y1147731D01*
X1543170Y1147673D01*
G03X1545608I1219J455D01*
G01X1545630Y1147731D01*
X1545733Y1147802D01*
X1546786D01*
X1546889Y1147731D01*
X1546911Y1147673D01*
G03X1549349I1219J455D01*
G01X1549371Y1147731D01*
X1549474Y1147802D01*
X1550526D01*
X1550629Y1147731D01*
X1550651Y1147673D01*
G03X1553089I1219J455D01*
G01X1553111Y1147731D01*
X1553214Y1147802D01*
X1554266D01*
X1554369Y1147731D01*
X1554391Y1147673D01*
G03X1555610Y1146827I1219J455D01*
G03X1556912Y1148129I0J1302D01*
G01Y1148150D01*
X1556911Y1148191D01*
X1556942Y1148266D01*
X1558125Y1149449D01*
G02X1558266Y1149508I142J-141D01*
G37*
G36*
G01X1553290Y1155790D02*
X1554190D01*
X1554307Y1155675D01*
X1554308Y1155592D01*
G03X1555610Y1154308I1302J18D01*
G03X1556612Y1154779I0J1301D01*
G01X1556639Y1154811D01*
X1556714Y1154849D01*
X1557052Y1154865D01*
G02X1557203Y1154806I9J-200D01*
G01X1557233Y1154776D01*
G02X1557292Y1154634I-141J-142D01*
G01Y1150116D01*
G02X1557233Y1149974I-200J0D01*
G01X1556531Y1149272D01*
G02X1556285Y1149242I-142J141D01*
G03X1555610Y1149431I-676J-1113D01*
G03X1554552Y1148887I0J-1301D01*
G02X1554389Y1148804I-162J117D01*
G01X1553091D01*
G02X1552928Y1148887I-1J200D01*
G03X1550812I-1058J-757D01*
G02X1550649Y1148804I-162J117D01*
G01X1549351D01*
G02X1549188Y1148887I-1J200D01*
G03X1547072I-1058J-757D01*
G02X1546909Y1148804I-162J117D01*
G01X1545610D01*
G02X1545447Y1148887I-1J200D01*
G03X1543331I-1058J-757D01*
G02X1543168Y1148804I-162J117D01*
G01X1541870D01*
G02X1541707Y1148887I-1J200D01*
G03X1539591I-1058J-757D01*
G02X1539428Y1148804I-162J117D01*
G01X1538130D01*
G02X1537967Y1148887I-1J200D01*
G03X1535851I-1058J-757D01*
G02X1535688Y1148804I-162J117D01*
G01X1535189D01*
G03X1535047Y1148745I0J-200D01*
G01X1534952Y1148650D01*
G02X1534781Y1148594I-141J142D01*
G01X1534417Y1148648D01*
X1534339Y1148702D01*
X1534317Y1148744D01*
G03X1533169Y1149431I-1148J-616D01*
G03X1531867Y1148129I0J-1302D01*
G03X1532554Y1146981I1303J0D01*
G01X1532596Y1146959D01*
X1532650Y1146881D01*
X1532704Y1146517D01*
G02X1532648Y1146346I-198J-30D01*
G01X1527472Y1141170D01*
G02X1527301Y1141114I-141J142D01*
G01X1526937Y1141168D01*
X1526859Y1141222D01*
X1526837Y1141264D01*
G03X1525689Y1141951I-1148J-616D01*
G03X1524387Y1140649I0J-1302D01*
G03X1525074Y1139501I1303J0D01*
G01X1525116Y1139479D01*
X1525170Y1139401D01*
X1525224Y1139037D01*
G02X1525168Y1138866I-198J-30D01*
G01X1523732Y1137430D01*
G02X1523561Y1137374I-141J142D01*
G01X1523197Y1137428D01*
X1523119Y1137482D01*
X1523097Y1137524D01*
G03X1521949Y1138211I-1148J-616D01*
G03X1520647Y1136909I0J-1302D01*
G03X1521334Y1135761I1303J0D01*
G01X1521376Y1135739D01*
X1521430Y1135661D01*
X1521484Y1135297D01*
G02X1521428Y1135126I-198J-30D01*
G01X1519991Y1133689D01*
G02X1519821Y1133633I-141J142D01*
G01X1519456Y1133687D01*
X1519378Y1133741D01*
X1519356Y1133783D01*
G03X1518208Y1134471I-1148J-614D01*
G03X1516906Y1133169I0J-1302D01*
G03X1517594Y1132021I1302J0D01*
G01X1517636Y1131999D01*
X1517690Y1131921D01*
X1517744Y1131556D01*
G02X1517688Y1131386I-198J-29D01*
G01X1516251Y1129949D01*
G02X1516081Y1129893I-141J142D01*
G01X1515716Y1129947D01*
X1515638Y1130001D01*
X1515616Y1130043D01*
G03X1514468Y1130731I-1148J-614D01*
G03X1513166Y1129429I0J-1302D01*
G03X1513170Y1129331I1302J4D01*
G01X1513173Y1129289D01*
X1513146Y1129211D01*
X1512917Y1128965D01*
G02X1512771Y1128901I-147J136D01*
G01X1506754D01*
G02X1506580Y1129003I0J200D01*
G01X1506382Y1129355D01*
X1506384Y1129462D01*
X1506412Y1129509D01*
G03X1506632Y1130291I-1282J783D01*
G03X1503628I-1502J0D01*
G03X1503848Y1129509I1502J1D01*
G01X1503876Y1129462D01*
X1503878Y1129355D01*
X1503680Y1129003D01*
G02X1503506Y1128901I-174J98D01*
G01X1495181D01*
X1494847Y1129235D01*
Y1135723D01*
Y1136950D01*
X1495650Y1137753D01*
X1511995D01*
X1513723Y1139481D01*
X1513847Y1139503D01*
X1513906Y1139475D01*
G03X1514468Y1139347I563J1174D01*
G03X1515770Y1140649I0J1302D01*
G03X1515642Y1141211I-1302J-1D01*
G01X1515614Y1141270D01*
X1515636Y1141394D01*
X1517463Y1143221D01*
X1517587Y1143243D01*
X1517646Y1143215D01*
G03X1518208Y1143087I563J1174D01*
G03X1519510Y1144389I0J1302D01*
G03X1519382Y1144951I-1302J-1D01*
G01X1519354Y1145010D01*
X1519376Y1145134D01*
X1521203Y1146961D01*
X1521329Y1146983D01*
X1521386Y1146955D01*
G03X1521949Y1146827I563J1174D01*
G03X1523251Y1148129I0J1302D01*
G03X1523123Y1148692I-1302J0D01*
G01X1523095Y1148749D01*
X1523117Y1148875D01*
X1524943Y1150701D01*
X1525069Y1150723D01*
X1525126Y1150695D01*
G03X1525689Y1150567I563J1174D01*
G03X1526991Y1151869I0J1302D01*
G03X1526863Y1152432I-1302J0D01*
G01X1526835Y1152489D01*
X1526857Y1152615D01*
X1528684Y1154442D01*
X1528808Y1154464D01*
X1528867Y1154436D01*
G03X1529429Y1154308I563J1174D01*
G03X1530731Y1155592I0J1302D01*
G01X1530732Y1155675D01*
X1530849Y1155790D01*
X1531749D01*
X1531866Y1155675D01*
X1531867Y1155592D01*
G03X1534471I1302J18D01*
G01X1534472Y1155675D01*
X1534589Y1155790D01*
X1535489D01*
X1535606Y1155675D01*
X1535607Y1155592D01*
G03X1538211I1302J18D01*
G01X1538212Y1155675D01*
X1538329Y1155790D01*
X1539030D01*
X1539146Y1155675D01*
X1539147Y1155592D01*
G03X1542151I1502J18D01*
G01X1542152Y1155675D01*
X1542268Y1155790D01*
X1542969D01*
X1543086Y1155675D01*
X1543087Y1155592D01*
G03X1545691I1302J18D01*
G01X1545692Y1155675D01*
X1545809Y1155790D01*
X1550450D01*
X1550567Y1155675D01*
X1550568Y1155592D01*
G03X1553172I1302J18D01*
G01X1553173Y1155675D01*
X1553290Y1155790D01*
G37*
G36*
G01X1553289Y1174388D02*
X1554191D01*
X1554306Y1174282D01*
X1554312Y1174204D01*
G03X1555610Y1173008I1298J106D01*
G03X1556273Y1173190I-1J1302D01*
G01X1556320Y1173217D01*
X1556427Y1173218D01*
X1556776Y1173019D01*
G02X1556877Y1172845I-99J-174D01*
G01Y1168295D01*
G02X1556776Y1168121I-200J0D01*
G01X1556427Y1167922D01*
X1556319Y1167923D01*
X1556273Y1167950D01*
G03X1555610Y1168132I-664J-1120D01*
G03X1554308Y1166830I0J-1302D01*
G03X1554370Y1166435I1302J2D01*
G01X1554385Y1166389D01*
X1554370Y1166295D01*
X1554150Y1165995D01*
G02X1553998Y1165912I-163J117D01*
G01X1553492D01*
X1553482D01*
G02X1553330Y1165995I11J200D01*
G01X1553149Y1166243D01*
G02X1553110Y1166361I161J119D01*
G01Y1166434D01*
X1553118Y1166462D01*
G03X1553172Y1166830I-1248J371D01*
G03X1550568I-1302J0D01*
G03X1550630Y1166435I1302J2D01*
G01X1550645Y1166389D01*
X1550630Y1166295D01*
X1550410Y1165995D01*
G02X1550258Y1165912I-163J117D01*
G01X1549752D01*
X1549742D01*
G02X1549590Y1165995I11J200D01*
G01X1549409Y1166243D01*
G02X1549370Y1166361I161J119D01*
G01Y1166434D01*
X1549378Y1166462D01*
G03X1549432Y1166830I-1248J371D01*
G03X1546828I-1302J0D01*
G03X1546890Y1166435I1302J2D01*
G01X1546905Y1166389D01*
X1546890Y1166295D01*
X1546670Y1165995D01*
G02X1546518Y1165912I-163J117D01*
G01X1546011D01*
X1546001D01*
G02X1545849Y1165995I11J200D01*
G01X1545668Y1166243D01*
G02X1545629Y1166361I161J119D01*
G01Y1166434D01*
X1545637Y1166462D01*
G03X1545691Y1166830I-1248J371D01*
G03X1543087I-1302J0D01*
G03X1543149Y1166435I1302J2D01*
G01X1543164Y1166389D01*
X1543149Y1166295D01*
X1542929Y1165995D01*
G02X1542777Y1165912I-163J117D01*
G01X1538531D01*
X1538521D01*
G02X1538369Y1165995I11J200D01*
G01X1538188Y1166243D01*
G02X1538149Y1166361I161J119D01*
G01Y1166434D01*
X1538157Y1166462D01*
G03X1538211Y1166830I-1248J371D01*
G03X1535607I-1302J0D01*
G03X1535669Y1166435I1302J2D01*
G01X1535684Y1166389D01*
X1535669Y1166295D01*
X1535449Y1165995D01*
G02X1535297Y1165912I-163J117D01*
G01X1531051D01*
X1531041D01*
G02X1530889Y1165995I11J200D01*
G01X1530708Y1166243D01*
G02X1530669Y1166361I161J119D01*
G01Y1166434D01*
X1530677Y1166462D01*
G03X1530731Y1166830I-1248J371D01*
G03X1528127I-1302J0D01*
G03X1528189Y1166435I1302J2D01*
G01X1528204Y1166389D01*
X1528189Y1166295D01*
X1527969Y1165995D01*
G02X1527817Y1165912I-163J117D01*
G01X1527311D01*
X1527301D01*
G02X1527149Y1165995I11J200D01*
G01X1526968Y1166243D01*
G02X1526929Y1166361I161J119D01*
G01Y1166434D01*
X1526937Y1166462D01*
G03X1526991Y1166830I-1248J371D01*
G03X1524387I-1302J0D01*
G03X1524449Y1166435I1302J2D01*
G01X1524464Y1166389D01*
X1524449Y1166295D01*
X1524229Y1165995D01*
G02X1524077Y1165912I-163J117D01*
G01X1523570D01*
X1523560D01*
G02X1523408Y1165995I11J200D01*
G01X1523227Y1166243D01*
G02X1523188Y1166361I161J119D01*
G01Y1166434D01*
X1523196Y1166462D01*
G03X1523250Y1166830I-1248J371D01*
G03X1520646I-1302J0D01*
G03X1520708Y1166435I1302J2D01*
G01X1520723Y1166389D01*
X1520708Y1166295D01*
X1520488Y1165995D01*
G02X1520336Y1165912I-163J117D01*
G01X1519749D01*
G03X1519666Y1165894I0J-200D01*
G01X1519613Y1165869D01*
X1519499Y1165885D01*
X1519402Y1165966D01*
G02X1519355Y1166214I129J153D01*
G03X1519510Y1166830I-1147J616D01*
G03X1516906I-1302J0D01*
G03X1518164Y1165529I1302J0D01*
G01X1518224Y1165527D01*
X1518321Y1165459D01*
X1518478Y1165061D01*
G02X1518455Y1164872I-186J-73D01*
G01X1518444Y1164857D01*
X1514235Y1160648D01*
X1514188Y1160622D01*
X1514161Y1160615D01*
G03X1513195Y1159625I307J-1265D01*
G01X1513189Y1159596D01*
X1513162Y1159546D01*
X1505531Y1151916D01*
G02X1505389Y1151857I-142J141D01*
G01X1498073D01*
G02X1497924Y1151924I0J200D01*
G01X1497725Y1152148D01*
G02X1497676Y1152305I150J133D01*
G03X1497687Y1152491I-1491J182D01*
G03X1496185Y1153993I-1502J0D01*
G03X1495618Y1153882I0J-1502D01*
G01X1495571Y1153863D01*
X1495473Y1153873D01*
X1495217Y1154045D01*
X1495200Y1154043D01*
X1495134Y1154102D01*
G02X1495067Y1154251I133J149D01*
G01Y1162233D01*
G02X1495126Y1162375I200J0D01*
G01X1495787Y1163036D01*
G02X1495929Y1163095I142J-141D01*
G01X1501993D01*
G03X1502135Y1163154I0J200D01*
G01X1503352Y1164371D01*
G03X1503411Y1164513I-141J142D01*
G01Y1166492D01*
G02X1503426Y1166569I200J1D01*
G01X1503453Y1166633D01*
G03X1503467Y1166688I-185J76D01*
G01X1503473Y1166742D01*
X1503534Y1166828D01*
X1503918Y1167001D01*
G02X1504133Y1166968I82J-183D01*
G03X1505130Y1166589I997J1122D01*
G03Y1169593I0J1502D01*
G03X1504133Y1169214I0J-1501D01*
G01X1504088Y1169175D01*
X1503972Y1169157D01*
X1503586Y1169331D01*
G02X1503468Y1169513I82J182D01*
G01Y1173219D01*
G03X1503452Y1173297I-200J0D01*
G01X1503426Y1173358D01*
G02X1503411Y1173435I185J76D01*
G01Y1173694D01*
G02X1503470Y1173836I200J0D01*
G01X1503963Y1174329D01*
G02X1503965Y1174331I142J-140D01*
G02X1504105Y1174388I140J-143D01*
G01X1513150D01*
X1513264Y1174283D01*
X1513270Y1174205D01*
G03X1515666I1198J105D01*
G01X1515672Y1174283D01*
X1515786Y1174388D01*
X1516788D01*
X1516903Y1174282D01*
X1516909Y1174204D01*
G03X1519505I1298J106D01*
G01X1519511Y1174282D01*
X1519626Y1174388D01*
X1520529D01*
X1520644Y1174282D01*
X1520650Y1174204D01*
G03X1523246I1298J106D01*
G01X1523252Y1174282D01*
X1523367Y1174388D01*
X1524270D01*
X1524385Y1174282D01*
X1524391Y1174204D01*
G03X1526987I1298J106D01*
G01X1526993Y1174282D01*
X1527108Y1174388D01*
X1528010D01*
X1528125Y1174282D01*
X1528131Y1174204D01*
G03X1530727I1298J106D01*
G01X1530733Y1174282D01*
X1530848Y1174388D01*
X1531750D01*
X1531865Y1174282D01*
X1531871Y1174204D01*
G03X1534467I1298J106D01*
G01X1534473Y1174282D01*
X1534588Y1174388D01*
X1535490D01*
X1535605Y1174282D01*
X1535611Y1174204D01*
G03X1538207I1298J106D01*
G01X1538213Y1174282D01*
X1538328Y1174388D01*
X1539331D01*
X1539445Y1174283D01*
X1539452Y1174205D01*
G03X1541846I1197J105D01*
G01X1541853Y1174283D01*
X1541967Y1174388D01*
X1542970D01*
X1543085Y1174282D01*
X1543091Y1174204D01*
G03X1545687I1298J106D01*
G01X1545693Y1174282D01*
X1545808Y1174388D01*
X1546711D01*
X1546826Y1174282D01*
X1546832Y1174204D01*
G03X1549428I1298J106D01*
G01X1549434Y1174282D01*
X1549549Y1174388D01*
X1550451D01*
X1550566Y1174282D01*
X1550572Y1174204D01*
G03X1553168I1298J106D01*
G01X1553174Y1174282D01*
X1553289Y1174388D01*
G37*
G36*
G01X1554031Y1164911D02*
X1555882D01*
G02X1556024Y1164852I0J-200D01*
G01X1556963Y1163913D01*
G02X1557022Y1163771I-141J-142D01*
G01Y1157461D01*
G02X1556963Y1157319I-200J0D01*
G01X1556445Y1156801D01*
G02X1556212Y1156765I-141J141D01*
G01X1556211D01*
G03X1555610Y1156912I-601J-1155D01*
G01X1555609D01*
G03X1554908Y1156707I0J-1302D01*
G02X1554660Y1156733I-108J168D01*
G01X1554630Y1156762D01*
X1554558Y1156792D01*
X1554527D01*
X1552962D01*
X1552922D01*
X1552850Y1156762D01*
X1552820Y1156733D01*
G02X1552572Y1156707I-140J142D01*
G03X1551871Y1156912I-701J-1097D01*
G01X1551869D01*
G03X1551168Y1156707I0J-1302D01*
G02X1550920Y1156733I-108J168D01*
G01X1550890Y1156762D01*
X1550818Y1156792D01*
X1550787D01*
X1545481D01*
X1545441D01*
X1545369Y1156762D01*
X1545339Y1156733D01*
G02X1545091Y1156707I-140J142D01*
G03X1544390Y1156912I-701J-1097D01*
G01X1544388D01*
G03X1543687Y1156707I0J-1302D01*
G02X1543439Y1156733I-108J168D01*
G01X1543409Y1156762D01*
X1543337Y1156792D01*
X1543306D01*
X1541673D01*
G02X1541612Y1156801I-2J200D01*
G01X1541527Y1156829D01*
X1541502Y1156846D01*
G03X1540649Y1157112I-853J-1236D01*
G03X1539796Y1156846I0J-1502D01*
G01X1539771Y1156829D01*
X1539686Y1156801D01*
G02X1539625Y1156792I-59J191D01*
G01X1538001D01*
X1537961D01*
X1537889Y1156762D01*
X1537859Y1156733D01*
G02X1537611Y1156707I-140J142D01*
G03X1536910Y1156912I-701J-1097D01*
G01X1536908D01*
G03X1536207Y1156707I0J-1302D01*
G02X1535959Y1156733I-108J168D01*
G01X1535929Y1156762D01*
X1535857Y1156792D01*
X1535826D01*
X1534261D01*
X1534221D01*
X1534149Y1156762D01*
X1534119Y1156733D01*
G02X1533871Y1156707I-140J142D01*
G03X1533170Y1156912I-701J-1097D01*
G01X1533168D01*
G03X1532467Y1156707I0J-1302D01*
G02X1532219Y1156733I-108J168D01*
G01X1532189Y1156762D01*
X1532117Y1156792D01*
X1532086D01*
X1530521D01*
X1530481D01*
X1530409Y1156762D01*
X1530379Y1156733D01*
G02X1530131Y1156707I-140J142D01*
G03X1529430Y1156912I-701J-1097D01*
G01X1529429D01*
G03X1528329Y1156307I0J-1303D01*
G02X1528301Y1156272I-169J107D01*
G01X1527649Y1155620D01*
X1527609Y1155580D01*
X1527501Y1155553D01*
X1527055Y1155694D01*
X1526982Y1155777D01*
X1526972Y1155833D01*
G03X1525689Y1156912I-1283J-223D01*
G03X1524387Y1155610I0J-1302D01*
G03X1525466Y1154327I1302J0D01*
G01X1525522Y1154317D01*
X1525605Y1154244D01*
X1525729Y1153852D01*
G02X1525679Y1153650I-191J-60D01*
G01X1525031Y1153002D01*
G02X1525014Y1152987I-141J142D01*
G01X1524989Y1152967D01*
X1524981Y1152962D01*
G03X1524596Y1152577I708J-1093D01*
G01X1524591Y1152569D01*
X1524571Y1152544D01*
G02X1524556Y1152527I-157J124D01*
G01X1523909Y1151880D01*
X1523869Y1151840D01*
X1523761Y1151813D01*
X1523315Y1151954D01*
X1523242Y1152037D01*
X1523232Y1152093D01*
G03X1521949Y1153172I-1283J-223D01*
G03X1520647Y1151870I0J-1302D01*
G03X1521726Y1150587I1302J0D01*
G01X1521782Y1150577D01*
X1521865Y1150504D01*
X1521989Y1150112D01*
G02X1521939Y1149910I-191J-60D01*
G01X1521291Y1149262D01*
G02X1521274Y1149247I-141J142D01*
G01X1521249Y1149227D01*
X1521241Y1149222D01*
G03X1520856Y1148837I708J-1093D01*
G01X1520851Y1148829D01*
X1520831Y1148804D01*
G02X1520816Y1148787I-157J124D01*
G01X1520168Y1148139D01*
X1520128Y1148099D01*
X1520020Y1148072D01*
X1519574Y1148213D01*
X1519501Y1148296D01*
X1519491Y1148352D01*
G03X1518208Y1149431I-1283J-223D01*
G03X1516906Y1148129I0J-1302D01*
G03X1517985Y1146846I1302J0D01*
G01X1518041Y1146836D01*
X1518124Y1146763D01*
X1518248Y1146371D01*
G02X1518198Y1146169I-191J-60D01*
G01X1517546Y1145517D01*
G02X1517511Y1145489I-142J141D01*
G03X1517108Y1145086I697J-1100D01*
G02X1517080Y1145051I-169J107D01*
G01X1516428Y1144399D01*
X1516388Y1144359D01*
X1516280Y1144332D01*
X1515834Y1144473D01*
X1515761Y1144556D01*
X1515751Y1144612D01*
G03X1514468Y1145691I-1283J-223D01*
G03X1513166Y1144389I0J-1302D01*
G03X1514245Y1143106I1302J0D01*
G01X1514301Y1143096D01*
X1514384Y1143023D01*
X1514508Y1142631D01*
G02X1514458Y1142429I-191J-60D01*
G01X1513806Y1141777D01*
G02X1513771Y1141749I-142J141D01*
G03X1513373Y1141354I697J-1100D01*
G01X1513368Y1141346D01*
X1513348Y1141321D01*
G02X1513333Y1141304I-157J124D01*
G01X1510842Y1138813D01*
G02X1510701Y1138754I-142J141D01*
G01X1497939D01*
G02X1497772Y1138844I0J200D01*
G01X1497588Y1139121D01*
G02X1497570Y1139309I166J111D01*
G01Y1139310D01*
G03X1497687Y1139887I-1385J581D01*
G01Y1139909D01*
G03X1496185Y1141393I-1502J-18D01*
G03X1495003Y1140818I0J-1502D01*
G01X1494963Y1140767D01*
X1494841Y1140731D01*
X1494423Y1140875D01*
G02X1494288Y1141064I65J189D01*
G01Y1150272D01*
G02X1494347Y1150414I200J0D01*
G01X1494618Y1150685D01*
G02X1494760Y1150744I142J-141D01*
G01X1505944D01*
G03X1506086Y1150803I0J200D01*
G01X1513512Y1158229D01*
G02X1513762Y1158256I142J-141D01*
G03X1514468Y1158048I706J1094D01*
G03X1515770Y1159350I0J1302D01*
G03X1515562Y1160056I-1302J0D01*
G02X1515589Y1160306I168J108D01*
G01X1518986Y1163703D01*
G03X1519043Y1163816I-141J142D01*
G01X1519048Y1163848D01*
X1519077Y1163906D01*
X1520023Y1164852D01*
G02X1520164Y1164910I141J-142D01*
G01X1520351D01*
G03X1520365Y1164911I-79J1198D01*
G01X1523531D01*
G03X1523545Y1164910I93J1197D01*
G01X1524092D01*
G03X1524106Y1164911I-79J1198D01*
G01X1527272D01*
G03X1527286Y1164910I93J1197D01*
G01X1527832D01*
G03X1527846Y1164911I-79J1198D01*
G01X1531012D01*
G03X1531026Y1164910I93J1197D01*
G01X1535312D01*
G03X1535326Y1164911I-79J1198D01*
G01X1538492D01*
G03X1538506Y1164910I93J1197D01*
G01X1542792D01*
G03X1542806Y1164911I-79J1198D01*
G01X1545972D01*
G03X1545986Y1164910I93J1197D01*
G01X1546533D01*
G03X1546547Y1164911I-79J1198D01*
G01X1549713D01*
G03X1549727Y1164910I93J1197D01*
G01X1550273D01*
G03X1550287Y1164911I-79J1198D01*
G01X1553453D01*
G03X1553467Y1164910I93J1197D01*
G01X1554013D01*
G03X1554027Y1164911I-79J1198D01*
G01X1554031D01*
G37*
G36*
G01X1551320Y1198800D02*
X1562990D01*
G02X1563132Y1198741I0J-200D01*
G01X1563243Y1198630D01*
G02X1563289Y1198420I-142J-141D01*
G01X1563143Y1198024D01*
X1563051Y1197954D01*
X1562992Y1197949D01*
G03X1561888Y1196751I98J-1198D01*
G03X1563090Y1195549I1202J0D01*
G03X1563678Y1195702I1J1202D01*
G01X1563724Y1195729D01*
X1563830Y1195728D01*
X1564174Y1195526D01*
G02X1564273Y1195353I-101J-173D01*
G01Y1194409D01*
G02X1564174Y1194236I-200J0D01*
G01X1563830Y1194034D01*
X1563724Y1194033D01*
X1563678Y1194060D01*
G03X1563090Y1194213I-587J-1049D01*
G03Y1191809I0J-1202D01*
G03X1563678Y1191962I1J1202D01*
G01X1563724Y1191989D01*
X1563830Y1191988D01*
X1564174Y1191786D01*
G02X1564273Y1191613I-101J-173D01*
G01Y1186929D01*
G02X1564174Y1186756I-200J0D01*
G01X1563830Y1186554D01*
X1563724Y1186553D01*
X1563678Y1186580D01*
G03X1563090Y1186733I-587J-1049D01*
G03Y1184329I0J-1202D01*
G03X1563678Y1184482I1J1202D01*
G01X1563724Y1184509D01*
X1563830Y1184508D01*
X1564174Y1184306D01*
G02X1564273Y1184133I-101J-173D01*
G01Y1183189D01*
G02X1564174Y1183016I-200J0D01*
G01X1563830Y1182814D01*
X1563724Y1182813D01*
X1563678Y1182840D01*
G03X1563090Y1182993I-587J-1049D01*
G03Y1180589I0J-1202D01*
G03X1563678Y1180742I1J1202D01*
G01X1563724Y1180769D01*
X1563830Y1180768D01*
X1564174Y1180566D01*
G02X1564273Y1180393I-101J-173D01*
G01Y1179449D01*
G02X1564174Y1179276I-200J0D01*
G01X1563830Y1179074D01*
X1563724Y1179073D01*
X1563678Y1179100D01*
G03X1563090Y1179253I-587J-1049D01*
G03Y1176849I0J-1202D01*
G03X1563678Y1177002I1J1202D01*
G01X1563724Y1177029D01*
X1563830Y1177028D01*
X1564174Y1176826D01*
G02X1564273Y1176653I-101J-173D01*
G01Y1176383D01*
G02X1564214Y1176241I-200J0D01*
G01X1563632Y1175659D01*
G02X1563490Y1175600I-142J141D01*
G01X1557656D01*
G02X1557514Y1175659I0J200D01*
G01X1557132Y1176041D01*
G02X1557073Y1176183I141J142D01*
G01Y1184317D01*
G03X1557014Y1184459I-200J0D01*
G01X1556672Y1184801D01*
X1556652Y1184928D01*
X1556682Y1184987D01*
G03X1556812Y1185531I-1073J544D01*
G03X1555610Y1186733I-1202J0D01*
G03X1554426Y1185738I0J-1202D01*
G01X1554413Y1185666D01*
X1554302Y1185572D01*
X1553178D01*
X1553067Y1185666D01*
X1553054Y1185738D01*
G03X1551870Y1186733I-1184J-207D01*
G03X1551648Y1186712I2J-1202D01*
G01X1551599Y1186703D01*
X1551506Y1186732D01*
X1551201Y1187037D01*
X1551172Y1187130D01*
X1551181Y1187179D01*
G03X1551202Y1187401I-1181J224D01*
G03X1551181Y1187623I-1202J-2D01*
G01X1551172Y1187672D01*
X1551201Y1187765D01*
X1551506Y1188070D01*
X1551599Y1188099D01*
X1551648Y1188090D01*
G03X1551870Y1188069I224J1181D01*
G03Y1190473I0J1202D01*
G03X1551648Y1190452I2J-1202D01*
G01X1551599Y1190443D01*
X1551506Y1190472D01*
X1551201Y1190777D01*
X1551172Y1190870D01*
X1551181Y1190919D01*
G03X1551202Y1191141I-1181J224D01*
G03X1551181Y1191363I-1202J-2D01*
G01X1551172Y1191412D01*
X1551201Y1191505D01*
X1551506Y1191810D01*
X1551599Y1191839D01*
X1551648Y1191830D01*
G03X1551870Y1191809I224J1181D01*
G03Y1194213I0J1202D01*
G03X1551648Y1194192I2J-1202D01*
G01X1551599Y1194183D01*
X1551506Y1194212D01*
X1551201Y1194517D01*
X1551172Y1194610D01*
X1551181Y1194659D01*
G03X1551202Y1194881I-1181J224D01*
G03X1550000Y1193679I-1202J0D01*
G03X1550222Y1193700I-2J1202D01*
G01X1550271Y1193709D01*
X1550364Y1193680D01*
X1550669Y1193375D01*
X1550698Y1193282D01*
X1550689Y1193233D01*
G03X1550668Y1193011I1181J-224D01*
G03X1550689Y1192789I1202J2D01*
G01X1550698Y1192740D01*
X1550669Y1192647D01*
X1550364Y1192342D01*
X1550271Y1192313D01*
X1550222Y1192322D01*
G03X1550000Y1192343I-224J-1181D01*
G03Y1189939I0J-1202D01*
G03X1550222Y1189960I-2J1202D01*
G01X1550271Y1189969D01*
X1550364Y1189940D01*
X1550669Y1189635D01*
X1550698Y1189542D01*
X1550689Y1189493D01*
G03X1550668Y1189271I1181J-224D01*
G03X1550689Y1189049I1202J2D01*
G01X1550698Y1189000D01*
X1550669Y1188907D01*
X1550364Y1188602D01*
X1550271Y1188573D01*
X1550222Y1188582D01*
G03X1550000Y1188603I-224J-1181D01*
G03X1548798Y1187401I0J-1202D01*
G03X1548819Y1187179I1202J2D01*
G01X1548828Y1187130D01*
X1548799Y1187037D01*
X1548494Y1186732D01*
X1548401Y1186703D01*
X1548352Y1186712D01*
G03X1548130Y1186733I-224J-1181D01*
G03X1547907Y1186712I1J-1202D01*
G01X1547859Y1186703D01*
X1547764Y1186732D01*
X1547460Y1187036D01*
X1547431Y1187130D01*
X1547440Y1187179D01*
G03X1547461Y1187401I-1181J224D01*
G03X1546259Y1186199I-1202J0D01*
G03X1546482Y1186220I-1J1202D01*
G01X1546530Y1186229D01*
X1546625Y1186200D01*
X1546929Y1185896D01*
X1546958Y1185802D01*
X1546949Y1185753D01*
G03X1546946Y1185738I1177J-243D01*
G01X1546933Y1185666D01*
X1546822Y1185572D01*
X1495960D01*
G03X1495819Y1185513I1J-200D01*
G01X1494347Y1184041D01*
G03X1494288Y1183900I141J-142D01*
G01Y1176393D01*
G03X1494347Y1176252I200J1D01*
G01X1496152Y1174447D01*
G03X1496278Y1174388I143J141D01*
G01X1496314Y1174386D01*
X1496377Y1174357D01*
X1496423Y1174312D01*
G02X1496425Y1174310I-140J-142D01*
G03X1496567Y1174251I142J141D01*
G01X1501020D01*
G02X1501162Y1174192I0J-200D01*
G01X1502407Y1172947D01*
G02X1502466Y1172805I-141J-142D01*
G01Y1167128D01*
G02X1502407Y1166986I-200J0D01*
G01X1501580Y1166159D01*
G02X1501438Y1166100I-142J141D01*
G01X1497384D01*
G02X1497243Y1166158I0J200D01*
G03X1495127I-1058J-1066D01*
G02X1494986Y1166100I-141J142D01*
G01X1484928D01*
G02X1484856Y1166113I-1J200D01*
G01X1484759Y1166151D01*
X1484730Y1166178D01*
G03X1484630Y1166265I-1035J-1089D01*
G03X1484544Y1166329I-939J-1172D01*
G03X1484375Y1166429I-848J-1240D01*
G01X1484347Y1166444D01*
X1483520Y1167271D01*
X1483519Y1167272D01*
G03X1483502Y1167289I-858J-841D01*
G01X1483501Y1167290D01*
X1483454Y1167337D01*
X1483359Y1167433D01*
G02X1483301Y1167574I142J141D01*
G01Y1175790D01*
G02X1483360Y1175932I200J0D01*
G01X1483427Y1175999D01*
X1483557Y1176130D01*
G02X1483656Y1176184I141J-141D01*
G01X1483678Y1176189D01*
G03X1483699Y1179193I15J1502D01*
G02X1483656Y1179198I1J200D01*
G02X1483557Y1179252I42J195D01*
G01X1483427Y1179383D01*
X1483360Y1179450D01*
G02X1483301Y1179592I141J142D01*
G01Y1190845D01*
G02X1483360Y1190987I200J0D01*
G01X1491114Y1198741D01*
G02X1491256Y1198800I142J-141D01*
G01X1511278D01*
X1511394Y1198686D01*
X1511395Y1198603D01*
G03X1513799I1202J19D01*
G01X1513800Y1198686D01*
X1513916Y1198800D01*
X1515018D01*
X1515135Y1198685D01*
X1515136Y1198603D01*
G03X1517540I1202J18D01*
G01X1517541Y1198685D01*
X1517658Y1198800D01*
X1518758D01*
X1518875Y1198685D01*
X1518876Y1198603D01*
G03X1521280I1202J18D01*
G01X1521281Y1198685D01*
X1521398Y1198800D01*
X1522499D01*
X1522616Y1198685D01*
X1522617Y1198603D01*
G03X1525021I1202J18D01*
G01X1525022Y1198685D01*
X1525139Y1198800D01*
X1526239D01*
X1526356Y1198685D01*
X1526357Y1198603D01*
G03X1528761I1202J18D01*
G01X1528762Y1198685D01*
X1528879Y1198800D01*
X1529979D01*
X1530096Y1198685D01*
X1530097Y1198603D01*
G03X1532501I1202J18D01*
G01X1532502Y1198685D01*
X1532619Y1198800D01*
X1533719D01*
X1533836Y1198685D01*
X1533837Y1198603D01*
G03X1536241I1202J18D01*
G01X1536242Y1198685D01*
X1536359Y1198800D01*
X1537459D01*
X1537576Y1198685D01*
X1537577Y1198603D01*
G03X1539981I1202J18D01*
G01X1539982Y1198685D01*
X1540099Y1198800D01*
X1541199D01*
X1541316Y1198685D01*
X1541317Y1198603D01*
G03X1543721I1202J18D01*
G01X1543722Y1198685D01*
X1543839Y1198800D01*
X1544939D01*
X1545056Y1198685D01*
X1545057Y1198603D01*
G03X1547461I1202J18D01*
G01X1547462Y1198685D01*
X1547579Y1198800D01*
X1548680D01*
X1548797Y1198685D01*
X1548798Y1198603D01*
G03X1551202I1202J18D01*
G01X1551203Y1198685D01*
X1551320Y1198800D01*
G37*
G36*
G01X1555610Y1180489D02*
G03X1555657Y1180490I-4J1302D01*
G01X1555698Y1180491D01*
X1555773Y1180462D01*
X1556010Y1180234D01*
G02X1556072Y1180090I-138J-145D01*
G01Y1176011D01*
G02X1556010Y1175867I-200J1D01*
G01X1555774Y1175639D01*
X1555698Y1175610D01*
X1555657Y1175611D01*
G03X1555611Y1175612I-51J-1301D01*
G01X1555609D01*
G03X1554950Y1175433I0J-1302D01*
G01X1554928Y1175420D01*
X1554850Y1175398D01*
G02X1554795Y1175390I-56J192D01*
G01X1552685D01*
G02X1552630Y1175398I1J200D01*
G01X1552552Y1175420D01*
X1552530Y1175433D01*
G03X1551871Y1175612I-659J-1123D01*
G01X1551869D01*
G03X1551210Y1175433I0J-1302D01*
G01X1551188Y1175420D01*
X1551110Y1175398D01*
G02X1551055Y1175390I-56J192D01*
G01X1548945D01*
G02X1548890Y1175398I1J200D01*
G01X1548812Y1175420D01*
X1548790Y1175433D01*
G03X1548131Y1175612I-659J-1123D01*
G01X1548129D01*
G03X1547470Y1175433I0J-1302D01*
G01X1547448Y1175420D01*
X1547370Y1175398D01*
G02X1547315Y1175390I-56J192D01*
G01X1545204D01*
G02X1545149Y1175398I1J200D01*
G01X1545071Y1175420D01*
X1545049Y1175433D01*
G03X1544390Y1175612I-659J-1123D01*
G01X1544388D01*
G03X1543729Y1175433I0J-1302D01*
G01X1543707Y1175420D01*
X1543629Y1175398D01*
G02X1543574Y1175390I-56J192D01*
G01X1541178D01*
X1541139Y1175407D01*
G03X1540649Y1175512I-491J-1097D01*
G03X1540159Y1175407I1J-1202D01*
G01X1540120Y1175390D01*
X1537724D01*
G02X1537669Y1175398I1J200D01*
G01X1537591Y1175420D01*
X1537569Y1175433D01*
G03X1536910Y1175612I-659J-1123D01*
G01X1536908D01*
G03X1536695Y1175594I3J-1302D01*
G01X1536648Y1175587D01*
X1536559Y1175614D01*
X1536258Y1175902D01*
X1536227Y1175989D01*
X1536232Y1176037D01*
G03X1536241Y1176180I-1193J147D01*
G03X1535039Y1177382I-1202J0D01*
G03X1534817Y1177361I2J-1202D01*
G01X1534768Y1177352D01*
X1534674Y1177381D01*
X1534370Y1177685D01*
X1534341Y1177780D01*
X1534350Y1177828D01*
G03X1534371Y1178051I-1181J224D01*
G03X1533169Y1179253I-1202J0D01*
G03X1532947Y1179232I2J-1202D01*
G01X1532898Y1179223D01*
X1532805Y1179252D01*
X1532500Y1179557D01*
X1532471Y1179650D01*
X1532480Y1179699D01*
G03X1532501Y1179921I-1181J224D01*
G03X1531299Y1178719I-1202J0D01*
G03X1531521Y1178740I-2J1202D01*
G01X1531570Y1178749D01*
X1531663Y1178720D01*
X1531968Y1178415D01*
X1531997Y1178322D01*
X1531988Y1178273D01*
G03X1531967Y1178051I1181J-224D01*
G03X1531976Y1177907I1202J3D01*
G01X1531981Y1177859D01*
X1531950Y1177772D01*
X1531649Y1177484D01*
X1531560Y1177457D01*
X1531513Y1177465D01*
G03X1531299Y1177482I-210J-1285D01*
G01X1527559D01*
G03X1526256Y1176180I0J-1303D01*
G03X1526264Y1176044I1303J8D01*
G01X1526268Y1175999D01*
X1526238Y1175914D01*
X1525955Y1175631D01*
X1525870Y1175600D01*
X1525824Y1175605D01*
G03X1525690Y1175612I-135J-1295D01*
G01X1525688D01*
G03X1525029Y1175433I0J-1302D01*
G01X1525007Y1175420D01*
X1524929Y1175398D01*
G02X1524874Y1175390I-56J192D01*
G01X1522763D01*
G02X1522708Y1175398I1J200D01*
G01X1522630Y1175420D01*
X1522608Y1175433D01*
G03X1521949Y1175612I-659J-1123D01*
G01X1521947D01*
G03X1521288Y1175433I0J-1302D01*
G01X1521266Y1175420D01*
X1521188Y1175398D01*
G02X1521133Y1175390I-56J192D01*
G01X1519022D01*
G02X1518967Y1175398I1J200D01*
G01X1518889Y1175420D01*
X1518867Y1175433D01*
G03X1518208Y1175612I-659J-1123D01*
G01X1518206D01*
G03X1517547Y1175433I0J-1302D01*
G01X1517525Y1175420D01*
X1517447Y1175398D01*
G02X1517392Y1175390I-56J192D01*
G01X1514995D01*
X1514956Y1175407D01*
G03X1514468Y1175511I-489J-1098D01*
G03X1513980Y1175407I1J-1202D01*
G01X1513941Y1175390D01*
X1496708D01*
G02X1496567Y1175449I1J200D01*
G01X1496433Y1175582D01*
G02X1496381Y1175773I142J141D01*
G01X1496480Y1176158D01*
X1496553Y1176234D01*
X1496604Y1176249D01*
G03X1497687Y1177691I-419J1442D01*
G03X1496185Y1179193I-1502J0D01*
G03X1495804Y1179144I0J-1502D01*
G01X1495792Y1179141D01*
X1495767Y1179137D01*
G02X1495619Y1179177I-26J198D01*
G01X1495368Y1179369D01*
G02X1495290Y1179527I122J158D01*
G01Y1183485D01*
G02X1495349Y1183626I200J-1D01*
G01X1496234Y1184511D01*
G02X1496375Y1184570I142J-141D01*
G01X1513515D01*
G02X1513615Y1184543I0J-200D01*
G01X1513634Y1184532D01*
X1513647Y1184522D01*
G03X1514468Y1184229I823J1009D01*
G03X1514681Y1184247I-3J1302D01*
G01X1514729Y1184255D01*
X1514818Y1184227D01*
X1515119Y1183940D01*
X1515150Y1183852D01*
X1515145Y1183805D01*
G03X1515136Y1183661I1193J-147D01*
G03X1515157Y1183438I1202J1D01*
G01X1515166Y1183390D01*
X1515137Y1183295D01*
X1514833Y1182991D01*
X1514739Y1182962D01*
X1514690Y1182971D01*
G03X1514468Y1182992I-224J-1181D01*
G03X1515670Y1181790I0J-1202D01*
G03X1515649Y1182013I-1202J-1D01*
G01X1515640Y1182061D01*
X1515669Y1182156D01*
X1515973Y1182460D01*
X1516067Y1182489D01*
X1516116Y1182480D01*
G03X1516338Y1182459I224J1181D01*
G03X1516559Y1182479I3J1202D01*
G01X1516609Y1182489D01*
X1516702Y1182460D01*
X1517006Y1182155D01*
X1517035Y1182062D01*
X1517026Y1182013D01*
G03X1517005Y1181791I1181J-224D01*
G03X1519409I1202J0D01*
G03X1519388Y1182013I-1202J-2D01*
G01X1519379Y1182062D01*
X1519408Y1182156D01*
X1519712Y1182460D01*
X1519807Y1182489D01*
X1519855Y1182480D01*
G03X1520078Y1182459I224J1181D01*
G03X1521280Y1183661I0J1202D01*
G03X1521271Y1183805I-1202J-3D01*
G01X1521266Y1183853D01*
X1521297Y1183941D01*
X1521598Y1184228D01*
X1521687Y1184256D01*
X1521734Y1184248D01*
G03X1521948Y1184230I216J1284D01*
G01X1522226D01*
G02X1522375Y1184164I0J-200D01*
G01X1522602Y1183911D01*
X1522628Y1183831D01*
X1522624Y1183788D01*
G03X1522617Y1183661I1195J-130D01*
G03X1525021I1202J0D01*
G03X1525014Y1183788I-1202J-3D01*
G01X1525010Y1183831D01*
X1525036Y1183911D01*
X1525263Y1184164D01*
G02X1525412Y1184230I149J-134D01*
G01X1525690D01*
G03X1525903Y1184248I-3J1302D01*
G01X1525950Y1184255D01*
X1526039Y1184228D01*
X1526340Y1183940D01*
X1526371Y1183853D01*
X1526366Y1183805D01*
G03X1526357Y1183661I1193J-147D01*
G03X1528761I1202J0D01*
G03X1528752Y1183805I-1202J-3D01*
G01X1528747Y1183852D01*
X1528778Y1183940D01*
X1529079Y1184227D01*
X1529168Y1184255D01*
X1529216Y1184247D01*
G03X1529429Y1184229I216J1284D01*
G03X1529642Y1184247I-3J1302D01*
G01X1529690Y1184255D01*
X1529779Y1184227D01*
X1530080Y1183940D01*
X1530111Y1183852D01*
X1530106Y1183805D01*
G03X1530097Y1183661I1193J-147D01*
G03X1532501I1202J0D01*
G03X1532492Y1183804I-1202J-4D01*
G01X1532487Y1183851D01*
X1532518Y1183939D01*
X1532819Y1184226D01*
X1532908Y1184254D01*
X1532955Y1184246D01*
G03X1533169Y1184228I216J1285D01*
G01X1533446D01*
G02X1533594Y1184162I0J-200D01*
G01X1533822Y1183909D01*
X1533848Y1183829D01*
X1533844Y1183786D01*
G03X1533837Y1183661I1195J-130D01*
G03X1536241I1202J0D01*
G03X1536234Y1183786I-1202J-5D01*
G01X1536230Y1183829D01*
X1536256Y1183909D01*
X1536484Y1184162D01*
G02X1536632Y1184228I148J-134D01*
G01X1536909D01*
G03X1537123Y1184246I-2J1303D01*
G01X1537170Y1184254D01*
X1537259Y1184226D01*
X1537560Y1183939D01*
X1537591Y1183851D01*
X1537586Y1183804D01*
G03X1537577Y1183661I1193J-147D01*
G03X1538779Y1182459I1202J0D01*
G03X1539001Y1182480I-2J1202D01*
G01X1539050Y1182489D01*
X1539143Y1182460D01*
X1539448Y1182155D01*
X1539477Y1182062D01*
X1539468Y1182013D01*
G03X1539447Y1181791I1181J-224D01*
G03X1539468Y1181569I1202J2D01*
G01X1539477Y1181520D01*
X1539448Y1181427D01*
X1539143Y1181122D01*
X1539050Y1181093D01*
X1539001Y1181102D01*
G03X1538779Y1181123I-224J-1181D01*
G03Y1178719I0J-1202D01*
G03X1539001Y1178740I-2J1202D01*
G01X1539050Y1178749D01*
X1539144Y1178720D01*
X1539448Y1178416D01*
X1539477Y1178321D01*
X1539468Y1178273D01*
G03X1539447Y1178050I1181J-224D01*
G03X1540649Y1179252I1202J0D01*
G03X1540427Y1179231I2J-1202D01*
G01X1540378Y1179222D01*
X1540284Y1179251D01*
X1539980Y1179555D01*
X1539951Y1179650D01*
X1539960Y1179698D01*
G03X1539981Y1179921I-1181J224D01*
G03X1539960Y1180143I-1202J-2D01*
G01X1539951Y1180192D01*
X1539980Y1180285D01*
X1540285Y1180590D01*
X1540378Y1180619D01*
X1540427Y1180610D01*
G03X1540649Y1180589I224J1181D01*
G03X1541851Y1181791I0J1202D01*
G03X1541830Y1182013I-1202J-2D01*
G01X1541821Y1182062D01*
X1541850Y1182155D01*
X1542155Y1182460D01*
X1542248Y1182489D01*
X1542297Y1182480D01*
G03X1542519Y1182459I224J1181D01*
G03X1542741Y1182480I-2J1202D01*
G01X1542790Y1182489D01*
X1542883Y1182460D01*
X1543188Y1182155D01*
X1543217Y1182062D01*
X1543208Y1182013D01*
G03X1543187Y1181791I1181J-224D01*
G03X1544389Y1182993I1202J0D01*
G03X1544167Y1182972I2J-1202D01*
G01X1544118Y1182963D01*
X1544025Y1182992D01*
X1543720Y1183297D01*
X1543691Y1183390D01*
X1543700Y1183439D01*
G03X1543721Y1183661I-1181J224D01*
G03X1543712Y1183805I-1202J-3D01*
G01X1543707Y1183852D01*
X1543738Y1183940D01*
X1544039Y1184227D01*
X1544128Y1184255D01*
X1544176Y1184247D01*
G03X1544389Y1184229I216J1284D01*
G03X1545210Y1184522I-2J1302D01*
G01X1545223Y1184532D01*
X1545242Y1184543D01*
G02X1545342Y1184570I100J-173D01*
G01X1547177D01*
G02X1547277Y1184543I0J-200D01*
G01X1547296Y1184532D01*
X1547309Y1184522D01*
G03X1548130Y1184229I823J1009D01*
G03X1548951Y1184522I-2J1302D01*
G01X1548964Y1184532D01*
X1548983Y1184543D01*
G02X1549083Y1184570I100J-173D01*
G01X1550917D01*
G02X1551017Y1184543I0J-200D01*
G01X1551036Y1184532D01*
X1551049Y1184522D01*
G03X1551870Y1184229I823J1009D01*
G03X1552691Y1184522I-2J1302D01*
G01X1552704Y1184532D01*
X1552723Y1184543D01*
G02X1552823Y1184570I100J-173D01*
G01X1554657D01*
G02X1554757Y1184543I0J-200D01*
G01X1554776Y1184532D01*
X1554789Y1184522D01*
G03X1555610Y1184229I823J1009D01*
G03X1555722Y1184234I-2J1302D01*
G01X1555767Y1184238D01*
X1555849Y1184208D01*
X1556013Y1184044D01*
G02X1556072Y1183902I-141J-142D01*
G01Y1183492D01*
G02X1556010Y1183348I-200J1D01*
G01X1555773Y1183120D01*
X1555698Y1183091D01*
X1555657Y1183092D01*
G03X1555610Y1183093I-51J-1301D01*
G03Y1180489I0J-1302D01*
G37*
G36*
G01X1542111Y322850D02*
G03I-577J0D01*
G37*
G36*
G01X1547728Y110445D02*
G03I-597J0D01*
G37*
G36*
G01X1552720Y115401D02*
G03I-597J0D01*
G37*
G36*
G01Y110445D02*
G03I-597J0D01*
G37*
G36*
G01X1547728Y115401D02*
G03I-597J0D01*
G37*
G36*
G01X1552720Y129574D02*
G03I-597J0D01*
G37*
G36*
G01Y124618D02*
G03I-597J0D01*
G37*
G36*
G01X1547728Y129574D02*
G03I-597J0D01*
G37*
G36*
G01Y124618D02*
G03I-597J0D01*
G37*
G36*
G01X1563122Y117557D02*
G03I-597J0D01*
G37*
G36*
G01X1558130D02*
G03I-597J0D01*
G37*
G36*
G01Y131731D02*
G03I-597J0D01*
G37*
G36*
G01Y122513D02*
G03I-597J0D01*
G37*
G36*
G01X1563122Y131731D02*
G03I-597J0D01*
G37*
G36*
G01Y122513D02*
G03I-597J0D01*
G37*
G36*
G01Y136687D02*
G03I-597J0D01*
G37*
G36*
G01X1558130D02*
G03I-597J0D01*
G37*
G36*
G01X1556728Y318596D02*
G03I-577J0D01*
G37*
G36*
G01X1556871Y327814D02*
G03I-577J0D01*
G37*
G36*
G01X1557014Y332022D02*
G03I-577J0D01*
G37*
G36*
G01X1575422Y338843D02*
G03I-577J0D01*
G37*
G36*
G01X1593867Y339876D02*
G03I-577J0D01*
G37*
G36*
G01X1632807Y330400D02*
G03I-577J0D01*
G37*
G36*
G01X1655082Y110445D02*
G03I-597J0D01*
G37*
G36*
G01X1650090Y115401D02*
G03I-597J0D01*
G37*
G36*
G01Y110445D02*
G03I-597J0D01*
G37*
G36*
G01X1655082Y115401D02*
G03I-597J0D01*
G37*
G36*
G01X1650090Y124618D02*
G03I-597J0D01*
G37*
G36*
G01X1660492Y122513D02*
G03I-597J0D01*
G37*
G36*
G01Y131731D02*
G03I-597J0D01*
G37*
G36*
G01X1655082Y129574D02*
G03I-597J0D01*
G37*
G36*
G01Y124618D02*
G03I-597J0D01*
G37*
G36*
G01X1650090Y129574D02*
G03I-597J0D01*
G37*
G36*
G01X1660492Y117557D02*
G03I-597J0D01*
G37*
G36*
G01Y136687D02*
G03I-597J0D01*
G37*
G36*
G01X1665484Y122513D02*
G03I-597J0D01*
G37*
G36*
G01Y131731D02*
G03I-597J0D01*
G37*
G36*
G01Y117557D02*
G03I-597J0D01*
G37*
G36*
G01Y136687D02*
G03I-597J0D01*
G37*
G36*
G01X1735403Y376499D02*
G03I-577J0D01*
G37*
G36*
G01X1757444Y110445D02*
G03I-597J0D01*
G37*
G36*
G01X1752452Y115401D02*
G03I-597J0D01*
G37*
G36*
G01Y110445D02*
G03I-597J0D01*
G37*
G36*
G01X1757444Y115401D02*
G03I-597J0D01*
G37*
G36*
G01Y129574D02*
G03I-597J0D01*
G37*
G36*
G01Y124618D02*
G03I-597J0D01*
G37*
G36*
G01X1752452Y129574D02*
G03I-597J0D01*
G37*
G36*
G01Y124618D02*
G03I-597J0D01*
G37*
G36*
G01X1748138Y385161D02*
G03I-577J0D01*
G37*
G36*
G01X1767846Y122513D02*
G03I-597J0D01*
G37*
G36*
G01Y131731D02*
G03I-597J0D01*
G37*
G36*
G01X1762854Y122513D02*
G03I-597J0D01*
G37*
G36*
G01Y131731D02*
G03I-597J0D01*
G37*
G36*
G01X1767846Y117557D02*
G03I-597J0D01*
G37*
G36*
G01X1762854D02*
G03I-597J0D01*
G37*
G36*
G01Y136687D02*
G03I-597J0D01*
G37*
G36*
G01X1767846D02*
G03I-597J0D01*
G37*
%LPC*%
G75*
G36*
G01X598791Y1171314D02*
X599182Y1171325D01*
X599259Y1171362D01*
X599287Y1171396D01*
G02X600294Y1171872I1007J-827D01*
G01X604034D01*
G02Y1169268I0J-1302D01*
G01X600294D01*
G02X599287Y1169744I0J1303D01*
G01X599259Y1169778D01*
X599182Y1169815D01*
X598791Y1169826D01*
X598713Y1169792D01*
X598683Y1169760D01*
G02X597795Y1169368I-888J810D01*
G02Y1171772I0J1202D01*
G02X598683Y1171380I0J-1202D01*
G01X598713Y1171348D01*
X598791Y1171314D01*
G37*
G36*
G01Y1178795D02*
X599182Y1178805D01*
X599259Y1178843D01*
X599287Y1178877D01*
G02X600294Y1179354I1008J-826D01*
G01X604034D01*
G02Y1176748I0J-1303D01*
G01X600294D01*
G02X599288Y1177224I1J1303D01*
G01X599259Y1177259D01*
X599183Y1177296D01*
X598792Y1177306D01*
X598713Y1177273D01*
X598683Y1177240D01*
G02X597795Y1176848I-888J810D01*
G02Y1179252I0J1202D01*
G02X598682Y1178861I0J-1202D01*
G01X598712Y1178828D01*
X598791Y1178795D01*
G37*
G36*
G01X611941Y1179420D02*
X612169Y1179673D01*
X612195Y1179752D01*
X612191Y1179795D01*
G02X612184Y1179921I1195J130D01*
G02X614588I1202J0D01*
G02X614581Y1179795I-1202J4D01*
G01X614577Y1179752D01*
X614603Y1179673D01*
X614831Y1179420D01*
G03X614979Y1179354I148J134D01*
G01X615256D01*
G02Y1176748I0J-1303D01*
G01X611516D01*
G02Y1179354I0J1303D01*
G01X611793D01*
G03X611941Y1179420I0J200D01*
G37*
G36*
G01X1313487Y316930D02*
X1313151D01*
X1313084Y316905D01*
X1313056Y316881D01*
G02X1312069Y316511I-987J1131D01*
G02Y319515I0J1502D01*
G02X1313056Y319145I0J-1501D01*
G01X1313084Y319121D01*
X1313151Y319096D01*
X1313487D01*
X1313554Y319121D01*
X1313582Y319145D01*
G02X1314569Y319515I987J-1131D01*
G02Y316511I0J-1502D01*
G02X1313582Y316881I0J1501D01*
G01X1313554Y316905D01*
X1313487Y316930D01*
G37*
G36*
G01X1307346Y317167D02*
X1307010D01*
X1306943Y317142D01*
X1306915Y317118D01*
G02X1305928Y316748I-987J1131D01*
G02Y319752I0J1502D01*
G02X1306915Y319382I0J-1501D01*
G01X1306943Y319358D01*
X1307010Y319333D01*
X1307346D01*
X1307413Y319358D01*
X1307441Y319382D01*
G02X1308428Y319752I987J-1131D01*
G02Y316748I0J-1502D01*
G02X1307441Y317118I0J1501D01*
G01X1307413Y317142D01*
X1307346Y317167D01*
G37*
G36*
G01X1301283Y330515D02*
X1301485Y330784D01*
X1301505Y330853D01*
X1301502Y330890D01*
G02X1301498Y331000I1498J110D01*
G02X1304502I1502J0D01*
G02X1303313Y329531I-1502J0D01*
G01X1303277Y329523D01*
X1303217Y329485D01*
X1303015Y329216D01*
X1302995Y329147D01*
X1302998Y329110D01*
G02X1303002Y329000I-1498J-110D01*
G02X1302962Y328654I-1502J-2D01*
G01X1302952Y328613D01*
X1302966Y328533D01*
X1303169Y328221D01*
X1303236Y328176D01*
X1303277Y328168D01*
G02X1304502Y326692I-277J-1476D01*
G02X1301498I-1502J0D01*
G02X1301538Y327038I1502J2D01*
G01X1301548Y327079D01*
X1301534Y327159D01*
X1301331Y327471D01*
X1301264Y327516D01*
X1301223Y327524D01*
G02X1299998Y329000I277J1476D01*
G02X1301187Y330469I1502J0D01*
G01X1301223Y330477D01*
X1301283Y330515D01*
G37*
G36*
G01X1301024Y342848D02*
X1300759Y343074D01*
X1300675Y343098D01*
X1300632Y343091D01*
G02X1300400Y343073I-232J1484D01*
G02Y346077I0J1502D01*
G02X1301623Y345447I0J-1502D01*
G03X1301742Y345368I163J116D01*
G01X1301861Y345341D01*
G03X1302004Y345362I44J195D01*
G02X1302896Y345598I892J-1566D01*
G02X1304698Y343796I0J-1802D01*
G01Y340396D01*
G02X1302896Y338594I-1802J0D01*
G02X1302003Y338830I-1J1802D01*
G03X1301861Y338851I-98J-174D01*
G01X1301741Y338825D01*
G03X1301622Y338746I44J-195D01*
G02X1300400Y338117I-1222J873D01*
G02Y341121I0J1502D01*
G02X1300632Y341103I0J-1502D01*
G01X1300675Y341096D01*
X1300759Y341120D01*
X1301024Y341346D01*
G03X1301094Y341498I-130J152D01*
G01Y342696D01*
G03X1301024Y342848I-200J0D01*
G37*
G36*
G01X1313267Y333585D02*
G02X1312240Y333179I-1027J1096D01*
G02Y336183I0J1502D01*
G02X1313706Y335009I0J-1502D01*
G03X1314370Y334805I390J87D01*
G02X1315397Y335211I1027J-1096D01*
G02Y332207I0J-1502D01*
G02X1313931Y333381I0J1502D01*
G03X1313267Y333585I-390J-87D01*
G37*
G36*
G01X1512964Y1171314D02*
X1513355Y1171325D01*
X1513432Y1171362D01*
X1513460Y1171396D01*
G02X1514467Y1171872I1007J-827D01*
G01X1518207D01*
G02Y1169268I0J-1302D01*
G01X1514467D01*
G02X1513460Y1169744I0J1303D01*
G01X1513432Y1169778D01*
X1513355Y1169815D01*
X1512964Y1169826D01*
X1512886Y1169792D01*
X1512856Y1169760D01*
G02X1511968Y1169368I-888J810D01*
G02Y1171772I0J1202D01*
G02X1512856Y1171380I0J-1202D01*
G01X1512886Y1171348D01*
X1512964Y1171314D01*
G37*
G36*
G01Y1178795D02*
X1513355Y1178805D01*
X1513432Y1178843D01*
X1513460Y1178877D01*
G02X1514467Y1179354I1008J-826D01*
G01X1518207D01*
G02Y1176748I0J-1303D01*
G01X1514467D01*
G02X1513461Y1177224I1J1303D01*
G01X1513432Y1177259D01*
X1513356Y1177296D01*
X1512965Y1177306D01*
X1512886Y1177273D01*
X1512856Y1177240D01*
G02X1511968Y1176848I-888J810D01*
G02Y1179252I0J1202D01*
G02X1512855Y1178861I0J-1202D01*
G01X1512885Y1178828D01*
X1512964Y1178795D01*
G37*
G36*
G01X1522638Y1179699D02*
G02X1522617Y1179921I1181J224D01*
G02X1523819Y1178719I1202J0D01*
G02X1523596Y1178740I1J1202D01*
G03X1523129Y1178273I-74J-393D01*
G02X1523150Y1178051I-1181J-224D01*
G02X1521948Y1179253I-1202J0D01*
G02X1522171Y1179232I-1J-1202D01*
G03X1522638Y1179699I74J393D01*
G37*
G54D48*
X590957Y1117691D03*
X622736Y1151870D03*
X590957Y1142891D03*
Y1155491D03*
Y1180691D03*
X887417Y566713D03*
X1341169Y325926D03*
X1347990Y322539D03*
X1338378Y334347D03*
X1346093Y340805D03*
X1349636Y340862D03*
X1338378Y348830D03*
X1332359Y322685D03*
X1331085Y334347D03*
X1323816D03*
Y341615D03*
X1331922Y359836D03*
X1331085Y348868D03*
X1323816D03*
X1326489Y356945D03*
X1313103Y339606D03*
X1316017Y349889D03*
X1308012Y348109D03*
X1299959Y351454D03*
X1338275Y341603D03*
X1505130Y1117691D03*
X1536909Y1151870D03*
X1505130Y1155491D03*
Y1142891D03*
Y1180691D03*
G54D50*
X645177Y1185531D03*
Y1178051D03*
Y1193011D03*
Y1196751D03*
X641437Y1193011D03*
Y1196751D03*
X609646Y1191141D03*
X613386D03*
Y1194881D03*
X609646D03*
X617126Y1187401D03*
X620866D03*
X617126Y1194881D03*
Y1191141D03*
X620866D03*
Y1194881D03*
X628346Y1187401D03*
X624606D03*
Y1191141D03*
X632086Y1194881D03*
X628346D03*
X624606D03*
X628346Y1191141D03*
X632086D03*
X609646Y1187401D03*
X613386D03*
X602165D03*
X605905D03*
X602165Y1194881D03*
X605905D03*
X602165Y1191141D03*
X605905D03*
X598424Y1191142D03*
X637697Y1159350D03*
X630216D03*
X633957D03*
X626476D03*
X607776Y1155610D03*
Y1159350D03*
X618996D03*
X600295Y1151870D03*
X604035D03*
X600295Y1148129D03*
X604035Y1159350D03*
X600295Y1166829D03*
X607775Y1170570D03*
X611516D03*
X626476D03*
X630216D03*
X622736D03*
X637697D03*
X633957D03*
X637697Y1178051D03*
Y1181791D03*
X630216Y1178051D03*
X622736Y1178050D03*
X633957Y1178051D03*
Y1181791D03*
X618996Y1178051D03*
X607775D03*
X1514468Y1166829D03*
X1521948Y1170570D03*
X1525689D03*
X1540649D03*
X1544389D03*
X1536909D03*
X1551870D03*
X1548130D03*
X1551870Y1159350D03*
X1548130D03*
X1533169D03*
X1544389D03*
X1540649D03*
X1518208Y1151870D03*
X1521949Y1155610D03*
X1518208D03*
X1521949Y1159350D03*
X1518208D03*
X1514468Y1151870D03*
Y1148129D03*
Y1155610D03*
X1559350Y1193011D03*
Y1196751D03*
X1555610Y1193011D03*
Y1196751D03*
X1559350Y1185531D03*
Y1178051D03*
X1516338Y1187401D03*
Y1191141D03*
Y1194881D03*
X1535039Y1187401D03*
X1531299D03*
X1527559D03*
X1523819D03*
X1520078D03*
X1535039Y1194881D03*
Y1191141D03*
X1531299D03*
Y1194881D03*
X1523819D03*
X1527559D03*
Y1191141D03*
X1523819D03*
X1520078D03*
Y1194881D03*
X1538779Y1187401D03*
Y1194881D03*
Y1191141D03*
X1546259D03*
X1542519D03*
Y1194881D03*
X1546259D03*
X1542519Y1187401D03*
X1512597Y1191142D03*
X1551870Y1178051D03*
Y1181791D03*
X1548130Y1178051D03*
Y1181791D03*
X1544389Y1178051D03*
X1527559Y1179921D03*
G54D58*
X604035Y1121948D03*
X600295D03*
X607776Y1125688D03*
X611516D03*
X637697Y1140649D03*
X633957D03*
X641437D03*
X645177Y1144389D03*
X637697D03*
X641437D03*
X633957D03*
X618996Y1133169D03*
Y1136909D03*
X622736D03*
X630216Y1140649D03*
X626476D03*
X622736D03*
X618996D03*
X626476Y1144389D03*
X630216D03*
X604035Y1118208D03*
X607776Y1121948D03*
X615256Y1129429D03*
X604035Y1125688D03*
X607776Y1129429D03*
X611516D03*
X615256Y1136909D03*
X600295Y1118208D03*
X622736Y1144389D03*
X600295Y1136909D03*
X604035D03*
X637697Y1151870D03*
X633957D03*
X626476D03*
X630216D03*
X618996D03*
X607776Y1140649D03*
X604035D03*
X615256Y1151869D03*
X607776Y1144389D03*
X600295Y1133169D03*
X1087302Y1159350D03*
Y1166830D03*
Y1144389D03*
Y1148129D03*
Y1151870D03*
Y1155610D03*
X1098523Y1181791D03*
X1106003D03*
X1102263Y1185531D03*
X1098523Y1178051D03*
X1102263Y1181791D03*
Y1174310D03*
X1106003Y1185531D03*
Y1178051D03*
X1098523Y1174310D03*
X1106003D03*
X1102263Y1178051D03*
X1098523Y1159350D03*
X1102263Y1166830D03*
X1098523Y1170570D03*
X1106003Y1159350D03*
Y1170570D03*
X1102263Y1159350D03*
X1094783D03*
X1106003Y1166830D03*
X1094783D03*
X1098523D03*
X1102263Y1170570D03*
Y1151870D03*
X1106003Y1155610D03*
Y1148129D03*
X1102263D03*
X1098523Y1151870D03*
X1102263Y1155610D03*
X1106003Y1144389D03*
Y1151869D03*
X1098523Y1155610D03*
X1094783Y1148129D03*
Y1155610D03*
Y1151870D03*
X1098523Y1148129D03*
X1094783Y1144389D03*
X1102263D03*
X1120964Y1181791D03*
X1117224D03*
X1113484D03*
X1120964Y1189271D03*
X1117224D03*
X1113484D03*
X1109743D03*
X1120964Y1166830D03*
Y1170570D03*
X1117224Y1166830D03*
X1113484Y1170570D03*
X1120964Y1159350D03*
X1109743Y1166830D03*
X1113484Y1159350D03*
X1109743D03*
X1117224D03*
Y1170570D03*
X1109743D03*
X1113484Y1166830D03*
X1117224Y1155610D03*
X1109743Y1148129D03*
Y1155610D03*
X1120964Y1151870D03*
X1117224D03*
X1113484D03*
X1120964Y1144389D03*
X1117224D03*
X1113484D03*
Y1155610D03*
X1109743Y1151869D03*
X1120964Y1148129D03*
X1117224D03*
X1113484D03*
X1109743Y1144389D03*
X1120964Y1155610D03*
X1109743Y1140649D03*
X1113484D03*
X1117224D03*
X1120964D03*
Y1193011D03*
X1117224D03*
X1113484D03*
X1109743Y1185531D03*
X1113484Y1174310D03*
X1109743Y1178051D03*
X1117224Y1174310D03*
X1109743Y1181791D03*
Y1174310D03*
X1117224Y1185531D03*
X1113484D03*
X1120964Y1178051D03*
X1117224D03*
X1113484D03*
X1120964Y1185531D03*
Y1174310D03*
X1135924Y1155610D03*
X1128444D03*
X1124704D03*
X1132184D03*
X1135925Y1151870D03*
X1132184D03*
X1128444D03*
X1124704D03*
X1135924Y1144389D03*
X1124704Y1140649D03*
X1128444D03*
X1132184D03*
X1135924D03*
X1124704Y1193011D03*
X1135924D03*
X1132184D03*
X1128444D03*
X1132184Y1185531D03*
X1128444D03*
X1124704D03*
X1135924Y1178051D03*
X1132184D03*
X1128444D03*
X1124704D03*
X1135924Y1181791D03*
X1132184D03*
X1128444D03*
X1124704D03*
X1135924Y1189271D03*
X1132184D03*
X1128444D03*
X1124704D03*
X1135924Y1174310D03*
X1128444D03*
X1132184D03*
X1124704D03*
X1135924Y1185531D03*
X1128444Y1159350D03*
X1135924Y1170570D03*
X1132184Y1166830D03*
X1128444Y1170570D03*
X1135924Y1159350D03*
X1124704Y1166830D03*
X1128444D03*
X1124704Y1170570D03*
Y1159350D03*
X1135925Y1166830D03*
X1132184Y1170570D03*
Y1159350D03*
Y1144389D03*
X1128444D03*
X1124704D03*
X1135924Y1148129D03*
X1132184D03*
X1128444D03*
X1124704D03*
X1154625Y1193011D03*
X1150885D03*
X1143405D03*
X1139665D03*
X1150885Y1174310D03*
X1139665D03*
X1154625Y1185531D03*
X1150885D03*
X1154625Y1178051D03*
X1150885D03*
X1143405Y1185531D03*
X1139665D03*
X1143405Y1178051D03*
X1139665D03*
X1143405Y1174310D03*
X1150885Y1189271D03*
X1154625D03*
X1150885Y1181791D03*
X1154625D03*
X1143405D03*
X1139665D03*
X1143405Y1189271D03*
X1139665D03*
X1154625Y1174310D03*
X1150885Y1166830D03*
X1154625Y1170570D03*
Y1159350D03*
X1143405D03*
Y1170570D03*
X1139665Y1166830D03*
Y1170570D03*
X1143405Y1166830D03*
X1139665Y1159350D03*
X1154625Y1166830D03*
X1150885Y1170570D03*
Y1159350D03*
X1154625Y1144389D03*
X1150885D03*
X1143405D03*
X1139665D03*
X1143405Y1155610D03*
Y1148129D03*
X1139665D03*
X1150885D03*
X1154625D03*
Y1155610D03*
X1150885D03*
X1139665D03*
X1143405Y1151870D03*
X1139665D03*
X1154625Y1151869D03*
X1150885D03*
X1139665Y1140649D03*
X1143405D03*
X1150885D03*
X1154625D03*
X1162106Y1193011D03*
X1158365D03*
X1169586D03*
X1165846D03*
X1169586Y1174310D03*
X1165846D03*
X1158365D03*
Y1185531D03*
X1162106D03*
X1169586D03*
X1165846D03*
X1158365Y1178051D03*
X1162106D03*
X1169586D03*
X1165846D03*
X1158365Y1189271D03*
X1162106D03*
X1165846D03*
X1169586D03*
X1158365Y1181791D03*
X1162106D03*
X1165846D03*
X1169586D03*
X1162106Y1174310D03*
X1165846Y1166830D03*
X1169586Y1170570D03*
X1158365Y1166830D03*
X1162106Y1170570D03*
Y1159350D03*
X1169586D03*
X1158365D03*
Y1170570D03*
X1169586Y1166830D03*
X1162106D03*
X1165846Y1170570D03*
Y1159350D03*
Y1155610D03*
X1158365D03*
Y1151869D03*
X1162106D03*
X1169586D03*
X1165846D03*
X1158365Y1144389D03*
X1162106D03*
X1169586D03*
X1165846D03*
X1158365Y1148129D03*
X1162106D03*
X1165846D03*
X1169586D03*
X1162106Y1155610D03*
X1169586D03*
X1158365Y1140649D03*
X1162106D03*
X1165846D03*
X1169586D03*
X1180806Y1185531D03*
X1173326D03*
X1177066D03*
X1180806Y1178051D03*
X1173326D03*
X1177066D03*
X1184546Y1189271D03*
X1173326D03*
X1177066D03*
X1180806D03*
X1184546Y1185531D03*
X1173326Y1181791D03*
X1177066D03*
X1180806D03*
Y1170570D03*
X1177066D03*
X1184546Y1166830D03*
X1180806D03*
Y1159350D03*
X1184546D03*
X1177066D03*
Y1166830D03*
X1173326Y1170570D03*
Y1159350D03*
Y1166830D03*
X1180806Y1144389D03*
X1177066D03*
X1173326Y1148129D03*
X1177066D03*
X1180806D03*
X1184546Y1144389D03*
Y1148129D03*
Y1151869D03*
Y1155610D03*
X1177066D03*
X1180806D03*
X1173326D03*
Y1151869D03*
X1180806D03*
X1177066D03*
X1173326Y1144389D03*
X1184546Y1140649D03*
X1173326D03*
X1177066D03*
X1180806D03*
X1173326Y1193011D03*
X1180806D03*
X1177066D03*
X1184546D03*
X1177066Y1174310D03*
X1180806D03*
X1173326D03*
X1188287Y1166830D03*
Y1159350D03*
Y1155610D03*
Y1151869D03*
Y1148129D03*
X1518208Y1121948D03*
X1514468D03*
X1521949Y1125688D03*
X1525689D03*
X1551870Y1140649D03*
X1548130D03*
X1555610D03*
X1559350Y1144389D03*
X1551870D03*
X1555610D03*
X1548130D03*
X1533169Y1133169D03*
Y1136909D03*
X1536909D03*
X1544389Y1140649D03*
X1540649D03*
X1536909D03*
X1533169D03*
X1540649Y1144389D03*
X1544389D03*
X1518208Y1118208D03*
X1521949Y1121948D03*
X1529429Y1129429D03*
X1518208Y1125688D03*
X1521949Y1129429D03*
X1525689D03*
X1529429Y1136909D03*
X1514468Y1118208D03*
X1536909Y1144389D03*
X1514468Y1136909D03*
X1518208D03*
X1551870Y1151870D03*
X1548130D03*
X1540649D03*
X1544389D03*
X1533169D03*
X1521949Y1140649D03*
X1518208D03*
X1529429Y1151869D03*
X1521949Y1144389D03*
X1514468Y1133169D03*
G54D51*
X622736Y1159350D03*
X1536909D03*
G54D54*
X1267125Y1263386D03*
%LPD*%
G75*
G54D10*
G01X58443Y1272257D02*
Y1260231D01*
X66324Y1241204D01*
Y1217987D01*
X71541Y1212771D01*
Y1210180D01*
X64486Y1203125D01*
Y1180756D01*
X77734Y1167508D01*
Y1095676D01*
G01X247278Y618288D02*
Y614096D01*
X250660Y610714D01*
Y542190D01*
X246148Y537678D01*
Y454403D01*
X254678Y445873D01*
G01X878382Y554942D02*
X888561Y544763D01*
X898374D01*
X905570Y551959D01*
Y556848D01*
X908846Y560124D01*
G01X1003181Y323057D02*
X1005842Y325718D01*
Y333409D01*
X1004800Y334451D01*
Y349574D01*
X1000420Y353954D01*
G01X1050295Y891100D02*
X1048795Y889600D01*
X1023709D01*
X1022316Y888207D01*
Y885081D01*
X1022313Y885078D01*
Y861601D01*
X1017845Y857133D01*
Y849936D01*
X1015845Y847936D01*
X1008378D01*
X1005599Y845157D01*
Y841601D01*
X1008654Y838546D01*
Y808894D01*
X1006422Y806662D01*
Y793578D01*
X1007027Y792973D01*
G01X1011782Y1016591D02*
Y1005547D01*
X1006126Y999891D01*
Y986084D01*
X1011409Y980801D01*
Y978538D01*
X1013942Y976005D01*
X1031408D01*
X1037536Y969877D01*
Y933348D01*
X1030917Y926729D01*
X1020471D01*
X1011409Y917667D01*
Y912118D01*
X1012842Y910685D01*
G01X1050295Y891100D02*
Y894700D01*
X1048125Y896870D01*
X1026657D01*
X1012842Y910685D01*
G01X1161451Y618288D02*
Y567270D01*
X1155052Y560871D01*
Y449700D01*
X1158879Y445873D01*
X1168851D01*
G01X1170465Y677836D02*
X1167864Y675235D01*
Y637424D01*
X1161451Y631011D01*
Y618288D01*
G01X1333974Y1033483D02*
X1297752Y997261D01*
Y974810D01*
X1292384Y969442D01*
Y965156D01*
X1293733Y963807D01*
Y959573D01*
X1292384Y958224D01*
Y938004D01*
X1298975Y931413D01*
Y925750D01*
X1294075Y920850D01*
Y917000D01*
G01X1564670Y650122D02*
X1567977Y646815D01*
X1571376Y638610D01*
Y625242D01*
X1567239Y615254D01*
X1562385Y610400D01*
G01X1618538Y618288D02*
Y560585D01*
X1611738Y553785D01*
Y452223D01*
X1618088Y445873D01*
X1625938D01*
G01X1618538Y618288D02*
X1627224Y639258D01*
Y643252D01*
X3704Y5374D03*
X3017Y24773D03*
Y44773D03*
Y64773D03*
Y84773D03*
Y104773D03*
Y124773D03*
Y144773D03*
Y164773D03*
Y184773D03*
Y204773D03*
Y224773D03*
Y244773D03*
Y264773D03*
Y284773D03*
Y304773D03*
X3221Y324773D03*
X3035Y978036D03*
Y998036D03*
Y1018036D03*
Y1038036D03*
Y1058036D03*
Y1078036D03*
Y1098036D03*
Y1118036D03*
Y1138036D03*
Y1158036D03*
Y1178036D03*
Y1198036D03*
Y1238036D03*
Y1258036D03*
Y1278036D03*
Y1298036D03*
Y1318036D03*
Y1338036D03*
Y1358036D03*
Y1378036D03*
Y1398036D03*
Y1418036D03*
Y1438036D03*
Y1458036D03*
Y1478036D03*
Y1498036D03*
Y1538036D03*
Y1558036D03*
Y1578036D03*
X3017Y1639466D03*
X15972Y3000D03*
X20408Y51296D03*
Y55296D03*
X14751Y62381D03*
X7271Y70981D03*
X14264Y94236D03*
X10292D03*
X18000Y90000D03*
X9364Y107501D03*
X16728Y107910D03*
X12652Y116894D03*
X14996Y133034D03*
X11442Y132719D03*
X19184Y144728D03*
X15184D03*
X13615Y153263D03*
X10966Y155873D03*
Y152873D03*
X12709Y175777D03*
X16709Y175943D03*
X15139Y198883D03*
X15520Y195176D03*
X18320D03*
X13020D03*
X10520D03*
X15139Y201683D03*
X12880Y203393D03*
X10380D03*
X19068Y206838D03*
X16568D03*
X22599Y228646D03*
X18564Y238589D03*
X9745Y245784D03*
X13715Y259381D03*
X19075Y278429D03*
X8335Y280663D03*
X15499Y288542D03*
X10971Y333342D03*
X17964Y349298D03*
Y369298D03*
Y389298D03*
Y409298D03*
Y429298D03*
Y449298D03*
Y469298D03*
Y489298D03*
Y509298D03*
Y529298D03*
Y549298D03*
Y569298D03*
Y589298D03*
Y609298D03*
Y629298D03*
Y649298D03*
Y669298D03*
Y689298D03*
Y709298D03*
Y729298D03*
Y749298D03*
Y769298D03*
Y789298D03*
Y809298D03*
Y829298D03*
Y849298D03*
Y869298D03*
Y889298D03*
Y909298D03*
Y929298D03*
X9554Y961954D03*
X17964Y949298D03*
X17033Y1006819D03*
X14357Y1009906D03*
X20216Y1009748D03*
X14197Y1014205D03*
Y1017759D03*
X20197Y1014205D03*
Y1017759D03*
X20079Y1429347D03*
X12599Y1438143D03*
X19745Y1508846D03*
X19735Y1530499D03*
X19859Y1520657D03*
X18879Y1534334D03*
X10367Y1553080D03*
X12000Y1644980D03*
X26956Y4469D03*
X28317Y24773D03*
Y44773D03*
X24316Y67527D03*
Y63527D03*
Y59527D03*
X35638Y53597D03*
X33288Y109410D03*
Y116497D03*
X30788D03*
X25988D03*
X22439Y106495D03*
X35207Y106561D03*
X30788Y123584D03*
X33288Y123583D03*
X25988Y123584D03*
X33288Y130670D03*
X30788D03*
X25988D03*
X23184Y144728D03*
X29201Y151651D03*
X26201D03*
X20709Y175777D03*
X26565Y177448D03*
X34520Y213539D03*
X21530Y236121D03*
X27966Y238689D03*
X28740Y247292D03*
X33902Y244297D03*
X21449Y253198D03*
X28740Y267292D03*
X21386Y273198D03*
X37117Y279991D03*
X23479Y295619D03*
X35650Y487982D03*
Y478982D03*
Y483982D03*
Y499982D03*
Y491982D03*
X25819Y531726D03*
Y536726D03*
Y527726D03*
Y552726D03*
Y540726D03*
X32452Y581222D03*
X29652D03*
X35252D03*
Y591215D03*
X29652D03*
X32452D03*
X34254Y611091D03*
X29451Y633560D03*
X36692Y641817D03*
X30369Y663048D03*
X27625Y663094D03*
X25818Y682139D03*
X27854Y671553D03*
X30414Y671508D03*
X28818Y682139D03*
X36529Y1006321D03*
X30479Y1006509D03*
X24456Y1006401D03*
X32093Y1009748D03*
X26155Y1009985D03*
X29197Y1014205D03*
X32197Y1017759D03*
X26197D03*
X35197Y1014205D03*
X21196Y1065529D03*
Y1063029D03*
X36089Y1062601D03*
Y1065101D03*
X35925Y1075663D03*
X33425D03*
X28996Y1065529D03*
X23796D03*
X26396D03*
Y1063029D03*
X23796D03*
X28996D03*
X28606Y1082678D03*
X23406D03*
X26006D03*
Y1080178D03*
X23406D03*
X28606D03*
X20806Y1082678D03*
Y1080178D03*
X21321Y1098769D03*
X26521D03*
X29121D03*
X23921D03*
Y1101335D03*
X29121D03*
X26521D03*
X21321D03*
X32574Y1111633D03*
X29874D03*
X27274D03*
X24674D03*
Y1121333D03*
X27274D03*
X29874D03*
X32574D03*
X24674Y1130333D03*
X21974D03*
X21209Y1138705D03*
X23709D03*
X27934Y1204311D03*
X30934D03*
X30410Y1218497D03*
Y1220997D03*
X27934Y1215511D03*
X30934D03*
X34314Y1215403D03*
X27934Y1212711D03*
Y1209911D03*
Y1207111D03*
X30934Y1212711D03*
Y1209911D03*
Y1207111D03*
X30410Y1234797D03*
Y1232297D03*
Y1227897D03*
Y1225397D03*
Y1241697D03*
Y1239197D03*
X29860Y1438552D03*
X23603Y1449735D03*
X33189Y1501373D03*
X26231Y1554167D03*
X32000Y1644980D03*
X46450Y82984D03*
Y77784D03*
Y75184D03*
Y80384D03*
Y85584D03*
X45988Y90512D03*
X51550Y90615D03*
X37988Y109410D03*
X46240D03*
X45988Y102323D03*
X46240Y116496D03*
X37988Y102323D03*
Y116496D03*
X46931Y130670D03*
X49236Y121658D03*
X37988Y123583D03*
X52437Y137756D03*
X37988D03*
X45984Y163264D03*
X37284Y285272D03*
X42690Y451466D03*
X48596Y458466D03*
X41643Y473419D03*
X44563Y482165D03*
X39643Y555194D03*
X36843D03*
X49839Y546830D03*
X39643Y563194D03*
X36843D03*
X39643Y571194D03*
X36843D03*
X42192Y641817D03*
X51449Y822718D03*
X47949D03*
X48683Y1006510D03*
X42470Y1006738D03*
X50541Y1009589D03*
X44999Y1009510D03*
X38823Y1009273D03*
X47197Y1014205D03*
X41197D03*
X44197Y1017759D03*
X38197D03*
X48704Y1017982D03*
X43889Y1062601D03*
X38689D03*
X41289D03*
Y1065101D03*
X38689D03*
X43889D03*
X39659Y1105100D03*
X42259D03*
X44859D03*
X47559D03*
X48585Y1123867D03*
X47559Y1114800D03*
X44859D03*
X42259D03*
X39659D03*
X48547Y1133688D03*
X51047D03*
X44960Y1190619D03*
X49500Y1199066D03*
X49638Y1203884D03*
X51197Y1218206D03*
X39452Y1250932D03*
X47621Y1343672D03*
X48089Y1501387D03*
X39095Y1501361D03*
X47074Y1555923D03*
X40951Y1555932D03*
X52000Y1644980D03*
X55638Y53597D03*
X55871Y99961D03*
X55921Y95236D03*
X56098Y109410D03*
Y116496D03*
X55964Y103037D03*
X64098Y102323D03*
Y109410D03*
Y116496D03*
X56098Y130670D03*
X64098Y123583D03*
Y130670D03*
Y137756D03*
X65189Y228961D03*
Y231461D03*
Y223661D03*
Y226461D03*
X68896Y226141D03*
X54733Y231226D03*
Y228726D03*
Y223726D03*
Y226226D03*
X69139Y236611D03*
X68841Y248891D03*
X57987Y258880D03*
X58279Y293796D03*
X66293Y285690D03*
X68793D03*
X66293Y288190D03*
X68793D03*
X60779Y293796D03*
X65759Y437508D03*
X61759D03*
X57759D03*
X54936Y449352D03*
X59522Y448874D03*
X68619Y447269D03*
X68497Y450201D03*
X66224Y473045D03*
X58224D03*
X53643Y472905D03*
X62224Y473045D03*
X66371Y482134D03*
Y484634D03*
X59670Y500086D03*
X64550Y504699D03*
X62050D03*
X59550D03*
X68236Y519458D03*
X61752Y516979D03*
X64252D03*
X59252D03*
X60233Y521804D03*
X68202Y522129D03*
X64495Y527449D03*
X60233Y524304D03*
X56540Y531378D03*
Y528878D03*
X61695Y527449D03*
X68202Y527129D03*
Y524629D03*
Y529629D03*
X67622Y572842D03*
X64408Y572975D03*
X67684Y605637D03*
X62789Y608311D03*
X59684Y605443D03*
X63684D03*
X66510Y628242D03*
X55318Y629362D03*
X53129Y627948D03*
X55307Y688473D03*
X60849Y826818D03*
X64649D03*
X58949Y821018D03*
X64849Y840418D03*
X60249D03*
X68598Y859415D03*
X71528Y913190D03*
X59962Y910251D03*
X53197Y1014205D03*
Y1017759D03*
X55699Y1072761D03*
X58250Y1220896D03*
Y1227796D03*
Y1230296D03*
Y1237196D03*
Y1234696D03*
Y1223396D03*
X58443Y1272257D03*
X54843Y1501625D03*
X60227Y1514751D03*
X60277Y1528395D03*
X55862Y1541791D03*
X65478Y1541980D03*
X60303Y1534436D03*
X64747Y1555890D03*
X68743Y1583498D03*
X60864Y1583484D03*
X58064D03*
X55264D03*
X60554Y1615152D03*
X74432Y5374D03*
X73745Y24773D03*
Y44773D03*
X73381Y94017D03*
X69381D03*
X73110Y101701D03*
X77804Y95879D03*
X73509Y115401D03*
X78501D03*
X83911Y117557D03*
X73509Y129574D03*
Y124618D03*
X78501Y129574D03*
Y124618D03*
X83911Y122513D03*
Y131731D03*
Y136687D03*
X71422Y151540D03*
X75072Y191941D03*
X81572Y184619D03*
X74939Y188727D03*
X83552Y206760D03*
X73158Y229286D03*
X76851Y222212D03*
X71696Y226141D03*
X76851Y224712D03*
X74139Y236611D03*
X71639D03*
X73158Y231786D03*
X71341Y248891D03*
X73841D03*
X76766Y256535D03*
X80766Y256303D03*
X71593Y285690D03*
Y288190D03*
X75819Y290755D03*
X79819D03*
X83819D03*
X71826Y480705D03*
X74326D03*
X69816Y475946D03*
Y478446D03*
X78033Y478586D03*
Y481086D03*
Y476086D03*
Y483586D03*
X75736Y519458D03*
X73236D03*
X70736D03*
X71995Y532749D03*
X74795D03*
X75777Y585507D03*
X71184D03*
X71730Y579475D03*
X71228Y590145D03*
X75822Y590190D03*
X75684Y605443D03*
X83684D03*
X81740Y636250D03*
X69670Y633205D03*
Y636005D03*
X81740Y633450D03*
X69670Y638805D03*
X81740Y639050D03*
X78129Y656900D03*
X72314Y680207D03*
Y683407D03*
X82714Y674707D03*
X74414Y681907D03*
X72549Y838818D03*
X74028Y889065D03*
X83079Y888515D03*
X76203Y897910D03*
X84679Y1018368D03*
X77734Y1095676D03*
X71020Y1224323D03*
X76005Y1580680D03*
X82433Y1580590D03*
X82291Y1633801D03*
X78291D03*
X70291D03*
X72000Y1644980D03*
X93334Y3000D03*
X88080Y103603D03*
X88903Y117557D03*
Y122513D03*
Y131731D03*
Y136687D03*
X91224Y141247D03*
X92337Y144172D03*
X85904Y152367D03*
X103456Y157370D03*
X87604Y180572D03*
X92287Y180527D03*
X96010Y192421D03*
X92242Y185121D03*
X87604Y185165D03*
X103841Y228631D03*
X85796Y279208D03*
X89900Y281307D03*
X94390Y293645D03*
Y290845D03*
Y288345D03*
X91890Y293645D03*
Y290845D03*
Y288345D03*
X98255Y374510D03*
X100120Y377898D03*
X100066Y381976D03*
X93456Y649838D03*
X89432Y668293D03*
X92134D03*
X95539Y664443D03*
X85614Y674707D03*
X87714Y684607D03*
X88875Y840940D03*
X90000Y871389D03*
X91128Y1006487D03*
X99836Y997860D03*
X95836D03*
X88287Y1026537D03*
X97247Y1030568D03*
X103124Y1165091D03*
X92000Y1644980D03*
X113334Y3000D03*
X119582Y102249D03*
X107364Y113394D03*
Y110394D03*
X111582Y102249D03*
X110013Y110784D03*
X115582Y102249D03*
X110152Y130898D03*
X117607Y133298D03*
X111754Y134579D03*
X107540Y172665D03*
Y180665D03*
X117501Y198883D03*
X115382Y195176D03*
X112882D03*
X117882D03*
X117501Y201683D03*
X115242Y203393D03*
X112742D03*
X107572Y200864D03*
Y212864D03*
Y208864D03*
Y216864D03*
Y221864D03*
X109329Y252371D03*
X112474Y716315D03*
X114397Y727974D03*
X120250Y758841D03*
X113505Y796856D03*
X109591Y796905D03*
X103836Y997860D03*
X111836D03*
X111275Y1008262D03*
X114770Y1009354D03*
X107836Y997860D03*
X115836D03*
X111275Y1011762D03*
X105971Y1025745D03*
X108933Y1102091D03*
X112433D03*
X103124D03*
X102761Y1096233D03*
X112433Y1114691D03*
X103124D03*
X108933D03*
Y1127291D03*
X112433D03*
X103124D03*
X112433Y1139891D03*
X103124Y1152491D03*
X108933D03*
X112433D03*
X108933Y1165091D03*
X112433D03*
X103184Y1177691D03*
X108933D03*
X112433D03*
X112000Y1644980D03*
X129318Y4469D03*
X130679Y24773D03*
Y44773D03*
X133200Y95111D03*
X128350Y116497D03*
X133150D03*
X124606Y106495D03*
X125599Y109172D03*
X122599D03*
X133150Y123584D03*
X128350D03*
X133150Y130670D03*
X128350D03*
X122867Y125107D03*
X128350Y137757D03*
X133150D03*
X126246Y141228D03*
X124340Y146012D03*
X131481Y143762D03*
X129134Y150847D03*
X120682Y195176D03*
X118930Y206838D03*
X121430D03*
X124961Y228646D03*
X131102Y247292D03*
X130328Y238689D03*
X123892Y236121D03*
X120926Y238589D03*
X123811Y253198D03*
X126131Y359511D03*
X125753Y365856D03*
X118122Y747565D03*
X119099Y755052D03*
X118467Y796785D03*
X122437Y860775D03*
X125698Y857515D03*
X122432Y857540D03*
X129666Y857514D03*
X133424Y857303D03*
X123387Y892000D03*
X124079Y1009354D03*
X119836Y997860D03*
X131836D03*
X127836D03*
X123836D03*
X120579Y1009354D03*
Y1021954D03*
X124079D03*
X133870Y1105091D03*
X133579Y1097469D03*
X133870Y1117691D03*
Y1130291D03*
Y1142891D03*
Y1155491D03*
Y1168091D03*
X132000Y1644980D03*
X138000Y53597D03*
X148812Y80384D03*
Y82984D03*
Y75184D03*
Y77784D03*
Y85584D03*
X148600Y90650D03*
X148350Y95236D03*
X135650Y109410D03*
X148602D03*
Y116496D03*
X148350Y102323D03*
X140350Y116496D03*
Y109410D03*
Y102323D03*
X135650Y116497D03*
X137569Y106561D03*
X148774Y124576D03*
X149827Y130670D03*
X135650Y123583D03*
Y130670D03*
X140350D03*
Y123583D03*
X149822Y137756D03*
X140350D03*
X136882Y213539D03*
X138563Y238714D03*
X138664Y241699D03*
X146196Y390223D03*
X143186Y402291D03*
X138194Y397335D03*
X143186D03*
X146196Y395179D03*
Y404396D03*
Y409352D03*
X138194Y402291D03*
X140786Y416465D03*
Y411509D03*
X135794Y416465D03*
Y411509D03*
X146196Y418569D03*
Y423525D03*
X140786Y425682D03*
X135794D03*
Y430638D03*
X136862Y857244D03*
X139836Y997860D03*
X147836D03*
X143836D03*
X135836D03*
X145516Y1024954D03*
Y1012354D03*
X144640Y1039439D03*
X150952Y1040115D03*
X146595Y1053457D03*
X158000Y53597D03*
X151366Y92849D03*
X153912Y90615D03*
X158283Y95236D03*
X158233Y99961D03*
X158460Y116496D03*
X158326Y103037D03*
X158460Y109410D03*
X166460Y116496D03*
Y109410D03*
Y102323D03*
X158460Y130670D03*
Y123583D03*
X166460D03*
Y130670D03*
X155051Y137756D03*
X166460D03*
X157095Y228726D03*
Y231226D03*
X167551Y223661D03*
X157095Y226226D03*
Y223726D03*
X160349Y258880D03*
X163141Y293796D03*
X160641D03*
X166528Y312392D03*
X164496Y309405D03*
X151188Y390223D03*
Y395179D03*
Y404396D03*
Y409352D03*
Y418569D03*
X151836Y997860D03*
X159836D03*
X155836D03*
X153693Y1051037D03*
X160547Y1049283D03*
X160807Y1043955D03*
X159228Y1065613D03*
X152000Y1644980D03*
X176794Y5374D03*
X176107Y24773D03*
Y44773D03*
X175871Y110445D03*
X180863Y115401D03*
Y110445D03*
X175871Y115401D03*
X180863Y129574D03*
Y124618D03*
X175871Y129574D03*
Y124618D03*
X173784Y151540D03*
X177434Y191941D03*
X177301Y188727D03*
X175520Y229286D03*
X179213Y224712D03*
Y222212D03*
X171258Y226141D03*
X167551Y231461D03*
Y228961D03*
Y226461D03*
X174058Y226141D03*
X174001Y236611D03*
X176501D03*
X175520Y231786D03*
X171501Y236611D03*
X176203Y248891D03*
X173703D03*
X171203D03*
X179128Y256535D03*
X173955Y285690D03*
Y288190D03*
X171155Y285690D03*
X168655Y288190D03*
X171155D03*
X168655Y285690D03*
X182181Y290755D03*
X178181D03*
X170215Y311671D03*
X177369Y389154D03*
X172000Y1644980D03*
X195697Y3000D03*
X188820Y80140D03*
Y76140D03*
X191568Y76587D03*
Y72615D03*
X186026Y97475D03*
X186273Y117557D03*
X191265D03*
X197380Y112083D03*
X186273Y131731D03*
Y122513D03*
X191265D03*
Y131731D03*
X189364Y146461D03*
X186273Y136687D03*
X191265D03*
X193586Y141247D03*
X188266Y152367D03*
X194649Y180527D03*
X189966Y180572D03*
X198372Y192421D03*
X189966Y185165D03*
X194604Y185121D03*
X183934Y184619D03*
X185914Y206760D03*
X183128Y256303D03*
X188158Y279208D03*
X192262Y281307D03*
X196752Y293645D03*
Y290845D03*
Y288345D03*
X194252Y293645D03*
Y290845D03*
Y288345D03*
X186181Y290755D03*
X191988Y389154D03*
X185169D03*
X185622Y1465513D03*
Y1460782D03*
Y1480868D03*
Y1476137D03*
Y1470244D03*
Y1485599D03*
X192000Y1644980D03*
X211262Y60922D03*
X206398Y55513D03*
X208463Y96472D03*
X203591Y91951D03*
X209530Y86046D03*
X205976Y85731D03*
X209726Y113394D03*
Y110394D03*
X213944Y102249D03*
X212375Y110784D03*
X201669Y103621D03*
X211969Y133298D03*
X214116Y134579D03*
X205818Y157370D03*
X209902Y172665D03*
Y180665D03*
X215244Y195176D03*
X209934Y200864D03*
X215104Y203393D03*
X209934Y208864D03*
Y221864D03*
X206203Y228631D03*
X211691Y252371D03*
X212980Y390995D03*
Y405168D03*
Y394395D03*
X205680Y401482D03*
Y398082D03*
X212980Y408568D03*
Y419341D03*
Y422741D03*
X205680Y415655D03*
Y412255D03*
Y426428D03*
Y440602D03*
Y429828D03*
X212980Y433515D03*
Y436915D03*
X205680Y444002D03*
X212980Y469381D03*
Y472781D03*
X205680Y490641D03*
Y479868D03*
X212980Y483554D03*
X205680Y476468D03*
X212980Y486954D03*
X205680Y494041D03*
Y524002D03*
X212980Y516915D03*
Y513515D03*
X205680Y520602D03*
Y534775D03*
X212980Y527688D03*
X205680Y538175D03*
X212980Y531088D03*
X208540Y621591D03*
X213296Y1438215D03*
X215697Y3000D03*
X231681Y4469D03*
X221944Y102249D03*
X224961Y109172D03*
X226968Y106495D03*
X230712Y116497D03*
X217944Y102249D03*
X227961Y109172D03*
X230712Y123584D03*
Y130670D03*
X219969Y133298D03*
X225229Y125107D03*
X228608Y141228D03*
X230712Y137757D03*
X226702Y146012D03*
X231496Y150847D03*
X220244Y195176D03*
X219863Y198883D03*
X217744Y195176D03*
X223044D03*
X223792Y206838D03*
X219863Y201683D03*
X221292Y206838D03*
X217604Y203393D03*
X227323Y228646D03*
X226254Y236121D03*
X223288Y238589D03*
X226173Y253198D03*
X230842Y313888D03*
X233258Y359186D03*
X217945Y1423924D03*
X217799Y1433684D03*
X222253Y1438483D03*
X229260Y1469587D03*
X218171Y1474460D03*
X224176Y1492816D03*
X223235Y1506770D03*
X222908Y1502028D03*
X226957Y1510442D03*
X216342Y1515642D03*
X217519Y1537172D03*
X233042Y24773D03*
Y44773D03*
X240363Y53597D03*
X235562Y95111D03*
X242712Y116496D03*
Y109410D03*
Y102323D03*
X238012Y116497D03*
X235512D03*
X238012Y109410D03*
X239931Y106561D03*
X238012Y123583D03*
Y130670D03*
X235512D03*
X242712D03*
Y123583D03*
X235512Y123584D03*
Y137757D03*
X242712Y137756D03*
X233843Y143762D03*
X239244Y213539D03*
X232690Y238689D03*
X240925Y238714D03*
X233464Y247292D03*
X238626Y244297D03*
X234986Y336161D03*
X236264Y342494D03*
X247278Y618288D03*
X240194Y643113D03*
X244267Y696911D03*
X241204Y814841D03*
X237591Y815266D03*
X232675Y1466801D03*
X240466Y1503857D03*
X243268Y1501903D03*
X237700Y1531600D03*
X260363Y53597D03*
X251174Y77784D03*
Y80384D03*
Y82984D03*
Y75184D03*
Y85584D03*
X253728Y92849D03*
X250962Y90650D03*
X256274Y90615D03*
X260595Y99961D03*
X260645Y95236D03*
X250712D03*
X260688Y103037D03*
X250964Y109410D03*
X250712Y102323D03*
X250964Y116496D03*
X260822D03*
Y109410D03*
X251136Y124576D03*
X260822Y130670D03*
Y123583D03*
X252189Y130670D03*
X257413Y137756D03*
X252184D03*
X259457Y228726D03*
Y231226D03*
Y226226D03*
Y223726D03*
X262711Y258880D03*
X263003Y293796D03*
X257993Y307994D03*
X255000Y427017D03*
X254692Y431029D03*
X253758Y435029D03*
X254678Y445873D03*
X264005Y467337D03*
Y470737D03*
X256705Y474424D03*
X264005Y484910D03*
X256705Y488597D03*
X264005Y481510D03*
X256705Y477824D03*
Y491997D03*
X264005Y514871D03*
X256705Y518558D03*
X264005Y511471D03*
X256705Y521958D03*
Y532731D03*
Y536131D03*
X264005Y525644D03*
Y529044D03*
Y561510D03*
X256705Y571997D03*
Y568597D03*
X264005Y564910D03*
X256705Y586171D03*
X264005Y575684D03*
Y579084D03*
X256705Y582771D03*
X264005Y589857D03*
X256705Y600344D03*
X264005Y593257D03*
Y604030D03*
X256705Y596944D03*
Y611117D03*
Y614517D03*
X264005Y607430D03*
X248090Y691114D03*
X254634Y698241D03*
X248506Y812042D03*
X256303Y812254D03*
X254058Y819851D03*
X252305Y831018D03*
X248042Y1532900D03*
X279156Y5374D03*
X278469Y24773D03*
Y44773D03*
X268822Y116496D03*
Y109410D03*
X278233Y115401D03*
Y110445D03*
X268822Y102323D03*
Y130670D03*
Y123583D03*
X278233Y129574D03*
Y124618D03*
X268822Y137756D03*
X276146Y151540D03*
X279796Y191941D03*
X279663Y188727D03*
X269913Y228961D03*
Y226461D03*
X276420Y226141D03*
X269913Y223661D03*
X277882Y229286D03*
X273620Y226141D03*
X269913Y231461D03*
X276363Y236611D03*
X278863D03*
X277882Y231786D03*
X273863Y236611D03*
X276065Y248891D03*
X273565D03*
X278565D03*
X276317Y288190D03*
X273517Y285690D03*
X271017Y288190D03*
X273517D03*
X271017Y285690D03*
X265503Y293796D03*
X276317Y285690D03*
X277575Y395084D03*
X274425Y381500D03*
X265011Y410394D03*
X265945Y440098D03*
Y437598D03*
Y435098D03*
Y432598D03*
Y430098D03*
X274949Y442606D03*
X274866Y446606D03*
X276344Y467367D03*
X274096Y820725D03*
X274697Y830951D03*
X275123Y847874D03*
X272000Y1644980D03*
X294959Y11097D03*
X286129Y36971D03*
X291182Y80140D03*
Y76140D03*
X293930Y76587D03*
Y72615D03*
X288388Y97475D03*
X288635Y117557D03*
X283225Y115401D03*
Y110445D03*
X293627Y117557D03*
X288635Y131731D03*
Y122513D03*
X283225Y129574D03*
Y124618D03*
X293627Y122513D03*
Y131731D03*
X291726Y146461D03*
X293627Y136687D03*
X288635D03*
X295948Y141247D03*
X290628Y152367D03*
X292328Y180572D03*
Y185165D03*
X286296Y184619D03*
X288276Y206760D03*
X281575Y224712D03*
Y222212D03*
X281490Y256535D03*
X285490Y256303D03*
X290520Y279208D03*
X294624Y281307D03*
X296614Y293645D03*
Y290845D03*
Y288345D03*
X284543Y290755D03*
X280543D03*
X288543D03*
X284075Y381500D03*
X292500Y410394D03*
Y403307D03*
X284295Y430760D03*
X284316Y433570D03*
X284132Y437072D03*
X284173Y439963D03*
X293307Y451677D03*
X295807D03*
X293307Y454177D03*
X295807D03*
X280897Y1563544D03*
Y1558813D03*
Y1568275D03*
X289558Y1593853D03*
X280897Y1589522D03*
Y1594253D03*
Y1609607D03*
X289558Y1609207D03*
X280897Y1598984D03*
X289558Y1598584D03*
Y1603315D03*
X280897Y1604876D03*
Y1614338D03*
X289558Y1613938D03*
Y1618669D03*
X292000Y1644980D03*
X298059Y3000D03*
X309106Y37543D03*
X308760Y55513D03*
X310882Y96613D03*
X305953Y91951D03*
X308338Y85731D03*
X311892Y86046D03*
X312088Y113394D03*
X299742Y112083D03*
X304031Y103621D03*
X308180Y157370D03*
X297011Y180527D03*
X312264Y172665D03*
Y180665D03*
X299759Y190285D03*
X296966Y185121D03*
X312296Y212864D03*
Y200864D03*
Y208864D03*
Y221864D03*
Y216864D03*
X308565Y228631D03*
X299114Y290845D03*
Y288345D03*
Y293645D03*
X302966Y324139D03*
X310013Y316731D03*
X306812Y342319D03*
X301943Y332017D03*
X308952Y356875D03*
X312316Y356747D03*
X301158Y380307D03*
X309258Y389912D03*
Y393924D03*
Y385912D03*
X301308Y395346D03*
X301393Y400039D03*
X309258Y409924D03*
Y405924D03*
Y401924D03*
X306673Y418838D03*
X298220Y1589522D03*
Y1594253D03*
X306881Y1593853D03*
Y1598584D03*
Y1603315D03*
X298220Y1609607D03*
Y1604876D03*
Y1598984D03*
X306881Y1609207D03*
X298220Y1614338D03*
X306881Y1613938D03*
Y1618669D03*
X312000Y1644980D03*
X318059Y3000D03*
X313624Y60922D03*
X324306Y102249D03*
X320306D03*
X327323Y109172D03*
X316306Y102249D03*
X314737Y110784D03*
X314854Y130898D03*
X322331Y133298D03*
X327591Y125107D03*
X329064Y146012D03*
X316478Y134579D03*
X322225Y198883D03*
X322606Y195176D03*
X325406D03*
X320106D03*
X317606D03*
X323654Y206838D03*
X319966Y203393D03*
X322225Y201683D03*
X317466Y203393D03*
X326154Y206838D03*
X329685Y228646D03*
X325650Y238589D03*
X328616Y236121D03*
X328535Y253198D03*
X314053Y252371D03*
X323882Y303839D03*
X319857Y321649D03*
X318508Y324322D03*
X315944Y332584D03*
X318500Y356519D03*
X315310Y356712D03*
X321549Y445315D03*
Y448115D03*
X315543Y1589522D03*
Y1594253D03*
X324204Y1593853D03*
X315543Y1609607D03*
Y1604876D03*
Y1598984D03*
X324204Y1609207D03*
Y1598584D03*
Y1603315D03*
X315543Y1614338D03*
X324204Y1613938D03*
Y1618669D03*
X334043Y4469D03*
X330905Y11806D03*
X335404Y24773D03*
X330905Y23806D03*
Y31806D03*
X335404Y44773D03*
X342725Y53597D03*
X337924Y95111D03*
X329330Y106495D03*
X345074Y116496D03*
X337874Y116497D03*
X340374D03*
X345074Y109410D03*
Y102323D03*
X340374Y109410D03*
X333074Y116497D03*
X330323Y109172D03*
X342293Y106561D03*
X337874Y130670D03*
X345074D03*
Y123583D03*
X340374D03*
X337874Y123584D03*
X333074D03*
Y130670D03*
X340374D03*
X333074Y137757D03*
X337874D03*
X330970Y141228D03*
X345074Y137756D03*
X336205Y143762D03*
X333858Y150847D03*
X341606Y213539D03*
X335052Y238689D03*
X343287Y238714D03*
X338768Y246874D03*
X340988Y244297D03*
X345050Y458334D03*
Y454334D03*
X339251Y1138130D03*
X335190Y1173065D03*
X342009Y1176100D03*
X335502Y1188222D03*
X332865Y1589522D03*
Y1594253D03*
X341527Y1593853D03*
X332865Y1598984D03*
X341527Y1609207D03*
Y1598584D03*
Y1603315D03*
X332865Y1609607D03*
Y1604876D03*
X341527Y1613938D03*
Y1618669D03*
X332865Y1614338D03*
X332000Y1644980D03*
X353536Y82984D03*
Y80384D03*
Y77784D03*
Y75184D03*
X356090Y92849D03*
X353536Y85584D03*
X358636Y90615D03*
X353324Y90650D03*
X362957Y99961D03*
X353074Y95236D03*
Y102323D03*
X353326Y109410D03*
Y116496D03*
X353498Y124576D03*
X354551Y130670D03*
X359525Y137756D03*
X354546D03*
X359376Y290592D03*
X348351Y319372D03*
X348806Y315427D03*
X351132Y322202D03*
X349120Y336100D03*
X348737Y375386D03*
X354486Y377173D03*
X357173Y392183D03*
X357218Y396866D03*
X361234Y402867D03*
X358042Y442518D03*
Y439718D03*
X347450Y447486D03*
X358207Y836462D03*
X349700Y1148000D03*
X357947Y1159455D03*
X352536Y1160168D03*
X357083Y1185205D03*
X361792Y1187310D03*
X348432Y1187215D03*
X360523Y1192282D03*
X360659Y1209789D03*
X350188Y1594253D03*
Y1589522D03*
Y1604876D03*
Y1609607D03*
Y1598984D03*
Y1614338D03*
X352000Y1644980D03*
X362725Y53597D03*
X363007Y95236D03*
X363050Y103037D03*
X363184Y116496D03*
Y109410D03*
X371184Y116496D03*
Y109410D03*
Y102323D03*
X363184Y130670D03*
Y123583D03*
X371184Y130670D03*
Y123583D03*
Y137756D03*
X372275Y226461D03*
X375982Y226141D03*
X361819Y231226D03*
Y228726D03*
Y223726D03*
Y226226D03*
X372275Y228961D03*
Y231461D03*
Y223661D03*
X378782Y226141D03*
X376225Y236611D03*
X375927Y248891D03*
X365073Y258880D03*
X365365Y293796D03*
X367865D03*
X373379Y288190D03*
X375879Y285690D03*
X373379D03*
X375879Y288190D03*
X364933Y374232D03*
X373264Y370010D03*
X361767Y392228D03*
X376992Y395248D03*
X368587Y409016D03*
X364551Y409032D03*
X361811Y396866D03*
X375919Y449118D03*
Y446318D03*
X364954Y450091D03*
X367919Y449118D03*
Y446318D03*
X376099Y458309D03*
Y454309D03*
X367564Y452740D03*
X376099Y462309D03*
X369282Y468088D03*
Y465288D03*
X366443Y472189D03*
X365332Y490070D03*
Y487570D03*
X373504Y517954D03*
X373703Y782555D03*
X365691Y815127D03*
X371507Y815303D03*
X362042Y814772D03*
X368067Y925136D03*
X368626Y931346D03*
X368964Y937738D03*
X372858Y935136D03*
X366761Y934550D03*
X370101Y953699D03*
X365748Y1134325D03*
X366133Y1162817D03*
X366429Y1185238D03*
X365029Y1214158D03*
X362735Y1211864D03*
X369839Y1218940D03*
X367816Y1310586D03*
Y1315542D03*
X372000Y1644980D03*
X388059Y3000D03*
X381518Y5374D03*
X388487Y24069D03*
X380831Y24773D03*
Y44773D03*
X393544Y76140D03*
Y80140D03*
X390750Y97475D03*
X390997Y117557D03*
X385587Y115401D03*
X380595D03*
X385587Y110445D03*
X380595D03*
X390997Y131731D03*
Y122513D03*
X385587Y129574D03*
X380595D03*
X385587Y124618D03*
X380595D03*
X390997Y136687D03*
X382158Y191941D03*
X388658Y184619D03*
X382025Y188727D03*
X390638Y206760D03*
X380244Y229286D03*
X383937Y222212D03*
Y224712D03*
X381225Y236611D03*
X378725D03*
X380244Y231786D03*
X378427Y248891D03*
X380927D03*
X383852Y256535D03*
X387852Y256303D03*
X392882Y279208D03*
X378679Y285690D03*
Y288190D03*
X386905Y290755D03*
X382905D03*
X390905D03*
X389237Y371070D03*
X385237Y370976D03*
X391737Y377581D03*
X396373Y407104D03*
X392444Y401949D03*
X393893Y413611D03*
X393833Y423944D03*
X385584Y450041D03*
Y452841D03*
Y455641D03*
X393837Y466409D03*
X393646Y474382D03*
X393823Y487382D03*
X393652Y482382D03*
X393746Y478382D03*
X385131Y487382D03*
X388593Y664232D03*
X386350Y693559D03*
X391478Y690675D03*
X391470Y732865D03*
X380963Y731000D03*
X380331Y782627D03*
X380607Y786932D03*
X387958Y813700D03*
X381631Y814147D03*
X384666Y814103D03*
X383391Y804000D03*
X383462Y860535D03*
X386614Y868286D03*
X391614Y938651D03*
X385512Y955356D03*
X390150Y955312D03*
Y959905D03*
X385467Y959950D03*
X378410Y1131573D03*
X380261Y1129692D03*
X386415Y1321645D03*
X391691Y1326715D03*
X394000Y1508100D03*
X381900Y1544800D03*
X382017Y1559700D03*
X392000Y1644980D03*
X408059Y3000D03*
X400714Y45448D03*
X404686D03*
X395989Y117557D03*
X402104Y112083D03*
X406393Y103621D03*
X395989Y131731D03*
Y122513D03*
Y136687D03*
X399373Y180527D03*
X394690Y180572D03*
X403096Y192421D03*
X394690Y185165D03*
X399328Y185121D03*
X410927Y228631D03*
X396986Y281307D03*
X398976Y293645D03*
X401476D03*
Y288345D03*
Y290845D03*
X398976Y288345D03*
Y290845D03*
X400728Y353152D03*
X394237Y370899D03*
X396373Y409904D03*
X409268Y408240D03*
X406843Y399161D03*
Y401661D03*
Y396661D03*
X394944Y398949D03*
X399518Y402642D03*
X402018D03*
X396633Y423944D03*
X409386Y420393D03*
X396693Y413611D03*
X399193D03*
X401693D03*
X401633Y423944D03*
X399133D03*
X395577Y455641D03*
Y450041D03*
Y452841D03*
X397315Y479560D03*
X405603Y668060D03*
X408103D03*
X403103D03*
X400603D03*
Y678060D03*
X405603D03*
X408103D03*
X403103D03*
X409284Y741316D03*
X400900Y755400D03*
X400914Y762675D03*
X408300Y755487D03*
X400900Y770100D03*
X407965Y770196D03*
X402376Y842677D03*
X399876D03*
X402376Y850677D03*
X399876D03*
X396306Y864409D03*
X406967Y878764D03*
X406415Y874840D03*
X407193Y883566D03*
X401121Y936686D03*
X409121Y939186D03*
X401121D03*
X409121Y936686D03*
X396182Y955858D03*
X402682Y948536D03*
X402815Y951750D03*
X399285Y1081599D03*
X398915Y1097278D03*
X396415D03*
X409231Y1123101D03*
X406105Y1139435D03*
X410131Y1129301D03*
X407631D03*
X409231Y1125801D03*
X406105Y1131935D03*
Y1134435D03*
Y1136935D03*
Y1141935D03*
Y1146935D03*
Y1144435D03*
X403263Y1152684D03*
X406319Y1204405D03*
X404004Y1198321D03*
Y1200821D03*
X406319Y1206905D03*
Y1211905D03*
Y1209405D03*
X404324Y1271889D03*
X397695Y1287071D03*
X404324Y1275889D03*
X399716Y1295198D03*
X398584Y1313443D03*
X408159Y1349072D03*
X404759D03*
X403029Y1379716D03*
X403111Y1384920D03*
X408212Y1379695D03*
X394657Y1377875D03*
X403111Y1390103D03*
X408212Y1390083D03*
X410152Y1410928D03*
X398112Y1403741D03*
X401711Y1419771D03*
X406667D03*
X401990Y1446807D03*
X399731Y1442755D03*
X407469Y1495035D03*
X407854Y1492118D03*
X406377Y1499142D03*
X397245Y1511640D03*
X404053Y1513673D03*
X397220Y1521207D03*
X400911Y1537902D03*
X407048D03*
X400911Y1544424D03*
X407048Y1549936D03*
X400911D03*
X397461Y1569560D03*
X401461D03*
X420050Y33425D03*
X414145Y27486D03*
X413904Y32569D03*
X426147Y151540D03*
X414626Y180665D03*
Y172665D03*
X414658Y212864D03*
Y200864D03*
Y208864D03*
Y216864D03*
Y221864D03*
X422873Y309966D03*
X419955Y306966D03*
X414999D03*
X422988Y323627D03*
X415129Y325181D03*
X412671Y333418D03*
X416318Y367903D03*
X424479Y367859D03*
X418876Y401661D03*
Y396661D03*
X411768Y408240D03*
X414268D03*
X418876Y399161D03*
X411847Y424240D03*
X414386Y420393D03*
X411886D03*
X411847Y426740D03*
X415453Y455039D03*
X418754Y468607D03*
X411754Y474513D03*
X424731Y508152D03*
Y513452D03*
Y515952D03*
X414275Y508217D03*
Y510717D03*
Y515717D03*
Y513217D03*
X424731Y510952D03*
X419040Y533690D03*
Y528390D03*
Y530990D03*
Y536290D03*
Y538890D03*
X423266Y631438D03*
X420266D03*
X417666D03*
X420266Y637038D03*
Y634238D03*
X417666Y637038D03*
Y634238D03*
X423266Y637038D03*
Y634238D03*
X418226Y653288D03*
X423266Y642638D03*
X420266D03*
X417666D03*
X423266Y639838D03*
X420266D03*
X418226Y646480D03*
Y648980D03*
X417666Y639838D03*
X418226Y655788D03*
X410603Y668060D03*
Y678060D03*
X415700Y755400D03*
X415696Y762466D03*
X415700Y770200D03*
X422430Y834800D03*
X424649Y842644D03*
X422149D03*
Y850644D03*
X424649D03*
X422149Y858644D03*
X424649D03*
X425759Y869921D03*
Y872721D03*
Y875521D03*
Y867121D03*
X422379Y867229D03*
X425759Y878321D03*
X411214Y892109D03*
X425062Y883981D03*
X425121Y936686D03*
Y939186D03*
X417121Y936686D03*
Y939186D03*
X417677Y1052215D03*
X425175Y1098767D03*
X417171Y1098887D03*
X419987Y1098518D03*
X416988Y1104792D03*
X419731Y1123101D03*
X417231D03*
X422631Y1125801D03*
X425131Y1129301D03*
X422631D03*
X420131D03*
X417631D03*
X415131D03*
X412631D03*
X420131Y1125801D03*
X417631D03*
X425131D03*
X422495Y1152713D03*
Y1155213D03*
X412095Y1152713D03*
Y1155213D03*
X422934Y1200821D03*
Y1198321D03*
X420619Y1204617D03*
X417469Y1200821D03*
Y1198321D03*
X420619Y1207117D03*
Y1209617D03*
Y1212117D03*
X411174Y1282776D03*
X418537Y1300197D03*
X423741Y1300115D03*
X413354Y1300197D03*
X425582Y1291743D03*
X414280Y1362561D03*
X413437Y1379736D03*
Y1384899D03*
X425283Y1373958D03*
X413395Y1390062D03*
X411147Y1474993D03*
X419818Y1474945D03*
X415241Y1492990D03*
X415095Y1502750D03*
X411353Y1519440D03*
X419467Y1519706D03*
X420279Y1525978D03*
X410626Y1525991D03*
X413012Y1537902D03*
Y1544098D03*
X426196Y1534087D03*
X413012Y1549936D03*
X421616Y1549885D03*
X417461Y1569584D03*
X412000Y1644980D03*
X428059Y3000D03*
X441727Y146461D03*
X440629Y152367D03*
X435703Y306966D03*
X430747D03*
X427829Y309966D03*
X430361Y323187D03*
X443424Y332988D03*
X428420Y353578D03*
X435886Y353867D03*
X435702Y367813D03*
X430746D03*
X433724Y433975D03*
X432310Y436164D03*
X427782Y464026D03*
X442704Y506427D03*
X427693Y506520D03*
X438396Y511493D03*
X438353Y508685D03*
X427693Y509020D03*
X432700Y516277D03*
X435834Y509580D03*
X428740Y533690D03*
X442704Y533790D03*
X428740Y528390D03*
Y530990D03*
X442704Y528490D03*
Y531090D03*
X428740Y536290D03*
X431804Y536682D03*
X428740Y538890D03*
X431804Y539182D03*
X442704Y536390D03*
X439804Y536682D03*
X442704Y538990D03*
X439804Y539182D03*
X436369Y622883D03*
X441832Y626193D03*
X441612Y631011D03*
X429210Y784833D03*
X432303Y785067D03*
X428759Y869921D03*
Y867121D03*
Y872721D03*
Y875521D03*
Y878321D03*
X432332Y892049D03*
Y897649D03*
Y894849D03*
Y900449D03*
X433206Y1055498D03*
X430706D03*
Y1057998D03*
X433206D03*
Y1060498D03*
Y1062998D03*
X430706D03*
Y1060498D03*
X429677Y1106955D03*
X441359Y1123101D03*
X431476Y1118396D03*
X438233Y1139435D03*
X441359Y1125801D03*
X439759Y1129301D03*
X442259D03*
X429331Y1136935D03*
Y1134435D03*
Y1139435D03*
Y1131935D03*
X435733D03*
Y1134435D03*
Y1136935D03*
Y1139435D03*
X438233Y1131935D03*
Y1134435D03*
Y1136935D03*
X429348Y1129092D03*
X429331Y1141935D03*
X435733D03*
Y1146935D03*
Y1144435D03*
X438233Y1141935D03*
Y1146935D03*
Y1144435D03*
X437231Y1154902D03*
Y1152402D03*
X429331Y1146935D03*
Y1144435D03*
X427231Y1162384D03*
X433249Y1204405D03*
X430934Y1200821D03*
Y1198321D03*
X433249Y1209405D03*
Y1211905D03*
Y1206905D03*
X437991Y1286544D03*
X434424Y1286274D03*
X431885Y1313115D03*
X436002Y1382252D03*
X437675Y1550158D03*
X430657Y1563562D03*
X429784Y1548222D03*
X432000Y1644980D03*
X448059Y3000D03*
X445949Y141247D03*
X458181Y157370D03*
X443480Y344014D03*
X453463Y370694D03*
X448092Y375770D03*
X448391Y382641D03*
X446179Y447101D03*
X453544Y461961D03*
X451144Y472809D03*
X443094Y491251D03*
X452404Y533690D03*
Y528390D03*
Y530990D03*
X455104Y536582D03*
X452404Y536290D03*
X455104Y539082D03*
X452404Y538890D03*
X447279Y633881D03*
X448726Y653288D03*
Y646480D03*
Y648980D03*
Y655788D03*
X447836Y711199D03*
X460498Y870334D03*
X454815Y974622D03*
X448999Y994483D03*
X456210Y1004680D03*
X452319Y1000828D03*
X449731Y1000855D03*
X453270Y1003763D03*
X453710Y1018825D03*
X443091Y1022766D03*
Y1030266D03*
X450063Y1043140D03*
X443091Y1034266D03*
X449767Y1047047D03*
X450244Y1090268D03*
X457303Y1098767D03*
X452115Y1098518D03*
X446863Y1098428D03*
X450244Y1093068D03*
X449116Y1104792D03*
X449359Y1123101D03*
X451859D03*
X457259Y1129301D03*
X449759Y1125801D03*
X452259D03*
X444759Y1129301D03*
X447259D03*
X449759D03*
X452259D03*
X454759Y1125801D03*
X457259D03*
X454759Y1129301D03*
X443223Y1155213D03*
Y1152713D03*
X452623D03*
Y1155213D03*
X457559Y1162384D03*
X447549Y1204617D03*
X449864Y1198321D03*
Y1200821D03*
X447549Y1209617D03*
Y1207117D03*
Y1212117D03*
X454120Y1269498D03*
X456213Y1286776D03*
X451304Y1293045D03*
X456832Y1299121D03*
X454385Y1301845D03*
Y1305245D03*
X454125Y1574167D03*
Y1589522D03*
Y1604876D03*
X452000Y1644980D03*
X468059Y3000D03*
X474307Y102249D03*
X464738Y110784D03*
X462089Y113394D03*
X470307Y102249D03*
X466307D03*
X472332Y133298D03*
X464332D03*
X477592Y125107D03*
X466479Y134579D03*
X470107Y195176D03*
X467607D03*
X472607D03*
X472226Y198883D03*
X475407Y195176D03*
X473655Y206838D03*
X467467Y203393D03*
X469967D03*
X472226Y201683D03*
X467335Y359944D03*
X469530Y366754D03*
X470796Y394592D03*
X468558Y491669D03*
Y503669D03*
Y507669D03*
Y512669D03*
X463104Y536582D03*
X468850Y537507D03*
X463104Y539082D03*
X461849Y668016D03*
X459349D03*
X466849D03*
X469349D03*
X464349D03*
X469349Y678016D03*
X466849D03*
X459349D03*
X461849D03*
X464349D03*
X462242Y809792D03*
X463404Y846870D03*
X465492Y861970D03*
X471726Y883705D03*
X467494Y924532D03*
X474540Y927341D03*
X471110Y921577D03*
X471068Y930235D03*
X473992Y952546D03*
X475018Y992568D03*
X467345Y996480D03*
X469495Y1011303D03*
Y1023303D03*
Y1017303D03*
X462427Y1030218D03*
X460277Y1090268D03*
Y1093068D03*
X462913Y1106365D03*
X474818Y1123101D03*
X463604Y1118396D03*
X469192Y1131935D03*
X474818Y1125801D03*
X473218Y1129301D03*
X461459Y1136935D03*
Y1134435D03*
Y1139435D03*
Y1131935D03*
X471692Y1139435D03*
Y1136935D03*
Y1134435D03*
Y1131935D03*
X469192Y1139435D03*
Y1136935D03*
Y1134435D03*
X471692Y1146935D03*
Y1141935D03*
X469192Y1144435D03*
Y1146935D03*
Y1141935D03*
X471692Y1144435D03*
X461459D03*
X462687Y1152684D03*
X468850D03*
X461459Y1141935D03*
Y1146935D03*
X465785Y1197471D03*
X461285Y1193471D03*
Y1197471D03*
X465785Y1193471D03*
X463216Y1254164D03*
Y1250760D03*
Y1244055D03*
X474647Y1260160D03*
Y1257160D03*
X471647D03*
Y1260160D03*
X461613Y1286776D03*
X459290Y1297035D03*
X463290D03*
X462786Y1578498D03*
X471448Y1574167D03*
X462786Y1593853D03*
X471448Y1589522D03*
X462786Y1609207D03*
X471448Y1604876D03*
X472000Y1644980D03*
X484043Y4469D03*
X485404Y24773D03*
Y44773D03*
X487925Y95111D03*
X480324Y109172D03*
X477324D03*
X479331Y106495D03*
X483075Y116497D03*
X487875D03*
X490375Y109410D03*
Y116497D03*
X483075Y130670D03*
X487875Y123584D03*
Y130670D03*
X490375Y123583D03*
Y130670D03*
X483075Y123584D03*
X479065Y146012D03*
X480971Y141228D03*
X483075Y137757D03*
X487875D03*
X486206Y143762D03*
X483859Y150847D03*
X476155Y206838D03*
X491607Y213539D03*
X479686Y228646D03*
X478617Y236121D03*
X475651Y238589D03*
X485053Y238689D03*
X490989Y244297D03*
X492736Y491982D03*
X482905Y527726D03*
Y544726D03*
X486738Y581222D03*
X489538D03*
Y591215D03*
X486738D03*
X491340Y611091D03*
X484772Y625311D03*
X485005Y659771D03*
X491324Y667293D03*
X483059Y662649D03*
X485303Y681841D03*
X489572Y822805D03*
X479448Y828594D03*
X477574Y860815D03*
X490706Y859339D03*
X491616Y938771D03*
X476475Y952249D03*
X479613Y952189D03*
X489163Y977163D03*
X490143Y989521D03*
X481495Y1011303D03*
X475495D03*
X480711Y999941D03*
X477857Y1004375D03*
X481495Y1023303D03*
Y1017303D03*
X475495Y1023303D03*
X476148Y1057998D03*
Y1055498D03*
X478648D03*
Y1057998D03*
X476148Y1060498D03*
Y1062998D03*
X478648D03*
Y1060498D03*
X490762Y1098767D03*
X485574Y1098518D03*
X480322Y1098428D03*
X482575Y1104792D03*
X485318Y1123101D03*
X482818D03*
X490718Y1129301D03*
X483218Y1125801D03*
X485718D03*
X475718Y1129301D03*
X478218D03*
X480718D03*
X483218D03*
X485718D03*
X488218Y1125801D03*
X490718D03*
X488218Y1129301D03*
X477682Y1152713D03*
Y1155213D03*
X488082D03*
Y1152713D03*
X477206Y1198321D03*
X490671D03*
Y1200821D03*
X479521Y1204405D03*
X477206Y1200821D03*
X479521Y1206905D03*
Y1211905D03*
Y1209405D03*
X489647Y1260160D03*
Y1257160D03*
X486647D03*
Y1260160D03*
X480647Y1257160D03*
X477647D03*
Y1260160D03*
X480647D03*
X483647Y1257160D03*
Y1260160D03*
X480109Y1578498D03*
X488771Y1574167D03*
Y1589522D03*
X480109Y1593853D03*
X488771Y1604876D03*
X480109Y1609207D03*
X492725Y53597D03*
X503537Y77784D03*
Y75184D03*
Y80384D03*
Y82984D03*
X506091Y92849D03*
X503537Y85584D03*
X503325Y90650D03*
X508637Y90615D03*
X503075Y95236D03*
Y102323D03*
X503327Y109410D03*
Y116496D03*
X495075D03*
Y102323D03*
Y109410D03*
X492294Y106561D03*
X495075Y130670D03*
Y123583D03*
X506653Y121652D03*
X504552Y130670D03*
X504547Y137756D03*
X495075D03*
X493288Y238714D03*
X497424Y354559D03*
X492317Y376252D03*
X493485Y439903D03*
X503682Y455466D03*
X497776Y448466D03*
X496729Y470419D03*
X501649Y482165D03*
X506925Y546830D03*
X493929Y555194D03*
X496729D03*
X493929Y563194D03*
X496729D03*
X493929Y571194D03*
X496729D03*
X492338Y581222D03*
Y591215D03*
X499278Y641817D03*
X493778D03*
X494632Y654622D03*
X496070Y665976D03*
X501618Y698355D03*
X499012Y699819D03*
X503311Y715652D03*
X500705Y705524D03*
X507546Y738539D03*
X504508Y783817D03*
X504641Y789139D03*
X494677Y830468D03*
X509665Y824512D03*
X503383Y863025D03*
X498507Y865392D03*
X494315Y941212D03*
X503144Y957934D03*
X493050Y976078D03*
X506566Y1000766D03*
Y1004766D03*
X498524Y997590D03*
X506566Y1016266D03*
Y1030766D03*
X505981Y1052487D03*
X496372Y1106298D03*
X506946Y1123101D03*
X497063Y1118396D03*
X506946Y1125801D03*
X505346Y1129301D03*
X507846D03*
X503820Y1139435D03*
Y1136935D03*
Y1134435D03*
Y1131935D03*
X501320Y1139435D03*
Y1136935D03*
Y1134435D03*
Y1131935D03*
X494918Y1136935D03*
Y1134435D03*
Y1139435D03*
Y1131935D03*
X503820Y1144435D03*
Y1146935D03*
Y1141935D03*
X501320Y1144435D03*
Y1146935D03*
Y1141935D03*
X494918Y1146935D03*
Y1144435D03*
Y1141935D03*
X502562Y1152713D03*
Y1155213D03*
X492818Y1162384D03*
X506451Y1204405D03*
X504136Y1198321D03*
Y1200821D03*
X493821Y1204617D03*
X496136Y1200821D03*
Y1198321D03*
X506451Y1206905D03*
Y1211905D03*
Y1209405D03*
X493821Y1207117D03*
Y1209617D03*
Y1212117D03*
X504647Y1257160D03*
X507347D03*
X501647D03*
Y1260160D03*
X495647D03*
X492647D03*
Y1257160D03*
X495647D03*
X498647D03*
Y1260160D03*
X507347D03*
X504647D03*
X497432Y1578498D03*
X506093Y1574167D03*
Y1589522D03*
X497432Y1593853D03*
X506093Y1604876D03*
X497432Y1609207D03*
X492000Y1644980D03*
X512725Y53597D03*
X512958Y99961D03*
X513008Y95236D03*
X513051Y103037D03*
X513185Y116496D03*
Y109410D03*
X521185Y116496D03*
Y109410D03*
Y102323D03*
X513185Y130670D03*
Y123583D03*
X521185Y130670D03*
Y123583D03*
X509251Y137756D03*
X521185D03*
X522276Y223661D03*
Y226461D03*
Y228961D03*
Y231461D03*
X511820Y231226D03*
Y228726D03*
Y223726D03*
Y226226D03*
X515074Y258880D03*
X517866Y293796D03*
X515366D03*
X523380Y285690D03*
Y288190D03*
X514769Y312953D03*
X519638Y314346D03*
X511790Y313804D03*
X520845Y434508D03*
X516845D03*
X512845D03*
X514608Y445874D03*
X510022Y446352D03*
X523705Y444269D03*
X523583Y447201D03*
X508729Y469905D03*
X521310Y470045D03*
X513310D03*
X517310D03*
X523457Y482134D03*
Y484634D03*
X521636Y504699D03*
X516636D03*
X519136D03*
X516756Y500086D03*
X517319Y521804D03*
X516338Y516979D03*
X521338D03*
X518838D03*
X513626Y528578D03*
Y531378D03*
X518781Y527449D03*
X517319Y524304D03*
X521581Y527449D03*
X521494Y572975D03*
X519875Y608311D03*
X523596Y628242D03*
X512404Y629362D03*
X510215Y627948D03*
X518812Y665867D03*
X511990Y686365D03*
X518001Y694940D03*
X522410Y694881D03*
X518067Y699378D03*
X518530Y703584D03*
X522628Y703884D03*
X508237Y723585D03*
X512502Y738539D03*
X516953Y738575D03*
X521909D03*
X513504Y755804D03*
X520833Y773389D03*
X513551Y773203D03*
X522697Y797102D03*
X525159Y913818D03*
X516902Y910251D03*
X520146Y939241D03*
X523289Y939195D03*
X509471Y981608D03*
X514690Y996766D03*
Y1004766D03*
X514649Y1020266D03*
X514843Y1030766D03*
X519500Y1028377D03*
X515831Y1090568D03*
X517702Y1098518D03*
X512450Y1098428D03*
X515831Y1093068D03*
X522890Y1098767D03*
X514703Y1104792D03*
X514946Y1123101D03*
X517446D03*
X522846Y1129301D03*
X515346Y1125801D03*
X517846D03*
X510346Y1129301D03*
X512846D03*
X515346D03*
X517846D03*
X520346Y1125801D03*
X522846D03*
X520346Y1129301D03*
X518210Y1155213D03*
Y1152713D03*
X508810D03*
Y1155213D03*
X523146Y1162384D03*
X520751Y1204617D03*
X523066Y1200821D03*
Y1198321D03*
X520751Y1207117D03*
Y1209617D03*
Y1212117D03*
X514755Y1578498D03*
Y1593853D03*
Y1609207D03*
X512000Y1644980D03*
X531518Y5374D03*
X530831Y24773D03*
Y44773D03*
X540751Y97475D03*
X530596Y115401D03*
X535588Y110445D03*
Y115401D03*
X530596Y110445D03*
Y124618D03*
Y129574D03*
X535588Y124618D03*
Y129574D03*
X528509Y151540D03*
X538659Y184619D03*
X532159Y191941D03*
X532026Y188727D03*
X530245Y229286D03*
X528783Y226141D03*
X525983D03*
X533938Y222212D03*
Y224712D03*
X526226Y236611D03*
X531226D03*
X528726D03*
X530245Y231786D03*
X528428Y248891D03*
X530928D03*
X533853Y256535D03*
X525928Y248891D03*
X537853Y256303D03*
X525880Y285690D03*
X528680D03*
X525880Y288190D03*
X528680D03*
X532906Y290755D03*
X536906D03*
X540906D03*
X524206Y354119D03*
X533027Y351836D03*
X530215Y364422D03*
X535142Y397552D03*
X535119Y483886D03*
Y481086D03*
Y478586D03*
X526902Y478446D03*
Y475946D03*
X531412Y480705D03*
X535119Y476086D03*
X528612Y480705D03*
X532936Y519544D03*
X525288Y522129D03*
X527936Y519544D03*
X525436D03*
X530436D03*
X525288Y524629D03*
Y527129D03*
Y529929D03*
X529481Y532849D03*
X532281D03*
X524708Y572842D03*
X532863Y585507D03*
X528270D03*
X528816Y579475D03*
X532908Y590190D03*
X528314Y590145D03*
X532770Y605443D03*
X538826Y633450D03*
X526756Y636005D03*
Y633205D03*
X538826Y636250D03*
Y639050D03*
X526756Y638805D03*
X524653Y643595D03*
X533486Y664052D03*
X538442D03*
X524941Y661387D03*
X530796D03*
X534940Y684489D03*
X539111Y681459D03*
X526956Y694959D03*
X526951Y699443D03*
X535387Y712617D03*
X526933Y703820D03*
X532628Y720776D03*
X526276Y721339D03*
X539763Y734097D03*
X534807D03*
X531763Y739097D03*
X526807D03*
X532450Y767474D03*
X542275Y760782D03*
X532278Y762736D03*
X524598Y753387D03*
X531313Y826630D03*
X538468Y888033D03*
X530968Y888283D03*
X533143Y897910D03*
X531076Y913190D03*
X528500Y1106365D03*
X529191Y1118396D03*
X527046Y1131935D03*
Y1139435D03*
Y1134435D03*
Y1136935D03*
X528274Y1152684D03*
X527046Y1146935D03*
Y1144435D03*
Y1141935D03*
X532000Y1644980D03*
X550421Y3000D03*
X543545Y80140D03*
Y76140D03*
X546293Y76587D03*
Y72615D03*
X540998Y117557D03*
X545990D03*
X552105Y112083D03*
X556394Y103621D03*
X545990Y122513D03*
Y131731D03*
X540998Y122513D03*
Y131731D03*
X544089Y146461D03*
X545990Y136687D03*
X540998D03*
X548311Y141247D03*
X542991Y152367D03*
X549374Y180527D03*
X544691Y180572D03*
X553097Y192421D03*
X549329Y185121D03*
X544691Y185165D03*
X540639Y206760D03*
X542883Y279208D03*
X546987Y281307D03*
X551477Y288345D03*
Y290845D03*
X548977Y288345D03*
Y290845D03*
Y293645D03*
X551477D03*
X541644Y389047D03*
X541706Y381723D03*
X540770Y605443D03*
X543101Y698772D03*
X552384Y762892D03*
X552188Y766577D03*
X556326Y793743D03*
X550087Y829836D03*
X556326Y829989D03*
X557836Y851669D03*
X546940Y871389D03*
X552923Y997860D03*
X552000Y1644980D03*
X570421Y3000D03*
X566287Y60922D03*
X561123Y55513D03*
X563224Y96813D03*
X558316Y91951D03*
X560701Y85731D03*
X564255Y86046D03*
X567100Y110784D03*
X564451Y113394D03*
X572669Y102249D03*
X568669D03*
X567290Y130898D03*
X568841Y134579D03*
X560543Y157370D03*
X564627Y180665D03*
Y172665D03*
X569969Y195176D03*
X572469D03*
X572329Y203393D03*
X574588Y201683D03*
X564659Y200864D03*
X569829Y203393D03*
X564659Y208864D03*
X560928Y228631D03*
X566416Y252371D03*
X570634Y375453D03*
X558616Y732530D03*
X562001Y732834D03*
X564276Y776701D03*
X564165Y894411D03*
X560923Y988813D03*
X564923Y997860D03*
X560923D03*
X568923D03*
X556923D03*
X568362Y1008262D03*
X571857Y1009354D03*
X568362Y1011762D03*
X569349Y1541947D03*
X560635Y1543531D03*
X566800Y1541800D03*
X586405Y4469D03*
X587766Y24773D03*
Y44773D03*
X576669Y102249D03*
X582686Y109172D03*
X579686D03*
X581693Y106495D03*
X585437Y116497D03*
X574694Y133298D03*
X585437Y123584D03*
Y130670D03*
X579954Y125107D03*
X581427Y146012D03*
X583333Y141228D03*
X585437Y137757D03*
X588568Y143762D03*
X586221Y150847D03*
X574969Y195176D03*
X577769D03*
X574588Y198883D03*
X578517Y206838D03*
X576017D03*
X582048Y228646D03*
X587415Y238689D03*
X588189Y247292D03*
X580979Y236121D03*
X578013Y238589D03*
X580898Y253198D03*
X578193Y336391D03*
X584679Y336285D03*
X576556Y728219D03*
X575979Y732517D03*
X582737Y819831D03*
X581158Y823473D03*
X580327Y892000D03*
X586136Y908935D03*
X583065Y903294D03*
X573895Y965319D03*
X580923Y997860D03*
X576923D03*
X588923D03*
X577666Y1009354D03*
X581166D03*
X572923Y997860D03*
X584923D03*
X587880Y1034834D03*
X587467Y1117691D03*
X581967D03*
X587467Y1130291D03*
X581967D03*
X587467Y1142891D03*
X581967Y1155491D03*
X587467D03*
X581967Y1142891D03*
Y1168091D03*
X587467D03*
X581967Y1180691D03*
X587467D03*
X587689Y1505724D03*
X583661Y1529142D03*
X573784Y1530646D03*
X575332Y1523740D03*
X583800Y1518000D03*
X583740Y1520640D03*
X587858Y1517942D03*
X577645Y1540982D03*
X580700Y1544100D03*
X595087Y53597D03*
X605687Y90650D03*
X590287Y95111D03*
X592737Y109410D03*
X590237Y116497D03*
X592737D03*
X597437Y102323D03*
Y109410D03*
Y116496D03*
X594656Y106561D03*
X597437Y123583D03*
Y130670D03*
X592737Y123583D03*
X590237Y123584D03*
Y130670D03*
X592737D03*
X597437Y137756D03*
X590237Y137757D03*
X593969Y213539D03*
X595650Y238714D03*
X593351Y244297D03*
X592900Y309871D03*
X603282Y390223D03*
X600272Y397335D03*
X603282Y395179D03*
Y404396D03*
Y409352D03*
X595280Y402291D03*
X600272D03*
X595280Y397335D03*
X592880Y416465D03*
Y411509D03*
X603282Y418569D03*
Y423525D03*
X597872Y425682D03*
X592880D03*
X597872Y416465D03*
Y411509D03*
X592880Y430638D03*
X592272Y877262D03*
X592110Y895611D03*
X601084Y913544D03*
X604715Y914640D03*
X602385Y940920D03*
X597556Y965829D03*
X602484Y965764D03*
X596923Y997860D03*
X592923D03*
X604923D03*
X600923D03*
X602603Y1012354D03*
Y1024954D03*
X606434Y1041904D03*
X603682Y1053457D03*
X592978Y1514812D03*
X591858Y1523542D03*
X598800Y1546400D03*
X615087Y53597D03*
X605899Y80384D03*
Y82984D03*
Y77784D03*
Y75184D03*
X608453Y92849D03*
X605899Y85584D03*
X610999Y90615D03*
X615370Y95236D03*
X615320Y99961D03*
X605437Y95236D03*
X615413Y103037D03*
X605437Y102323D03*
X605689Y109410D03*
Y116496D03*
X615547D03*
Y109410D03*
X605861Y124576D03*
X615547Y130670D03*
Y123583D03*
X606914Y130670D03*
X606909Y137756D03*
X612138D03*
X614182Y223726D03*
Y226226D03*
Y231226D03*
Y228726D03*
X617436Y258880D03*
X617728Y293796D03*
X620228D03*
X608274Y390223D03*
Y395179D03*
Y404396D03*
Y409352D03*
Y418569D03*
X612489Y941024D03*
X608965Y966414D03*
X616923Y997860D03*
X608923D03*
X612923D03*
X620151Y1040363D03*
X607993Y1036920D03*
X610780Y1051037D03*
X617634Y1049283D03*
X617894Y1043955D03*
X612955Y1062941D03*
X612000Y1644980D03*
X633248Y44884D03*
X632958Y110445D03*
X623547Y109410D03*
Y116496D03*
X632958Y115401D03*
X623547Y102323D03*
X632958Y124618D03*
X623547Y123583D03*
Y130670D03*
X632958Y129574D03*
X623547Y137756D03*
X630871Y151540D03*
X634521Y191941D03*
X634388Y188727D03*
X624638Y231461D03*
X636300Y222212D03*
Y224712D03*
X632607Y229286D03*
X624638Y223661D03*
X631145Y226141D03*
X624638Y226461D03*
X628345Y226141D03*
X624638Y228961D03*
X633588Y236611D03*
X631088D03*
X632607Y231786D03*
X628588Y236611D03*
X630790Y248891D03*
X633290D03*
X628290D03*
X636215Y256535D03*
X631042Y288190D03*
Y285690D03*
X625742Y288190D03*
X628242Y285690D03*
X625742D03*
X628242Y288190D03*
X635268Y290755D03*
X634455Y389154D03*
Y396240D03*
X622270Y864781D03*
X627354Y1604876D03*
X636015Y1609207D03*
X627354Y1609607D03*
X636015Y1618669D03*
Y1613938D03*
X627354Y1614338D03*
X632000Y1644980D03*
X645907Y76140D03*
Y80140D03*
X648655Y76587D03*
Y72615D03*
X643113Y97475D03*
X643360Y117557D03*
X637950Y110445D03*
Y115401D03*
X648352Y117557D03*
X643360Y122513D03*
Y131731D03*
X637950Y124618D03*
Y129574D03*
X648352Y122513D03*
Y131731D03*
X646451Y146461D03*
X643360Y136687D03*
X648352D03*
X650673Y141247D03*
X645353Y152367D03*
X647053Y180572D03*
X651736Y180527D03*
X651691Y185121D03*
X647053Y185165D03*
X641021Y184619D03*
X643001Y206760D03*
X640215Y256303D03*
X645245Y279208D03*
X649349Y281307D03*
X651339Y290845D03*
Y293645D03*
X653839D03*
X639268Y290755D03*
X643268D03*
X653839Y288345D03*
Y290845D03*
X651339Y288345D03*
X642255Y389154D03*
X649074D03*
X653338Y1609207D03*
X644677Y1604876D03*
Y1609607D03*
X653338Y1613938D03*
X644677Y1614338D03*
X653338Y1618669D03*
X652000Y1644980D03*
X668649Y60922D03*
X666209Y57297D03*
X665423Y96853D03*
X660678Y91951D03*
X663063Y85731D03*
X666617Y86046D03*
X658756Y103621D03*
X666813Y113394D03*
X669462Y110784D03*
X654467Y112083D03*
X669056Y133298D03*
X662905Y157370D03*
X666989Y172665D03*
Y180665D03*
X655459Y192421D03*
X667021Y200864D03*
Y208864D03*
Y221864D03*
Y216864D03*
X663290Y228631D03*
X668778Y252371D03*
X670066Y390995D03*
Y405168D03*
X662766Y398082D03*
X670066Y408568D03*
Y394395D03*
X662766Y401482D03*
X670066Y422741D03*
Y419341D03*
X662766Y415655D03*
Y426428D03*
Y412255D03*
Y440602D03*
X670066Y433515D03*
X662766Y429828D03*
X670066Y436915D03*
X662766Y444002D03*
X670066Y469381D03*
Y472781D03*
X662766Y476468D03*
Y490641D03*
X670066Y483554D03*
Y486954D03*
X662766Y479868D03*
Y494041D03*
X670066Y516915D03*
X662766Y520602D03*
Y524002D03*
X670066Y513515D03*
Y527688D03*
X662766Y534775D03*
X670066Y531088D03*
X662766Y538175D03*
X662000Y1604876D03*
Y1609607D03*
Y1614338D03*
X679031Y102249D03*
X682048Y109172D03*
X685048D03*
X684055Y106495D03*
X677056Y133298D03*
X682316Y125107D03*
X671203Y134579D03*
X683789Y146012D03*
X685695Y141228D03*
X672331Y195176D03*
X674831D03*
X677331D03*
X676950Y198883D03*
X680131Y195176D03*
X672191Y203393D03*
X676950Y201683D03*
X674691Y203393D03*
X678379Y206838D03*
X680879D03*
X684410Y228646D03*
X680375Y238589D03*
X683341Y236121D03*
X683260Y253198D03*
X682857Y339477D03*
X679322Y1604876D03*
Y1609607D03*
X670661Y1609207D03*
X679322Y1614338D03*
X670661Y1618669D03*
Y1613938D03*
X672000Y1644980D03*
X690073Y44662D03*
X697387Y53619D03*
X692649Y95111D03*
X695099Y109410D03*
X687799Y116497D03*
X692599D03*
X695099D03*
X699799Y116496D03*
Y109410D03*
Y102323D03*
X697018Y106561D03*
X687799Y123584D03*
X695099Y123583D03*
X692599Y123584D03*
X687799Y130670D03*
X692599D03*
X695099D03*
X699799Y123583D03*
Y130670D03*
X687799Y137757D03*
X692599D03*
X699799Y137756D03*
X690930Y143762D03*
X688583Y150847D03*
X696331Y213539D03*
X698012Y238714D03*
X689777Y238689D03*
X690551Y247292D03*
X695713Y244297D03*
X689486Y339583D03*
X696645Y1609607D03*
X687984Y1609207D03*
X696645Y1604876D03*
X687984Y1613938D03*
X696645Y1614338D03*
X687984Y1618669D03*
X692000Y1644980D03*
X717387Y53619D03*
X708261Y82984D03*
Y80384D03*
Y77784D03*
Y75184D03*
X710815Y92849D03*
X708261Y85584D03*
X708049Y90650D03*
X713361Y90615D03*
X717732Y95236D03*
X717682Y99961D03*
X707799Y95236D03*
X717775Y103037D03*
X707799Y102323D03*
X708051Y109410D03*
Y116496D03*
X717909D03*
Y109410D03*
X708223Y124576D03*
X717909Y130670D03*
Y123583D03*
X709276Y130670D03*
X714500Y137756D03*
X709271D03*
X716544Y228726D03*
Y231226D03*
Y226226D03*
Y223726D03*
X718338Y305272D03*
X713162Y434493D03*
X711764Y449873D03*
X713791Y474424D03*
Y488597D03*
Y477824D03*
Y491997D03*
Y518558D03*
Y521958D03*
Y536131D03*
Y532731D03*
Y571997D03*
Y568597D03*
Y582771D03*
Y586171D03*
Y596944D03*
Y600344D03*
Y611117D03*
Y614517D03*
X712901Y821600D03*
X712000Y1644980D03*
X725909Y102323D03*
Y116496D03*
Y109410D03*
Y130670D03*
Y123583D03*
Y137756D03*
X733233Y151540D03*
X736750Y188727D03*
X727000Y228961D03*
X730707Y226141D03*
X727000Y226461D03*
X733507Y226141D03*
X727000Y223661D03*
X734969Y229286D03*
X727000Y231461D03*
X733450Y236611D03*
X730950D03*
X734969Y231786D03*
X733152Y248891D03*
X730652D03*
X719798Y258880D03*
X733404Y285690D03*
X720090Y293796D03*
X722590D03*
X728104Y288190D03*
X730604Y285690D03*
X728104D03*
X730604Y288190D03*
X733404D03*
X731511Y390500D03*
X734606Y379562D03*
X734661Y393633D03*
X731511Y381113D03*
X722097Y410394D03*
Y403307D03*
X723031Y440098D03*
Y437598D03*
Y435098D03*
Y432598D03*
Y430098D03*
X723491Y458406D03*
Y451319D03*
X723315Y462264D03*
X721091Y470737D03*
Y467337D03*
X733430Y467367D03*
X721091Y484910D03*
Y481510D03*
Y514871D03*
Y511471D03*
Y525644D03*
Y529044D03*
Y561510D03*
Y564910D03*
Y579084D03*
Y575684D03*
Y593257D03*
Y604030D03*
Y589857D03*
Y607430D03*
X723177Y728219D03*
X722600Y869600D03*
X736452Y890548D03*
X719661Y904900D03*
X722789Y927095D03*
X722400Y942500D03*
X725194Y942073D03*
X720271Y931730D03*
X732306Y942682D03*
X728846Y948331D03*
X733798Y950186D03*
X727116Y959326D03*
X729600Y1625165D03*
X732000Y1644980D03*
X736242Y5374D03*
X735555Y24773D03*
Y44773D03*
X748269Y76140D03*
Y80140D03*
X751017Y76587D03*
Y72615D03*
X745475Y97475D03*
X750714Y117557D03*
X745722D03*
X740312Y115401D03*
Y110445D03*
X735320D03*
Y115401D03*
X745722Y131731D03*
Y122513D03*
X740312Y129574D03*
Y124618D03*
X735320D03*
Y129574D03*
X750714Y131731D03*
Y122513D03*
Y136687D03*
X745722D03*
X748813Y146461D03*
X747715Y152367D03*
X749415Y180572D03*
Y185165D03*
X743383Y184619D03*
X736883Y191941D03*
X745363Y206760D03*
X738662Y224712D03*
Y222212D03*
X735950Y236611D03*
X735652Y248891D03*
X738577Y256535D03*
X742577Y256303D03*
X747607Y279208D03*
X751711Y281307D03*
X741630Y290755D03*
X737630D03*
X745630D03*
X741161Y381500D03*
X749586Y410394D03*
Y403307D03*
X741259Y439963D03*
X741381Y430760D03*
X741402Y433570D03*
X741218Y437072D03*
X741503Y443180D03*
X741523Y454744D03*
X741465Y452018D03*
X749402Y458406D03*
X741568Y460250D03*
X749439Y1458777D03*
X740530Y1524113D03*
X751140Y1581335D03*
X740640Y1586885D03*
X748924Y1617709D03*
X735878Y1617010D03*
X747590Y1627871D03*
X755145Y3000D03*
X765847Y55513D03*
X763040Y91951D03*
X765425Y85731D03*
X756829Y112083D03*
X761118Y103621D03*
X753035Y141247D03*
X765267Y157370D03*
X754098Y180527D03*
X757821Y192421D03*
X754053Y185121D03*
X769383Y208864D03*
X763653Y224536D03*
X756201Y288345D03*
Y290845D03*
X753701Y288345D03*
Y290845D03*
Y293645D03*
X756201D03*
X760407Y324494D03*
X767099Y316731D03*
X763898Y342319D03*
X759029Y332017D03*
X766344Y393924D03*
Y389912D03*
Y385912D03*
X758038Y381143D03*
X766344Y409924D03*
Y405924D03*
Y401924D03*
X752341Y407148D03*
X756800Y403824D03*
X758381Y395391D03*
X759543Y445787D03*
X755593Y445908D03*
X755035Y1443524D03*
X765713Y1437365D03*
X760398Y1440276D03*
X766433Y1583713D03*
X759802Y1590864D03*
X763542Y1590186D03*
X767310Y1599164D03*
X756358Y1616917D03*
X752150Y1627871D03*
X762776Y1629415D03*
X752000Y1644980D03*
X775145Y3000D03*
X771011Y60922D03*
X781393Y102249D03*
X767929Y96890D03*
X768979Y86046D03*
X771824Y110784D03*
X777393Y102249D03*
X773393D03*
X769175Y113394D03*
X779418Y133298D03*
X771960Y130898D03*
X784678Y125107D03*
X773565Y134579D03*
X769351Y172665D03*
Y180665D03*
X779693Y195176D03*
X779312Y198883D03*
X777193Y195176D03*
X782493D03*
X774693D03*
X780741Y206838D03*
X783241D03*
X777053Y203393D03*
X779312Y201683D03*
X774553Y203393D03*
X769383Y200864D03*
X782737Y238589D03*
X771140Y252371D03*
X780968Y303839D03*
X776943Y321649D03*
X772990Y336324D03*
X772162Y332584D03*
X777569Y353506D03*
X778985Y442498D03*
X778881Y446510D03*
X779029Y450510D03*
X780575Y471484D03*
X775584Y466528D03*
X780575D03*
X775583Y471484D03*
X780575Y480701D03*
X775583D03*
Y485657D03*
X780575D03*
X783469Y1424655D03*
X768910Y1437741D03*
X768812Y1453306D03*
X777033Y1595215D03*
X781124Y1583553D03*
X781545Y1602835D03*
X774658Y1601012D03*
X777059Y1608982D03*
X784046Y1600438D03*
X778045Y1622545D03*
X782289Y1620109D03*
X773822Y1627418D03*
X771383Y1616917D03*
X772000Y1644980D03*
X791129Y4469D03*
X792490Y24773D03*
Y44773D03*
X799811Y53597D03*
X795011Y95111D03*
X784410Y109172D03*
X787410D03*
X794961Y116497D03*
X797461D03*
X790161D03*
X786417Y106495D03*
X797461Y109410D03*
X799380Y106561D03*
X797461Y123583D03*
X794961Y123584D03*
X790161D03*
X794961Y130670D03*
X797461D03*
X790161D03*
X794961Y137757D03*
X790161D03*
X788057Y141228D03*
X786151Y146012D03*
X793221Y140296D03*
X793292Y143762D03*
X790945Y150847D03*
X798693Y213539D03*
X786772Y228646D03*
X792913Y247292D03*
X792139Y238689D03*
X785703Y236121D03*
X798075Y244297D03*
X785622Y253198D03*
X788522Y290304D03*
X786461Y293028D03*
X790280Y287421D03*
X799937Y347340D03*
X795445Y356950D03*
X792564Y406410D03*
X784586Y421000D03*
Y418500D03*
Y413500D03*
Y416000D03*
X785985Y473640D03*
X790977D03*
X785985Y487813D03*
X790977D03*
X785985Y478596D03*
X790977D03*
X785985Y492769D03*
X790977D03*
X792277Y1173065D03*
X799020Y1175975D03*
X792382Y1191664D03*
X795296Y1416995D03*
X792848Y1414718D03*
X793459Y1429165D03*
X789647Y1427518D03*
X788648Y1422044D03*
X785820Y1425993D03*
X786787Y1433800D03*
X797318Y1471242D03*
X787447Y1593586D03*
X791610Y1593708D03*
X793564Y1642682D03*
X810623Y77784D03*
Y82984D03*
Y80384D03*
Y75184D03*
X813177Y92849D03*
X810623Y85584D03*
X810411Y90650D03*
X815723Y90615D03*
X810161Y95236D03*
Y102323D03*
X810413Y109410D03*
Y116496D03*
X802161D03*
Y109410D03*
Y102323D03*
X810585Y124576D03*
X811638Y130670D03*
X802161D03*
Y123583D03*
X811633Y137756D03*
X802161D03*
X800374Y238714D03*
X809466Y310604D03*
X804536Y441486D03*
X802136Y452334D03*
X810756Y491118D03*
Y488618D03*
Y483618D03*
X816364Y486870D03*
X810756Y486118D03*
X813864Y486870D03*
X815500Y824000D03*
X817884Y915425D03*
X814160Y1178240D03*
X814170Y1185205D03*
X805519Y1187215D03*
X804458Y1193112D03*
X812901Y1432804D03*
X815901D03*
X810059Y1432778D03*
X812104Y1426483D03*
X809986Y1438785D03*
X812986D03*
X815986D03*
X809986Y1441485D03*
X812986D03*
X815986D03*
X812901Y1435504D03*
X815901D03*
X810001D03*
X806874Y1447457D03*
X812474D03*
X806874Y1452587D03*
Y1457717D03*
X812474D03*
X815096Y1464387D03*
X812009Y1473432D03*
Y1470432D03*
X815096Y1467387D03*
X812096Y1479587D03*
Y1476587D03*
X815096Y1473387D03*
Y1479587D03*
Y1476587D03*
Y1470387D03*
X804919Y1489247D03*
X811457Y1639797D03*
X819811Y53597D03*
X820094Y95236D03*
X820044Y99961D03*
X820137Y103037D03*
X820271Y116496D03*
Y109410D03*
X828271Y116496D03*
Y109410D03*
Y102323D03*
X820271Y130670D03*
Y123583D03*
X828271Y130670D03*
Y123583D03*
X816637Y137756D03*
X828271D03*
X829362Y231461D03*
Y228961D03*
Y226461D03*
Y223661D03*
X818906Y228726D03*
Y231226D03*
Y226226D03*
Y223726D03*
X822160Y258880D03*
X824952Y293796D03*
X822452D03*
X830466Y285690D03*
Y288190D03*
X825792Y305225D03*
X825971Y345101D03*
X829381Y348036D03*
X824650Y446740D03*
X822040Y444091D03*
X826262Y462326D03*
Y459326D03*
X823529Y467189D03*
X818973Y491258D03*
Y488758D03*
X822418Y485070D03*
Y482570D03*
X823890Y703415D03*
X823670Y710542D03*
X824387Y726246D03*
X818307Y724144D03*
X821582Y727140D03*
X830484Y738750D03*
X822608Y848526D03*
X831583Y853454D03*
X823900Y882083D03*
X824804Y898395D03*
X829848Y914211D03*
X825336Y916774D03*
X831057Y916745D03*
X824414Y939655D03*
X824168Y949538D03*
X832423Y964669D03*
X830356Y1116251D03*
X827856D03*
X823220Y1170767D03*
X818879Y1187310D03*
X823516Y1185238D03*
X823608Y1208993D03*
X824901Y1427404D03*
X827901D03*
X821901D03*
X818901Y1430104D03*
X821901D03*
X830901D03*
X827901D03*
X824901D03*
Y1432804D03*
X827901D03*
X830901D03*
X821901D03*
X818901D03*
X824901Y1435504D03*
X827901D03*
X821901D03*
X818901D03*
X821986Y1441485D03*
X818986D03*
Y1438785D03*
X821986D03*
X817974Y1447457D03*
Y1452587D03*
Y1457717D03*
X818096Y1464387D03*
X821096D03*
X818096Y1473387D03*
X821096D03*
X824096D03*
X818096Y1479587D03*
X821096D03*
X824096D03*
X818096Y1476587D03*
X821096D03*
X824096D03*
X818096Y1467387D03*
Y1470387D03*
X821096D03*
Y1467387D03*
X824096D03*
Y1470387D03*
X831457Y1639797D03*
X838606Y5374D03*
X837919Y24773D03*
Y44773D03*
X847837Y97475D03*
X837682Y110445D03*
Y115401D03*
X848084Y117557D03*
X842674Y115401D03*
Y110445D03*
Y129574D03*
Y124618D03*
X837682D03*
Y129574D03*
X848084Y131731D03*
Y122513D03*
Y136687D03*
X839112Y188727D03*
X839245Y191941D03*
X845745Y184619D03*
X847725Y206760D03*
X837331Y229286D03*
X841024Y224712D03*
Y222212D03*
X833069Y226141D03*
X835869D03*
X835812Y236611D03*
X838312D03*
X833312D03*
X837331Y231786D03*
X833014Y248891D03*
X840939Y256535D03*
X838014Y248891D03*
X835514D03*
X844939Y256303D03*
X832966Y288190D03*
Y285690D03*
X835766Y288190D03*
Y285690D03*
X843992Y290755D03*
X839992D03*
X847992D03*
X839573Y325327D03*
X842240Y324854D03*
X833185Y456309D03*
Y452309D03*
Y448309D03*
X850732Y469382D03*
X835236Y533174D03*
X838152Y700215D03*
X845850Y710969D03*
X845784Y708089D03*
X835987Y713745D03*
X846484Y738750D03*
X836713Y738751D03*
X842661Y769521D03*
X846000Y772079D03*
X835553Y835119D03*
X848384Y839459D03*
X848739Y847459D03*
X845820Y863413D03*
X843574Y859423D03*
X837434Y851459D03*
X845820Y867413D03*
X848384Y871459D03*
Y875459D03*
X836909Y916618D03*
Y914018D03*
X848045Y1019310D03*
X848070Y1022190D03*
X836704Y1448849D03*
X850145Y3000D03*
X850631Y80140D03*
Y76140D03*
X853379Y76587D03*
Y72615D03*
X853076Y117557D03*
X859191Y112083D03*
X863480Y103621D03*
X853076Y131731D03*
Y122513D03*
Y136687D03*
X851777Y180572D03*
X856460Y180527D03*
X860183Y192421D03*
X851777Y185165D03*
X856415Y185121D03*
X866015Y224536D03*
X849969Y279208D03*
X854073Y281307D03*
X858563Y293645D03*
Y290845D03*
X856063Y293645D03*
Y290845D03*
X858563Y288345D03*
X856063D03*
X854622Y359004D03*
X854086Y385000D03*
X858586D03*
X857973Y404867D03*
X862522Y400229D03*
X862566Y404867D03*
X857928Y400184D03*
X862020Y410899D03*
X850733Y461382D03*
X850832Y473382D03*
X850738Y477382D03*
X850909Y482382D03*
X858169Y495032D03*
X867093Y570703D03*
Y582828D03*
X853900Y627700D03*
X853989Y630453D03*
Y632953D03*
X859441Y678015D03*
X855646Y692710D03*
X857986Y722670D03*
X859199Y744517D03*
X854484Y738633D03*
X853282Y789887D03*
X857632Y789385D03*
X851184Y839459D03*
X859603Y863570D03*
X859461Y859459D03*
X859463Y866125D03*
X851184Y879459D03*
X850800Y883500D03*
X858601Y934505D03*
X853030Y934690D03*
X851925Y951350D03*
X850686Y1006923D03*
X853449Y1007048D03*
X863334Y1009393D03*
X861047Y1018909D03*
X860887Y1023208D03*
Y1026762D03*
X863956Y1020763D03*
X863689Y1024974D03*
X863342Y1120636D03*
X855542D03*
X858142D03*
X860842D03*
X863442Y1130336D03*
X858242D03*
X855642D03*
X860942D03*
Y1139336D03*
X863442D03*
X861119Y1148080D03*
X863619D03*
X863944Y1432359D03*
Y1429359D03*
X860944Y1432359D03*
X857944Y1429359D03*
X860944D03*
Y1426359D03*
X857944D03*
X863944D03*
X857944Y1432359D03*
X863944Y1435359D03*
Y1441359D03*
Y1438359D03*
X860944Y1441359D03*
X857944Y1435359D03*
X860944D03*
X857944Y1441359D03*
Y1438359D03*
X860944D03*
X859071Y1447459D03*
X864671D03*
X859071Y1452589D03*
Y1457719D03*
X864671D03*
X864644Y1464759D03*
X861644D03*
X855644D03*
X858644D03*
Y1467759D03*
X855644Y1470759D03*
X858644D03*
X864644Y1467759D03*
Y1470759D03*
X861644Y1467759D03*
Y1470759D03*
X855644Y1467759D03*
Y1473759D03*
X858644D03*
X864644D03*
X861644D03*
X855644Y1476759D03*
X858644D03*
X864644D03*
X861644D03*
X851457Y1639797D03*
X873373Y60922D03*
X868209Y55513D03*
X867787Y85731D03*
X870395Y96738D03*
X865402Y91951D03*
X871341Y86046D03*
X871713Y172665D03*
Y180665D03*
X871826Y186778D03*
X871745Y200864D03*
Y208864D03*
X876622Y293721D03*
X872050Y302644D03*
X873262Y300030D03*
X879112Y302369D03*
X873885Y340892D03*
X873733Y357844D03*
X871382Y373971D03*
X872736Y383125D03*
X880736D03*
X872318Y408589D03*
X866128Y417532D03*
X869342Y417399D03*
X880910Y471982D03*
Y469182D03*
Y466382D03*
X875907Y486256D03*
X878382Y554942D03*
X867093Y558703D03*
Y562703D03*
Y566703D03*
Y578703D03*
X881476Y588202D03*
X881131Y577349D03*
X872862Y666859D03*
X878881Y667156D03*
X874142Y748914D03*
X875473Y742056D03*
X878670Y742841D03*
X870209Y949384D03*
X865973Y978187D03*
X874066Y977928D03*
X875391Y993796D03*
X872183Y993980D03*
X878976Y994020D03*
X871069Y1023114D03*
X878927Y1022387D03*
X878783Y1018751D03*
X872845Y1018988D03*
X866906Y1018751D03*
X866887Y1023208D03*
X875887D03*
X878887Y1026762D03*
X872887D03*
X866887D03*
X869741Y1025895D03*
X873824Y1071604D03*
X871224D03*
X876424D03*
Y1074104D03*
X871224D03*
X873824D03*
X868624Y1071604D03*
Y1074104D03*
X870057Y1091604D03*
X875257D03*
Y1089104D03*
X870057D03*
X872657D03*
X880115Y1084666D03*
X867457Y1091604D03*
Y1089104D03*
X872657Y1091604D03*
X875375Y1107647D03*
X872675D03*
X870075D03*
X867475D03*
X871364Y1120636D03*
X873964D03*
X876564D03*
X879264D03*
X875376Y1110175D03*
X872676D03*
X870076D03*
X867476D03*
X871364Y1139336D03*
X868664D03*
X879264Y1130336D03*
X876564D03*
X873964D03*
X871364D03*
X871624Y1213314D03*
X874624D03*
X871624Y1221714D03*
Y1218914D03*
Y1216114D03*
X874624Y1221714D03*
Y1218914D03*
Y1216114D03*
X872440Y1230083D03*
Y1227583D03*
X871624Y1224514D03*
X874624D03*
X872440Y1234483D03*
Y1236983D03*
X878004Y1224406D03*
X872440Y1243883D03*
Y1241383D03*
Y1248283D03*
Y1250783D03*
X883142Y1259935D03*
X875700Y1299700D03*
X872944Y1432359D03*
Y1429359D03*
Y1426359D03*
X869944Y1432359D03*
Y1429359D03*
Y1426359D03*
X866944Y1432359D03*
Y1429359D03*
Y1426359D03*
X872944Y1435359D03*
Y1441359D03*
Y1438359D03*
X869944Y1435359D03*
X866944D03*
X869944Y1441359D03*
Y1438359D03*
X866944Y1441359D03*
Y1438359D03*
X870171Y1447459D03*
Y1452589D03*
Y1457719D03*
X867644Y1464759D03*
X870644D03*
X867644Y1467759D03*
X870644D03*
X867644Y1470759D03*
X870644D03*
X867644Y1473759D03*
X870644D03*
X867644Y1476759D03*
X870644D03*
X871457Y1639797D03*
X886011Y154100D03*
X895780Y237517D03*
Y232634D03*
X891383Y243203D03*
X896034Y243307D03*
X892484Y260860D03*
X896953Y272012D03*
X895140Y265236D03*
X886059Y284644D03*
X885918Y289500D03*
X886026Y346584D03*
X888812Y357372D03*
X883552Y357276D03*
X896592Y362369D03*
Y366369D03*
Y370369D03*
X884736Y383125D03*
X888736D03*
X894844Y418983D03*
X889219Y426952D03*
X887770Y415290D03*
X891699Y420445D03*
X890270Y415290D03*
X891699Y423245D03*
X897344Y418983D03*
X894519Y426952D03*
X889596Y437264D03*
X896388Y437614D03*
X887096Y437264D03*
X892019Y426952D03*
X897019D03*
X890903Y469182D03*
Y471982D03*
Y466382D03*
X882907Y480350D03*
X896431Y534093D03*
X882891Y536122D03*
X885931Y534093D03*
X896449Y550863D03*
X893949Y550363D03*
X886549Y553963D03*
X892023Y570176D03*
X890959Y579788D03*
X890956Y588325D03*
X894015Y588253D03*
X891673Y600049D03*
X895933Y618143D03*
X887949Y608863D03*
X894449Y606363D03*
X895933Y609696D03*
X893241Y704656D03*
X891916Y799605D03*
X895916Y808965D03*
X883916D03*
X895829Y800660D03*
X888628Y918042D03*
X882763Y933472D03*
X888400Y994579D03*
X894660Y994330D03*
X891343Y994378D03*
X885099Y1021685D03*
X881887Y1023208D03*
X888743Y1019931D03*
X895394Y1026985D03*
X893147Y1020025D03*
X893887Y1023208D03*
X887887D03*
X890887Y1026762D03*
X884887D03*
X882779Y1074104D03*
Y1071604D03*
X887979Y1074104D03*
X885379D03*
X890579D03*
Y1071604D03*
X885379D03*
X887979D03*
X897056Y1091391D03*
X882615Y1084666D03*
X897056Y1095984D03*
X894249Y1114103D03*
X891549D03*
X888949D03*
X886349D03*
Y1123803D03*
X888949D03*
X891549D03*
X894249D03*
X895275Y1132870D03*
X892575D03*
X888650Y1199622D03*
X893190Y1208069D03*
X893328Y1212887D03*
X894887Y1227209D03*
X890738Y1311132D03*
X891107Y1314305D03*
X887342Y1314990D03*
X891457Y1639797D03*
X898813Y146461D03*
X903035Y141247D03*
X897715Y152367D03*
X898851Y231496D03*
X910977Y243307D03*
Y248032D03*
Y262205D03*
X898851Y274016D03*
X912786Y306697D03*
X901848Y307782D03*
Y312738D03*
X910076Y304843D03*
X905120D03*
X909417Y323302D03*
X912278Y343881D03*
X913206Y336489D03*
X912085Y332335D03*
X910040Y353532D03*
X902169Y413002D03*
Y418002D03*
Y415502D03*
X905094Y424581D03*
X902594D03*
X907594D03*
X905212Y436734D03*
X902712D03*
X907712D03*
X907173Y440581D03*
X898888Y437614D03*
X907173Y443081D03*
X910779Y471380D03*
X903431Y534093D03*
X906996Y530707D03*
X902459Y530755D03*
X899530Y530753D03*
X911630Y543998D03*
X910578Y550186D03*
X909362Y555614D03*
X898156Y554812D03*
X913853Y561487D03*
X904393Y570176D03*
X908517D03*
X898815D03*
X908846Y560124D03*
X909024Y578394D03*
X898232Y588320D03*
X909024Y586768D03*
X902635Y588305D03*
X906999Y588274D03*
X909024Y574394D03*
X898207Y599891D03*
X908730Y619120D03*
X913686D03*
X899898Y619040D03*
X904854D03*
X912462Y683770D03*
X909265Y677795D03*
X908699Y709387D03*
X911053Y800510D03*
X899916Y808965D03*
X902641Y800748D03*
X908920Y905630D03*
X909811Y962400D03*
X912690Y994350D03*
X897825Y994413D03*
X909166Y994188D03*
X897717Y1019915D03*
X899887Y1023208D03*
Y1026762D03*
X901739Y1091346D03*
X902389Y1081764D03*
X901694Y1095940D03*
X911071Y1123803D03*
X905771D03*
X903171D03*
X908371D03*
X910971Y1114103D03*
X908271D03*
X903071D03*
X905671D03*
X911699Y1129488D03*
X909041Y1126328D03*
X911641D03*
X901428Y1136426D03*
X903908Y1132870D03*
X904063Y1135946D03*
X898278Y1136426D03*
X904897Y1145169D03*
X902397D03*
X901940Y1236799D03*
Y1229899D03*
Y1232399D03*
X909077Y1232724D03*
X901940Y1246199D03*
Y1243699D03*
Y1239299D03*
X899699Y1283872D03*
X910788Y1299456D03*
X906506Y1299188D03*
X902908Y1299828D03*
X911117Y1314130D03*
X902875Y1309301D03*
X905740Y1309264D03*
X908700Y1316300D03*
X911135Y1345560D03*
X904177Y1359955D03*
X899944Y1432359D03*
X908944Y1426359D03*
Y1429359D03*
Y1432359D03*
X911944Y1426359D03*
Y1429359D03*
Y1432359D03*
X905944Y1426359D03*
X899944D03*
X902944D03*
Y1429359D03*
X899944D03*
X902944Y1432359D03*
X905944Y1429359D03*
Y1432359D03*
X902944Y1438359D03*
X899944D03*
Y1441359D03*
X902944Y1435359D03*
X899944D03*
X908944Y1438359D03*
Y1441359D03*
X911944Y1438359D03*
Y1441359D03*
X902944D03*
X905944Y1438359D03*
Y1441359D03*
X908944Y1435359D03*
X911944D03*
X905944D03*
X912171Y1447459D03*
X906671D03*
X901071D03*
X912171Y1457719D03*
Y1452589D03*
X906671Y1457719D03*
X901071D03*
Y1452589D03*
X908370Y1464583D03*
X905370D03*
X899370D03*
X902370D03*
X911370D03*
X905370Y1476583D03*
X908370D03*
X902370D03*
X899370D03*
X905370Y1473583D03*
X908370D03*
X902370D03*
X899370D03*
X902370Y1467583D03*
X899370Y1470583D03*
X902370D03*
X908370Y1467583D03*
Y1470583D03*
X905370Y1467583D03*
Y1470583D03*
X899370Y1467583D03*
X911370Y1476583D03*
Y1473583D03*
Y1467583D03*
Y1470583D03*
X911457Y1639797D03*
X930145Y3000D03*
X931393Y102249D03*
X919175Y113394D03*
X921824Y110784D03*
X923393Y102249D03*
X927393D03*
X921418Y133298D03*
X929418D03*
X923565Y134579D03*
X915267Y157370D03*
X925359Y180347D03*
X927859D03*
X925219Y188564D03*
X929978Y186854D03*
X927719Y188564D03*
X929978Y184054D03*
X919606Y231000D03*
X919577Y240945D03*
Y250394D03*
X919729Y274580D03*
X919577Y271654D03*
X919616Y268462D03*
X919577Y264567D03*
X920142Y308501D03*
X923732Y304585D03*
X926801Y323302D03*
X917906Y321670D03*
X922629Y336609D03*
X922198Y342051D03*
X917858Y331453D03*
X923902Y332411D03*
X927309Y357267D03*
X921389D03*
X915395D03*
X921847Y346622D03*
X915395Y363212D03*
X927309Y363239D03*
Y369210D03*
X921468D03*
X915395D03*
X914202Y418002D03*
Y413002D03*
Y415502D03*
X927636Y452505D03*
X929050Y450316D03*
X924999Y477948D03*
X924600Y533706D03*
X920961Y550075D03*
X915949Y563363D03*
X923453Y569578D03*
X921217Y589216D03*
X913998Y597103D03*
X915712Y613792D03*
X922626Y633772D03*
X929690Y666593D03*
X928704Y680261D03*
X914202Y797460D03*
X927916Y800909D03*
X921451Y903800D03*
X914193Y945318D03*
X928227Y951125D03*
X921364Y951251D03*
X923289Y965780D03*
X926796Y966297D03*
X924956Y994321D03*
X924864Y1026762D03*
Y1023208D03*
X925024Y1018909D03*
X927861Y1024768D03*
X914661Y1132612D03*
X914299Y1129488D03*
X914241Y1126328D03*
X927597Y1147708D03*
X914033Y1345613D03*
X927193Y1361547D03*
X931159Y1379427D03*
X920360Y1387039D03*
X920255Y1383264D03*
X931199Y1371951D03*
X931159Y1390827D03*
Y1406027D03*
X914944Y1426359D03*
Y1429359D03*
Y1432359D03*
Y1438359D03*
Y1441359D03*
Y1435359D03*
X914370Y1464583D03*
Y1476583D03*
Y1473583D03*
Y1467583D03*
Y1470583D03*
X926044Y1545370D03*
Y1542370D03*
X929094Y1542353D03*
Y1545353D03*
X926041Y1554503D03*
Y1551503D03*
Y1548503D03*
Y1557503D03*
Y1560503D03*
X941129Y4469D03*
X942490Y24773D03*
Y44773D03*
X945011Y95111D03*
X944961Y116497D03*
X934410Y109172D03*
X936417Y106495D03*
X937410Y109172D03*
X940161Y116497D03*
Y123584D03*
X944961D03*
X940161Y130670D03*
X944961D03*
X934678Y125107D03*
X940161Y137757D03*
X944961D03*
X936151Y146012D03*
X938057Y141228D03*
X943292Y143762D03*
X940945Y150847D03*
X930359Y180347D03*
X933159D03*
X931407Y192009D03*
X933907D03*
X937438Y213817D03*
X938125Y230891D03*
X942805Y223860D03*
X936369Y221292D03*
X946064Y252998D03*
X941845Y278968D03*
X939606Y310521D03*
X939653Y317474D03*
X940924Y328959D03*
X936608Y326058D03*
X945120Y326441D03*
X932388Y330517D03*
X930398Y342050D03*
X936453Y345336D03*
X945599Y345383D03*
X940972Y338238D03*
X932622Y336817D03*
X943663Y355674D03*
X944694Y352192D03*
X944900Y363700D03*
X938499Y362202D03*
X940600Y370600D03*
X941505Y463442D03*
X936653Y526836D03*
X944351Y534211D03*
X939992Y527726D03*
X931627Y561578D03*
Y565578D03*
X931620Y584417D03*
X931594Y599420D03*
X931647Y593271D03*
X931578Y590669D03*
X943181Y632536D03*
X945434Y634325D03*
X946128Y666522D03*
X933974Y719371D03*
X945626Y789761D03*
X941916Y808965D03*
X935262Y825135D03*
X932418D03*
X937200Y841000D03*
X938729Y874396D03*
X945982Y886737D03*
X942194Y891216D03*
X930800Y904840D03*
X935255Y962725D03*
X940015Y1020176D03*
X934911Y1023579D03*
X945864Y1023208D03*
X930864Y1026762D03*
X936864D03*
X942864D03*
X939864Y1023208D03*
X930864D03*
X930883Y1018751D03*
X936822Y1018988D03*
X942760Y1018751D03*
X943093Y1021769D03*
X943241Y1120636D03*
X940541D03*
X937941D03*
X935341D03*
X937941Y1130336D03*
X940541D03*
X943241D03*
X932641Y1139336D03*
X935341Y1130336D03*
Y1139336D03*
X935601Y1221714D03*
Y1218914D03*
Y1216114D03*
Y1213314D03*
X938601Y1221714D03*
Y1218914D03*
Y1216114D03*
Y1213314D03*
X936417Y1234483D03*
Y1236983D03*
Y1230083D03*
Y1227583D03*
X935601Y1224514D03*
X938601D03*
X941981Y1224406D03*
X936417Y1243883D03*
Y1241383D03*
Y1248283D03*
Y1250783D03*
X947119Y1259935D03*
X933254Y1308273D03*
X931137Y1375878D03*
X931159Y1383227D03*
X939559Y1398427D03*
X931159Y1394627D03*
Y1387027D03*
Y1398427D03*
Y1402227D03*
X939559D03*
X944235Y1406262D03*
X943725Y1430744D03*
Y1427744D03*
X934725Y1430744D03*
X940725Y1427744D03*
Y1430744D03*
X934725Y1427744D03*
X937725D03*
Y1430744D03*
X943725Y1433744D03*
Y1439744D03*
Y1436744D03*
X940725Y1433744D03*
Y1439744D03*
Y1436744D03*
X934725Y1433744D03*
X937725D03*
X934725Y1439744D03*
X937725D03*
X934725Y1436744D03*
X937725D03*
X930441Y1455039D03*
Y1458039D03*
Y1464039D03*
Y1461039D03*
Y1467039D03*
X937671Y1492139D03*
Y1488139D03*
X938670Y1510528D03*
X941270D03*
Y1505328D03*
X938670D03*
X940170Y1507928D03*
X943870Y1510528D03*
Y1505328D03*
X945370Y1507928D03*
X942770D03*
X935094Y1542353D03*
X932094D03*
X935094Y1545353D03*
X932094D03*
X938094Y1542353D03*
Y1545353D03*
X941094Y1542353D03*
X944094D03*
X941094Y1545353D03*
X944094D03*
X931457Y1639797D03*
X949811Y53597D03*
X960623Y82984D03*
Y77784D03*
Y80384D03*
Y75184D03*
Y85584D03*
X960411Y90650D03*
X960161Y95236D03*
Y102323D03*
X960413Y109410D03*
Y116496D03*
X947461Y116497D03*
X952161Y116496D03*
Y109410D03*
Y102323D03*
X947461Y109410D03*
X949380Y106561D03*
X961638Y130670D03*
X947461D03*
X952161D03*
Y123583D03*
X947461D03*
X961633Y137756D03*
X952161D03*
X949359Y198710D03*
X949443Y208206D03*
X951040Y223885D03*
X948741Y229468D03*
X949974Y291554D03*
X949579Y330517D03*
X949813Y336817D03*
X956348Y356371D03*
X952170Y356131D03*
X958823Y362802D03*
X954888Y369513D03*
X948400Y370045D03*
X956863Y451466D03*
X949823Y487982D03*
X949876Y478486D03*
X949823Y483982D03*
X958736Y482165D03*
X949823Y499982D03*
X953816Y555194D03*
X951016D03*
X953816Y571194D03*
X951016D03*
X953816Y563194D03*
X951016D03*
X949425Y581222D03*
Y591215D03*
X948427Y611091D03*
X956365Y641817D03*
X950865D03*
X949137Y666660D03*
X954526Y666671D03*
X957379Y826586D03*
X954760Y826734D03*
X954700Y837700D03*
X955850Y862902D03*
X949382Y886737D03*
X959545Y918306D03*
X949671Y991564D03*
X954937Y1021998D03*
X948864Y1026762D03*
X954864D03*
X951864Y1023208D03*
X957864D03*
X957678Y1018555D03*
X961208Y1018592D03*
X960636Y1021917D03*
X959371Y1026985D03*
X948975Y1021325D03*
X961033Y1091391D03*
Y1095984D03*
X950326Y1114103D03*
Y1123803D03*
X952926D03*
X955526D03*
Y1114103D03*
X958226D03*
X952926D03*
X958226Y1123803D03*
X956552Y1132870D03*
X959252D03*
X962255Y1136426D03*
X952627Y1199622D03*
X957305Y1212887D03*
X957167Y1208069D03*
X958864Y1227209D03*
X952514Y1391339D03*
X952395Y1395276D03*
X948235Y1406262D03*
X946725Y1427744D03*
Y1430744D03*
X949725D03*
Y1427744D03*
X960883Y1427997D03*
Y1430997D03*
X946725Y1433744D03*
X949725D03*
X946725Y1439744D03*
X949725D03*
X946725Y1436744D03*
X949725D03*
X960883Y1433997D03*
Y1436997D03*
Y1439997D03*
X956238Y1455139D03*
Y1458139D03*
Y1461139D03*
Y1464139D03*
X952676Y1461039D03*
Y1464039D03*
Y1458039D03*
Y1455039D03*
X956238Y1467139D03*
Y1469902D03*
X952676Y1467039D03*
X946470Y1510528D03*
Y1505328D03*
X956035Y1545333D03*
X959035D03*
X953035D03*
X950035D03*
X959035Y1542333D03*
X956035D03*
X953035D03*
X950035D03*
X947094Y1545353D03*
Y1542353D03*
X951457Y1639797D03*
X969811Y53597D03*
X963177Y92849D03*
X965723Y90615D03*
X970094Y95236D03*
X970044Y99961D03*
X978271Y109410D03*
Y102323D03*
X970137Y103037D03*
X970271Y116496D03*
Y109410D03*
X978271Y116496D03*
X970271Y130670D03*
Y123583D03*
X978271Y130670D03*
Y123583D03*
X963360Y121459D03*
X966347Y137756D03*
X978271D03*
X968906Y223726D03*
Y228726D03*
Y231226D03*
X979362Y223661D03*
X968906Y226226D03*
X972160Y258880D03*
X974952Y293796D03*
X972452D03*
X976763Y307303D03*
X972147Y323681D03*
X977150Y328472D03*
Y335472D03*
X975631Y343112D03*
Y346612D03*
X971721Y407762D03*
X968348Y402369D03*
X975932Y437508D03*
X971932D03*
X971826Y430187D03*
X966694Y427599D03*
X968462Y429368D03*
X962769Y458466D03*
X973695Y448874D03*
X969109Y449352D03*
X967816Y472905D03*
X972397Y472954D03*
X973843Y500086D03*
X978723Y504699D03*
X976223D03*
X973723D03*
X978425Y516979D03*
X973425D03*
X974406Y521804D03*
X975925Y516979D03*
X978668Y527449D03*
X974406Y524304D03*
X970713Y531378D03*
Y528878D03*
X975868Y527449D03*
X964012Y546830D03*
X978581Y572975D03*
X976962Y608311D03*
X980683Y628242D03*
X967302Y627948D03*
X969491Y629362D03*
X963950Y734178D03*
X965983Y763567D03*
X967562Y802982D03*
X978978Y817618D03*
X978214Y821224D03*
X970040Y842903D03*
X969309Y839334D03*
X967842Y864801D03*
X967510Y868971D03*
X973988Y910038D03*
X963864Y1026762D03*
Y1023208D03*
X965716Y1091346D03*
X966366Y1081764D03*
X965671Y1095940D03*
X967148Y1123803D03*
X969748D03*
X969648Y1114103D03*
X967048D03*
X972348Y1123803D03*
X975048D03*
X972248Y1114103D03*
X974948D03*
X965405Y1136426D03*
X970485Y1132870D03*
X967885D03*
X968874Y1145169D03*
X966374D03*
X978169Y1221268D03*
X965917Y1236799D03*
Y1229899D03*
Y1232399D03*
Y1246199D03*
Y1243699D03*
Y1239299D03*
X963883Y1430997D03*
Y1427997D03*
X966883Y1430997D03*
Y1427997D03*
X969883D03*
Y1430997D03*
X975883Y1427997D03*
Y1430997D03*
X972883D03*
Y1427997D03*
X963883Y1433997D03*
X966883D03*
X969883D03*
X963883Y1436997D03*
Y1439997D03*
X966883Y1436997D03*
Y1439997D03*
X969883Y1436997D03*
Y1439997D03*
X975883Y1433997D03*
X972883D03*
X975883Y1436997D03*
X972883D03*
X975883Y1439997D03*
X972883D03*
X971467Y1509515D03*
X974067D03*
X972567Y1512115D03*
X969967D03*
X976667Y1509515D03*
X977767Y1506915D03*
X975167D03*
X969967D03*
X972567D03*
X975167Y1512115D03*
X977767D03*
X971140Y1514693D03*
X968540D03*
X973740D03*
X976340D03*
X977547Y1546081D03*
X974547D03*
X971547D03*
X971457Y1639797D03*
X988606Y5374D03*
X987919Y24773D03*
Y44773D03*
X987682Y115401D03*
X992674D03*
Y110445D03*
X987682D03*
X992674Y124618D03*
X987682D03*
Y129574D03*
X992674D03*
X985595Y151540D03*
X989245Y191941D03*
X989112Y188727D03*
X987331Y229286D03*
X991024Y224712D03*
Y222212D03*
X983069Y226141D03*
X985869D03*
X979362Y231461D03*
Y228961D03*
Y226461D03*
X987331Y231786D03*
X985812Y236611D03*
X988312D03*
X983312D03*
X983014Y248891D03*
X988014D03*
X985514D03*
X990939Y256535D03*
X994939Y256303D03*
X985766Y288190D03*
X982966D03*
X985766Y285690D03*
X982966D03*
X980466Y288190D03*
Y285690D03*
X993992Y290755D03*
X989992D03*
X993132Y310942D03*
X993243Y321325D03*
X987055Y320273D03*
X993920Y335454D03*
X993420Y337954D03*
X992045Y366559D03*
X984045D03*
X988045D03*
X991392Y409230D03*
X979932Y437508D03*
X982792Y447269D03*
X982670Y450201D03*
X980397Y473045D03*
X992206Y478586D03*
Y481086D03*
Y483886D03*
X985699Y480705D03*
X980544Y482134D03*
Y484634D03*
X992206Y476086D03*
X988499Y480705D03*
X983989Y475946D03*
Y478446D03*
X982375Y522129D03*
X989936Y519531D03*
X987436D03*
X982436D03*
X984936D03*
X982375Y527129D03*
Y524629D03*
Y529929D03*
X989068Y532949D03*
X986268D03*
X981795Y572842D03*
X985903Y579475D03*
X985357Y585507D03*
X989950D03*
X985401Y590145D03*
X989995Y590190D03*
X989857Y605443D03*
X983843Y633205D03*
Y636005D03*
Y638805D03*
X983269Y853883D03*
X988054Y888283D03*
X990300Y897500D03*
X982783Y909995D03*
X989311Y920364D03*
X986645Y1108465D03*
X989513Y1097683D03*
X995009Y1131223D03*
X991763Y1140378D03*
Y1128378D03*
Y1134378D03*
X984558Y1140774D03*
X988112Y1137774D03*
X984558Y1128774D03*
Y1134774D03*
X987804Y1131619D03*
X990501Y1320756D03*
X988784Y1361974D03*
X986949Y1430997D03*
Y1427997D03*
X983949D03*
X989949Y1430997D03*
Y1427997D03*
X983949Y1430997D03*
X992949Y1427997D03*
Y1430997D03*
X986949Y1433997D03*
X983949D03*
X989949D03*
X992949D03*
X986949Y1436997D03*
X983949D03*
X986949Y1439997D03*
X983949D03*
X989949Y1436997D03*
Y1439997D03*
X992949Y1436997D03*
Y1439997D03*
X979538Y1464039D03*
Y1461039D03*
Y1458039D03*
Y1455039D03*
Y1467039D03*
Y1469802D03*
X979267Y1509515D03*
X984467D03*
X981867D03*
X985567Y1512115D03*
Y1506915D03*
X980367D03*
X982967D03*
Y1512115D03*
X980367D03*
X989667Y1509515D03*
X992267D03*
X987067D03*
X988167Y1512115D03*
X990767D03*
Y1506915D03*
X988167D03*
X984140Y1514693D03*
X981540D03*
X978940D03*
X986740D03*
X989340D03*
X986773Y1546081D03*
X983773D03*
X980773D03*
X991457Y1639797D03*
X1011187Y-33526D03*
Y-30126D03*
X1007508Y3000D03*
X1000631Y76140D03*
Y80140D03*
X1003379Y72615D03*
Y76587D03*
X997837Y97475D03*
X1013480Y103621D03*
X1003076Y117557D03*
X998084D03*
X1009191Y112083D03*
X1003076Y122513D03*
Y131731D03*
X998084Y122513D03*
Y131731D03*
X1001175Y146461D03*
X1003076Y136687D03*
X998084D03*
X1005397Y141247D03*
X1000077Y152367D03*
X1001777Y180572D03*
X1006460Y180527D03*
X1012999Y172665D03*
X1010183Y192421D03*
X1001777Y185165D03*
X1006415Y185121D03*
X995745Y184619D03*
X997725Y206760D03*
X999826Y278734D03*
X1004061Y280808D03*
X1008563Y293645D03*
X1006063D03*
Y290845D03*
Y288345D03*
X1008563Y290845D03*
Y288345D03*
X997992Y290755D03*
X1004635Y300276D03*
X1008635D03*
X1010499Y309062D03*
X998667Y322239D03*
X1004544Y318050D03*
X1004933Y314535D03*
X1003181Y323057D03*
X997921Y333654D03*
X1000420Y348954D03*
Y353954D03*
X997857Y605443D03*
X995913Y633450D03*
Y636250D03*
Y639050D03*
X1001676Y678015D03*
X1002751Y757169D03*
X1013319Y785929D03*
X1007027Y792973D03*
X1012703Y837659D03*
X1004713Y871389D03*
X998313Y888295D03*
X995317Y1137378D03*
X998600Y1369200D03*
Y1373400D03*
X1007850Y1368835D03*
X1009338Y1391597D03*
Y1388597D03*
X1008138Y1407186D03*
Y1409986D03*
X1005338Y1407186D03*
Y1409986D03*
X1008138Y1415586D03*
Y1412786D03*
X1005338Y1415586D03*
Y1412786D03*
X1008138Y1418386D03*
X1005338D03*
X998949Y1427997D03*
Y1430997D03*
X995949D03*
Y1427997D03*
X1009981Y1431097D03*
Y1428097D03*
X1006981D03*
Y1431097D03*
X998949Y1433997D03*
X995949D03*
X998949Y1436997D03*
X995949D03*
X998949Y1439997D03*
X995949D03*
X1009981Y1434097D03*
X1006981D03*
X1009981Y1437097D03*
X1006981D03*
X1009981Y1440097D03*
X1006981D03*
X1002538Y1463939D03*
Y1460939D03*
Y1457939D03*
Y1454939D03*
Y1466939D03*
Y1469702D03*
X1008549Y1509815D03*
X1007049Y1507215D03*
X1011149Y1509815D03*
X1009649Y1507215D03*
Y1512415D03*
X1007049D03*
X1008222Y1514993D03*
X1005622D03*
X1010822D03*
X1010606Y1547824D03*
X1007611Y1561247D03*
Y1558247D03*
Y1555247D03*
Y1552247D03*
X1004611Y1561247D03*
Y1558247D03*
Y1555247D03*
Y1552247D03*
X1010659Y1568771D03*
Y1565771D03*
X1010653Y1571669D03*
X1027508Y3000D03*
X1023373Y60922D03*
X1018209Y55513D03*
X1017787Y85731D03*
X1020254Y97068D03*
X1015402Y91951D03*
X1021341Y86046D03*
X1021537Y113394D03*
X1025755Y102249D03*
X1024186Y110784D03*
X1024289Y130898D03*
X1025927Y134579D03*
X1017629Y157370D03*
X1021713Y180665D03*
Y172665D03*
X1027055Y195176D03*
X1021713Y192665D03*
X1026915Y203393D03*
X1021745Y200864D03*
Y208864D03*
X1018014Y228631D03*
X1013354Y323362D03*
X1021451Y322879D03*
X1026032Y322906D03*
X1013327Y327453D03*
X1013318Y333190D03*
X1022845Y340944D03*
X1013313Y339909D03*
X1015195Y428305D03*
X1012188Y443421D03*
X1026916Y719769D03*
X1024684Y756485D03*
X1014064Y793660D03*
X1013918Y851306D03*
X1012842Y910685D03*
X1022346Y917669D03*
X1029570Y917718D03*
X1018419Y917575D03*
X1014719Y938322D03*
X1011782Y1016591D03*
X1017297Y1102091D03*
X1026606Y1102591D03*
X1023106Y1102091D03*
X1026606Y1114691D03*
X1023144Y1122164D03*
X1017297D03*
X1023144Y1134764D03*
X1017297D03*
X1023144Y1147364D03*
X1017297D03*
X1023144Y1159964D03*
X1017297D03*
Y1172564D03*
X1023162Y1174445D03*
X1023139Y1184856D03*
X1017297Y1185164D03*
X1012338Y1388597D03*
Y1391597D03*
X1015338D03*
Y1388597D03*
X1021338D03*
Y1391597D03*
X1018338D03*
Y1388597D03*
X1027338D03*
Y1391597D03*
X1024338D03*
Y1388597D03*
X1012981Y1431097D03*
Y1428097D03*
X1015981D03*
Y1431097D03*
X1021981Y1428097D03*
Y1431097D03*
X1018981D03*
Y1428097D03*
X1012981Y1434097D03*
X1015981D03*
X1012981Y1437097D03*
Y1440097D03*
X1015981Y1437097D03*
Y1440097D03*
X1021981Y1434097D03*
X1018981D03*
X1021981Y1437097D03*
X1018981D03*
X1021981Y1440097D03*
X1018981D03*
X1025138Y1463839D03*
Y1460839D03*
Y1457839D03*
Y1454839D03*
Y1466839D03*
Y1469602D03*
X1013749Y1509815D03*
X1016349D03*
X1021549D03*
X1018949D03*
X1024149D03*
X1022649Y1507215D03*
X1025249D03*
X1017449D03*
X1020049D03*
X1014849D03*
X1012249D03*
X1026749Y1509815D03*
X1012249Y1512415D03*
X1014849D03*
X1025249D03*
X1022649D03*
X1020049D03*
X1017449D03*
X1013422Y1514993D03*
X1023822D03*
X1021222D03*
X1018622D03*
X1016022D03*
X1026422D03*
X1013606Y1547824D03*
X1016606D03*
X1019606D03*
X1013659Y1568771D03*
X1016659D03*
X1019659D03*
X1013659Y1565771D03*
X1016659D03*
X1019659D03*
X1013653Y1571669D03*
X1016653D03*
X1019653D03*
X1011457Y1639797D03*
X1043492Y4469D03*
X1033755Y102249D03*
X1036772Y109172D03*
X1039772D03*
X1038779Y106495D03*
X1029755Y102249D03*
X1042523Y116497D03*
X1031780Y133298D03*
X1042523Y130670D03*
Y123584D03*
X1037040Y125107D03*
X1038513Y146012D03*
X1040419Y141228D03*
X1042523Y137757D03*
X1045654Y143762D03*
X1043307Y150847D03*
X1032055Y195176D03*
X1031674Y198883D03*
X1029555Y195176D03*
X1034855D03*
X1033103Y206838D03*
X1035603D03*
X1029415Y203393D03*
X1031674Y201683D03*
X1039134Y228646D03*
X1038065Y236121D03*
X1035099Y238589D03*
X1037984Y253198D03*
X1030184Y288709D03*
X1038068Y298789D03*
X1033112D03*
X1041496Y300276D03*
X1031354Y325901D03*
Y322905D03*
X1031382Y340947D03*
X1031310Y337888D03*
X1031377Y333671D03*
X1031362Y329268D03*
X1029885Y711762D03*
X1035619Y755809D03*
X1038344Y756476D03*
X1038678Y776750D03*
X1042414Y801443D03*
X1046045Y841217D03*
X1044390Y861210D03*
X1038010Y902565D03*
X1030338Y1391597D03*
Y1388597D03*
X1032867Y1431213D03*
Y1428213D03*
X1029867D03*
X1035867Y1431213D03*
Y1428213D03*
X1029867Y1431213D03*
X1038867Y1428213D03*
Y1431213D03*
X1041867D03*
Y1428213D03*
X1032867Y1434213D03*
X1029867D03*
X1035867D03*
X1038867D03*
X1032867Y1437213D03*
X1029867D03*
X1032867Y1440213D03*
X1029867D03*
X1035867Y1437213D03*
Y1440213D03*
X1038867Y1437213D03*
Y1440213D03*
X1041867Y1434213D03*
Y1437213D03*
Y1440213D03*
X1029349Y1509815D03*
X1027849Y1507215D03*
Y1512415D03*
X1031457Y1639797D03*
X1044853Y24773D03*
Y44773D03*
X1052174Y53597D03*
X1047373Y95111D03*
X1049823Y109410D03*
X1054523Y116496D03*
Y109410D03*
Y102323D03*
X1049823Y116497D03*
X1047323D03*
X1051742Y106561D03*
X1049823Y130670D03*
X1047323D03*
Y123584D03*
X1049823Y123583D03*
X1054523Y130670D03*
Y123583D03*
Y137756D03*
X1047323Y137757D03*
X1051055Y213539D03*
X1044501Y238689D03*
X1045275Y247292D03*
X1052736Y238714D03*
X1050437Y244297D03*
X1045364Y279895D03*
X1051796Y279965D03*
X1046674Y340031D03*
X1045966Y346808D03*
X1052367Y402291D03*
X1057359D03*
X1052367Y397335D03*
X1057359D03*
X1054959Y411509D03*
X1049967Y416465D03*
Y411509D03*
X1054959Y425682D03*
X1049967D03*
X1054959Y416465D03*
X1046068Y792742D03*
X1046930Y796557D03*
X1050358Y837793D03*
X1049087Y856033D03*
X1054900Y879321D03*
X1050295Y891100D03*
X1046485Y1034538D03*
X1057212Y1040356D03*
X1048043Y1105091D03*
Y1117691D03*
Y1130291D03*
Y1155491D03*
Y1142891D03*
Y1168091D03*
X1044867Y1428213D03*
Y1431213D03*
Y1434213D03*
Y1437213D03*
Y1440213D03*
X1051457Y1639797D03*
X1072174Y53597D03*
X1062985Y82984D03*
Y75184D03*
Y77784D03*
Y80384D03*
X1065539Y92849D03*
X1062985Y85584D03*
X1062773Y90650D03*
X1068085Y90615D03*
X1072456Y95236D03*
X1072406Y99961D03*
X1062523Y95236D03*
X1072499Y103037D03*
X1062523Y102323D03*
X1062775Y109410D03*
Y116496D03*
X1072633D03*
Y109410D03*
X1062947Y124576D03*
X1072633Y130670D03*
Y123583D03*
X1064000Y130670D03*
X1069224Y137756D03*
X1063995D03*
X1071268Y226226D03*
Y223726D03*
Y228726D03*
Y231226D03*
X1074522Y258880D03*
X1074814Y293796D03*
X1061325Y339509D03*
X1060679Y360151D03*
Y364276D03*
X1060369Y390223D03*
X1065361D03*
X1060369Y395179D03*
Y404396D03*
Y409352D03*
X1065361Y395179D03*
Y404396D03*
Y409352D03*
X1060369Y418569D03*
Y423525D03*
X1065361Y418569D03*
X1060698Y931619D03*
X1069685Y933391D03*
X1066878Y931909D03*
X1070009Y997860D03*
X1073525Y1012428D03*
X1076110Y1029535D03*
X1065079Y1036920D03*
X1076577Y1041332D03*
X1074232Y1055836D03*
X1067866Y1051037D03*
X1060768Y1053457D03*
X1071457Y1639797D03*
X1081187Y-72706D03*
Y-69306D03*
X1090280Y44773D03*
X1090044Y110445D03*
Y115401D03*
X1080633Y102323D03*
Y116496D03*
Y109410D03*
Y130670D03*
Y123583D03*
X1090044Y124618D03*
Y129574D03*
X1080633Y137756D03*
X1087957Y151540D03*
X1091607Y191941D03*
X1091474Y188727D03*
X1085431Y226141D03*
X1081724Y226461D03*
X1088231Y226141D03*
X1081724Y223661D03*
X1089693Y229286D03*
X1081724Y231461D03*
Y228961D03*
X1089693Y231786D03*
X1085674Y236611D03*
X1088174D03*
X1090674D03*
X1090376Y248891D03*
X1087876D03*
X1085376D03*
X1088128Y285690D03*
Y288190D03*
X1085328D03*
X1082828Y285690D03*
X1085328D03*
X1082828Y288190D03*
X1077314Y293796D03*
X1092354Y290755D03*
X1082297Y340770D03*
X1092554Y340318D03*
X1085615Y339815D03*
X1092561Y353374D03*
X1082787Y348501D03*
X1091542Y389154D03*
Y396240D03*
X1078920Y856700D03*
X1090375Y899047D03*
X1076800Y1012900D03*
X1078755Y1031518D03*
X1079178Y1037884D03*
X1083483Y1523433D03*
X1090747Y1617415D03*
X1092000Y1644980D03*
X1102993Y76140D03*
Y80140D03*
X1105741Y76587D03*
Y72615D03*
X1100199Y97475D03*
X1100446Y117557D03*
X1095036Y115401D03*
Y110445D03*
X1105438Y117557D03*
X1095036Y129574D03*
Y124618D03*
X1105438Y131731D03*
Y122513D03*
X1100446Y131731D03*
Y122513D03*
X1103537Y146461D03*
X1100446Y136687D03*
X1105438D03*
X1107759Y141247D03*
X1102439Y152367D03*
X1104139Y180572D03*
X1108822Y180527D03*
X1109903Y171523D03*
X1104139Y185165D03*
X1108777Y185121D03*
X1098107Y184619D03*
X1100087Y206760D03*
X1093386Y224712D03*
Y222212D03*
X1093301Y256535D03*
X1097301Y256303D03*
X1102331Y279208D03*
X1106435Y281307D03*
X1108425Y293645D03*
Y290845D03*
Y288345D03*
X1096354Y290755D03*
X1100354D03*
X1093478Y310305D03*
X1100703Y340560D03*
X1101999Y353495D03*
X1093994Y374003D03*
X1099342Y389154D03*
X1106161D03*
X1099342Y396240D03*
X1105298Y598400D03*
Y602400D03*
Y594400D03*
Y614400D03*
Y606400D03*
X1092769Y936975D03*
X1099900Y1535700D03*
X1096264Y1562285D03*
X1093713Y1585583D03*
X1107620Y1606752D03*
X1123052Y57511D03*
X1120149Y85731D03*
X1122613Y97042D03*
X1117764Y91951D03*
X1123703Y86046D03*
X1115842Y103621D03*
X1123899Y113394D03*
X1111553Y112083D03*
X1119991Y157370D03*
X1124075Y180665D03*
Y172665D03*
X1112545Y192421D03*
X1114708Y190185D03*
X1124107Y200864D03*
Y208864D03*
X1120376Y228631D03*
X1110925Y293645D03*
Y290845D03*
Y288345D03*
X1123500Y329000D03*
Y339000D03*
Y334000D03*
X1119853Y398082D03*
Y401482D03*
Y412255D03*
Y426428D03*
Y415655D03*
Y440602D03*
Y429828D03*
Y444002D03*
Y490641D03*
Y476468D03*
Y479868D03*
Y494041D03*
Y524002D03*
Y520602D03*
Y538175D03*
Y534775D03*
X1117913Y565414D03*
Y567914D03*
Y570414D03*
Y572914D03*
Y575414D03*
X1122705Y588515D03*
X1117453Y602205D03*
Y595118D03*
X1122718Y598857D03*
X1122705Y591015D03*
X1121191Y612555D03*
X1120512Y617332D03*
X1121022Y607750D03*
X1118863Y662981D03*
X1116296Y691851D03*
X1112000Y1644980D03*
X1125735Y60922D03*
X1136117Y102249D03*
X1139134Y109172D03*
X1141141Y106495D03*
X1132117Y102249D03*
X1128117D03*
X1126548Y110784D03*
X1134142Y133298D03*
X1126142D03*
X1139402Y125107D03*
X1140875Y146012D03*
X1128289Y134579D03*
X1134036Y198883D03*
X1134417Y195176D03*
X1131917D03*
X1137217D03*
X1129417D03*
X1137965Y206838D03*
X1134036Y201683D03*
X1131777Y203393D03*
X1129277D03*
X1135465Y206838D03*
X1141496Y228646D03*
X1137461Y238589D03*
X1140427Y236121D03*
X1140346Y253198D03*
X1127153Y390995D03*
X1142440Y404718D03*
X1127153Y408568D03*
Y405168D03*
Y394395D03*
X1142440Y412718D03*
X1127153Y422741D03*
Y419341D03*
Y436915D03*
Y433515D03*
Y472781D03*
Y469381D03*
Y486954D03*
Y483554D03*
Y516915D03*
Y513515D03*
X1138166Y534759D03*
X1127153Y527688D03*
Y531088D03*
X1138098Y543925D03*
X1138673Y555000D03*
X1126633Y560500D03*
X1129471Y732571D03*
X1132000Y1644980D03*
X1147214Y44773D03*
X1154535Y53597D03*
X1149735Y95111D03*
X1142134Y109172D03*
X1156885Y116496D03*
Y102323D03*
Y109410D03*
X1152185D03*
Y116497D03*
X1149685D03*
X1144885D03*
X1154104Y106561D03*
X1152185Y130670D03*
X1149685D03*
Y123584D03*
X1152185Y123583D03*
X1144885Y130670D03*
Y123584D03*
X1156885Y130670D03*
Y123583D03*
X1142781Y141228D03*
X1156885Y137756D03*
X1149685Y137757D03*
X1144885D03*
X1148016Y143762D03*
X1145669Y150847D03*
X1153417Y213539D03*
X1146863Y238689D03*
X1155098Y238714D03*
X1147637Y247292D03*
X1152799Y244297D03*
X1145761Y324148D03*
X1142440Y392718D03*
Y400718D03*
Y408718D03*
X1157251Y636842D03*
X1156023Y678462D03*
X1149437Y728541D03*
X1152316Y746625D03*
X1149345Y771517D03*
X1145910Y794217D03*
X1151277Y790996D03*
X1149627Y813323D03*
X1146985Y812642D03*
X1152000Y1644980D03*
X1165347Y82984D03*
Y75184D03*
Y77784D03*
Y80384D03*
X1167756Y92734D03*
X1165347Y85584D03*
X1170447Y90615D03*
X1165135Y90650D03*
X1174768Y99961D03*
X1164885Y95236D03*
Y102323D03*
X1165137Y109410D03*
Y116496D03*
X1165309Y124576D03*
X1166362Y130670D03*
X1171586Y137756D03*
X1166357D03*
X1173630Y226226D03*
Y223726D03*
Y228726D03*
Y231226D03*
X1173559Y304948D03*
X1169173Y427017D03*
X1168851Y449873D03*
X1171255Y456287D03*
X1168851Y445873D03*
X1170878Y474424D03*
Y477824D03*
Y488597D03*
Y491997D03*
Y518558D03*
Y521958D03*
Y532731D03*
Y536131D03*
X1161274Y550462D03*
X1170878Y571997D03*
Y568597D03*
Y586171D03*
Y582771D03*
Y596944D03*
Y600344D03*
Y614517D03*
Y611117D03*
X1161451Y618288D03*
X1163157Y638125D03*
X1160756Y665140D03*
X1170465Y677836D03*
X1170603Y715281D03*
X1163751Y719498D03*
X1168577Y733812D03*
X1157985Y791142D03*
X1161291Y791662D03*
X1173697Y791911D03*
X1160516Y800900D03*
X1169266Y800799D03*
X1172000Y1644980D03*
X1174535Y53597D03*
X1174818Y95236D03*
X1174861Y103037D03*
X1174995Y116496D03*
Y109410D03*
X1182995Y116496D03*
Y109410D03*
Y102323D03*
X1174995Y130670D03*
Y123583D03*
X1182995Y130670D03*
Y123583D03*
Y137756D03*
X1184086Y231461D03*
Y228961D03*
X1187793Y226141D03*
X1184086Y226461D03*
X1190593Y226141D03*
X1184086Y223661D03*
X1188036Y236611D03*
X1187738Y248891D03*
X1177035Y257919D03*
X1179676Y293796D03*
X1187690Y288190D03*
X1185190Y285690D03*
X1187690D03*
X1185190Y288190D03*
X1177176Y293796D03*
X1179901Y306366D03*
X1181706Y310131D03*
X1178045Y312193D03*
X1181379Y316049D03*
X1174929Y319167D03*
X1182911Y336516D03*
X1177036Y334148D03*
X1187996Y331992D03*
X1188598Y390500D03*
X1179184Y410394D03*
Y403307D03*
X1180118Y430098D03*
Y437598D03*
Y435098D03*
Y432598D03*
X1178083Y442856D03*
X1180578Y458406D03*
Y451319D03*
X1179184Y446595D03*
X1180402Y462264D03*
X1178178Y467337D03*
Y470737D03*
Y484910D03*
Y481510D03*
Y511471D03*
Y514871D03*
Y529044D03*
Y525644D03*
Y564910D03*
Y561510D03*
Y579084D03*
Y575684D03*
Y604030D03*
Y593257D03*
Y589857D03*
Y607430D03*
X1177745Y771744D03*
X1177566Y778539D03*
X1190062Y844378D03*
X1187703Y849734D03*
X1186742Y855466D03*
X1183431Y868340D03*
X1177775Y894053D03*
X1176577Y885974D03*
X1178480Y915220D03*
X1178000Y936500D03*
X1188431Y936568D03*
X1187200Y963400D03*
X1193330Y5374D03*
X1192643Y24773D03*
Y44773D03*
X1205355Y76140D03*
Y80140D03*
X1202561Y97475D03*
X1202808Y117557D03*
X1197398Y110445D03*
Y115401D03*
X1192406Y110445D03*
Y115401D03*
X1197398Y129574D03*
Y124618D03*
X1192406D03*
Y129574D03*
X1202808Y122513D03*
Y131731D03*
X1205899Y146461D03*
X1202808Y136687D03*
X1204801Y152367D03*
X1190319Y151540D03*
X1200469Y184619D03*
X1193969Y191941D03*
X1193836Y188727D03*
X1202449Y206760D03*
X1192055Y229286D03*
X1195748Y224712D03*
Y222212D03*
X1192055Y231786D03*
X1190536Y236611D03*
X1193036D03*
X1192738Y248891D03*
X1190238D03*
X1195663Y256535D03*
X1199663Y256303D03*
X1204693Y279208D03*
X1194716Y290755D03*
X1202716D03*
X1190490Y285690D03*
Y288190D03*
X1198716Y290755D03*
X1198248Y381500D03*
X1198468Y430760D03*
X1198489Y433570D03*
X1198305Y437072D03*
X1198346Y439963D03*
X1198552Y452018D03*
X1198590Y443180D03*
X1198610Y454744D03*
X1198655Y460250D03*
X1192990Y914873D03*
X1195118Y936296D03*
X1192000Y1644980D03*
X1212232Y3000D03*
X1208103Y72615D03*
Y76587D03*
X1222511Y85731D03*
X1220126Y91951D03*
X1218204Y103621D03*
X1207800Y117557D03*
X1213915Y112083D03*
X1207800Y122513D03*
Y131731D03*
Y136687D03*
X1210121Y141247D03*
X1222353Y157370D03*
X1206501Y180572D03*
X1211184Y180527D03*
X1212265Y171523D03*
X1214907Y192421D03*
X1206501Y185165D03*
X1211139Y185121D03*
X1217070Y190185D03*
X1222738Y228631D03*
X1208797Y281307D03*
X1213287Y293645D03*
Y290845D03*
Y288345D03*
X1210787Y293645D03*
Y290845D03*
Y288345D03*
X1217139Y324139D03*
X1221337Y332017D03*
X1220985Y342319D03*
X1217177Y369925D03*
X1206673Y410394D03*
Y403307D03*
X1206489Y458406D03*
X1212680Y445908D03*
X1216630Y445787D03*
X1212000Y1644980D03*
X1225405Y-72678D03*
Y-69278D03*
X1230761Y-33628D03*
Y-30228D03*
X1232232Y3000D03*
X1222933Y55513D03*
X1228097Y60922D03*
X1225041Y97080D03*
X1238479Y102249D03*
X1226065Y86046D03*
X1230479Y102249D03*
X1234479D03*
X1228910Y110784D03*
X1226261Y113394D03*
X1229195Y130898D03*
X1236504Y133298D03*
X1230651Y134579D03*
X1226437Y180665D03*
Y172665D03*
X1236779Y195176D03*
X1236398Y198883D03*
X1234279Y195176D03*
X1239579D03*
X1231779D03*
X1236398Y201683D03*
X1234139Y203393D03*
X1231639D03*
X1226469Y200864D03*
X1237827Y206838D03*
X1226469Y208864D03*
X1238055Y303839D03*
X1224186Y316731D03*
X1229922Y324550D03*
X1234904Y316942D03*
X1232197Y316964D03*
X1238293Y317296D03*
X1230077Y336324D03*
X1234656Y353506D03*
X1225755Y369391D03*
X1229122Y369355D03*
X1222601Y369251D03*
X1232000Y1644980D03*
X1248216Y4469D03*
X1249577Y24773D03*
Y44773D03*
X1252097Y95111D03*
X1243503Y106495D03*
X1244496Y109172D03*
X1241496D03*
X1247247Y116497D03*
X1254547Y109410D03*
Y116497D03*
X1252047D03*
X1247247Y123584D03*
Y130670D03*
X1252047Y123584D03*
X1254547Y123583D03*
Y130670D03*
X1252047D03*
X1241764Y125107D03*
X1243237Y146012D03*
X1245143Y141228D03*
X1247247Y137757D03*
X1252047D03*
X1250307Y140296D03*
X1250378Y143762D03*
X1248031Y150847D03*
X1240327Y206838D03*
X1243858Y228646D03*
X1249999Y247292D03*
X1239823Y238589D03*
X1242789Y236121D03*
X1242708Y253198D03*
X1256218Y1175987D03*
X1249363Y1166065D03*
X1245900Y1528000D03*
X1256898Y53597D03*
X1267709Y82984D03*
Y75184D03*
Y77784D03*
Y80384D03*
X1270263Y92849D03*
X1267709Y85584D03*
X1267497Y90650D03*
X1267247Y95236D03*
X1267499Y116496D03*
X1259247D03*
Y102323D03*
Y109410D03*
X1267247Y102323D03*
X1267499Y109410D03*
X1256466Y106561D03*
X1267671Y124576D03*
X1268724Y130670D03*
X1259247D03*
Y123583D03*
X1268719Y137756D03*
X1259247D03*
X1255779Y213539D03*
X1257460Y238714D03*
X1255161Y244297D03*
X1266962Y302167D03*
X1262665Y302730D03*
X1263328Y309003D03*
X1261659Y318258D03*
X1264088Y320382D03*
X1266616Y322456D03*
X1259500Y330000D03*
X1256000Y340500D03*
X1266219Y374300D03*
X1268659Y377173D03*
X1261623Y447486D03*
X1259223Y458334D03*
Y454334D03*
X1267843Y488618D03*
Y491118D03*
Y493618D03*
X1270951Y491870D03*
X1269876Y1132319D03*
X1263873Y1148000D03*
X1266709Y1160168D03*
X1271256Y1185205D03*
X1262605Y1187215D03*
X1268573Y1193019D03*
X1264573D03*
X1263242Y1523458D03*
X1262985Y1519459D03*
X1260260Y1546500D03*
X1276898Y53597D03*
X1272809Y90615D03*
X1277130Y99961D03*
X1277180Y95236D03*
X1277223Y103037D03*
X1277357Y116496D03*
Y109410D03*
X1285357Y116496D03*
Y109410D03*
Y102323D03*
Y123583D03*
X1277357Y130670D03*
Y123583D03*
X1285357Y130670D03*
X1273555Y137756D03*
X1285357D03*
X1275992Y223726D03*
Y226226D03*
Y231226D03*
Y228726D03*
X1286448Y223661D03*
Y226461D03*
Y228961D03*
Y231461D03*
X1279246Y258880D03*
X1279538Y293796D03*
X1282038D03*
X1271571Y281185D03*
X1283494Y339495D03*
X1284419Y359377D03*
X1281834Y374839D03*
X1287437Y370010D03*
X1275940Y392228D03*
X1271346Y392183D03*
X1275407Y402867D03*
X1271391Y396866D03*
X1275984D03*
X1282760Y409016D03*
X1278724Y409032D03*
X1272215Y442518D03*
Y439718D03*
X1279127Y450091D03*
X1282092Y449118D03*
Y446318D03*
X1281737Y452740D03*
X1283455Y468088D03*
Y465288D03*
X1280616Y472189D03*
X1279505Y487570D03*
Y490070D03*
X1276060Y496258D03*
X1273451Y491870D03*
X1276060Y493758D03*
X1284900Y678800D03*
X1285500Y851500D03*
X1279460Y854487D03*
Y859487D03*
Y884487D03*
Y889487D03*
X1274400Y914123D03*
X1281400Y940256D03*
X1275788Y1124088D03*
X1273865Y1132497D03*
X1282830Y1146937D03*
X1272120Y1159455D03*
X1280306Y1162817D03*
X1275965Y1187232D03*
X1280602Y1185238D03*
X1276573Y1193019D03*
X1280573D03*
X1272573D03*
X1277108Y1211664D03*
X1279402Y1213958D03*
X1275032Y1209589D03*
X1284198Y1218754D03*
X1302232Y3000D03*
X1295692Y5374D03*
X1303229Y23274D03*
X1295005Y24773D03*
X1297785Y30618D03*
X1295005Y44773D03*
X1304923Y97475D03*
X1299760Y110445D03*
Y115401D03*
X1294768Y110445D03*
Y115401D03*
Y129574D03*
X1299760D03*
Y124618D03*
X1294768D03*
X1296331Y191941D03*
X1302831Y184619D03*
X1296198Y188727D03*
X1292955Y226141D03*
X1290155D03*
X1294417Y229286D03*
X1298110Y222212D03*
Y224712D03*
X1290398Y236611D03*
X1295398D03*
X1292898D03*
X1294417Y231786D03*
X1298025Y256535D03*
X1290100Y248891D03*
X1292600D03*
X1295100D03*
X1302025Y256303D03*
X1290052Y288190D03*
X1292852D03*
Y285690D03*
X1305078Y290755D03*
X1297078D03*
X1301078D03*
X1287552Y288190D03*
X1290052Y285690D03*
X1287552D03*
X1294425Y321425D03*
X1292731Y331820D03*
X1299959Y356954D03*
X1303158Y371043D03*
X1299410Y370976D03*
X1291165Y395248D03*
X1290092Y449118D03*
Y446318D03*
X1299757Y450041D03*
Y452841D03*
Y455641D03*
X1290272Y458309D03*
Y454309D03*
Y462309D03*
X1299304Y487382D03*
X1296783Y511956D03*
X1300817Y568635D03*
X1301194Y565518D03*
X1305836Y660009D03*
X1298963Y659609D03*
X1289811Y677612D03*
X1289317Y706932D03*
X1297667Y832150D03*
X1293500Y827500D03*
Y843500D03*
Y835500D03*
X1296687Y839500D03*
X1293500Y851500D03*
X1294000Y863500D03*
X1296866Y894993D03*
X1305250Y889250D03*
X1291129Y892267D03*
X1294075Y917000D03*
X1297558Y970216D03*
X1302866Y1594253D03*
Y1589522D03*
Y1609607D03*
Y1598984D03*
Y1604876D03*
Y1614338D03*
X1292000Y1644980D03*
X1314887Y45448D03*
X1318859D03*
X1307717Y76140D03*
Y80140D03*
X1320566Y103621D03*
X1310162Y117557D03*
X1305170D03*
X1316277Y112083D03*
X1310162Y122513D03*
Y131731D03*
X1305170Y122513D03*
Y131731D03*
X1310162Y136687D03*
X1305170D03*
X1313546Y180527D03*
X1308863Y180572D03*
X1314627Y171523D03*
X1308863Y185165D03*
X1317269Y192421D03*
X1313501Y185121D03*
X1319432Y190185D03*
X1304811Y206760D03*
X1307055Y279208D03*
X1311159Y281307D03*
X1313149Y288345D03*
Y290845D03*
Y293645D03*
X1315649Y288345D03*
Y290845D03*
Y293645D03*
X1317584Y313058D03*
X1315256Y336510D03*
X1308410Y370899D03*
X1313691Y402642D03*
X1316191D03*
X1310546Y409904D03*
Y407104D03*
X1309117Y398949D03*
X1306617Y401949D03*
X1308066Y413611D03*
X1310866D03*
X1313366D03*
X1315866D03*
X1315806Y423944D03*
X1313306D03*
X1310806D03*
X1308006D03*
X1309750Y455641D03*
Y450041D03*
Y452841D03*
X1308010Y466409D03*
X1307996Y487382D03*
X1311488Y479560D03*
X1307919Y478382D03*
X1307825Y482382D03*
X1305412Y799061D03*
X1321000Y796000D03*
X1313000D03*
X1317000Y799000D03*
Y788000D03*
X1313000D03*
X1305134Y812065D03*
X1317000Y804000D03*
X1313000D03*
X1321000D03*
X1305356Y902597D03*
X1311325Y928918D03*
X1303907Y960093D03*
X1307580Y990314D03*
X1317254Y990777D03*
X1317053Y988111D03*
X1304664Y1023462D03*
X1309937Y1037038D03*
X1319326Y1040723D03*
X1313459Y1081599D03*
X1310589Y1097278D03*
X1313089D03*
X1317437Y1152684D03*
X1318178Y1198321D03*
Y1200821D03*
X1307167Y1245696D03*
X1308276Y1276446D03*
X1308107Y1283395D03*
X1303900Y1288000D03*
X1318287Y1295381D03*
Y1291381D03*
X1311527Y1593853D03*
Y1609207D03*
Y1598584D03*
Y1603315D03*
Y1613938D03*
Y1618669D03*
X1312000Y1644980D03*
X1322232Y3000D03*
X1334223Y33425D03*
X1328003Y32403D03*
X1328318Y27333D03*
X1328799Y172665D03*
Y180665D03*
X1328831Y212864D03*
Y200864D03*
Y208864D03*
Y221864D03*
Y216864D03*
X1325100Y228631D03*
X1330414Y310058D03*
X1325458D03*
X1322540Y313058D03*
X1333332D03*
X1332563Y326356D03*
X1325573Y326719D03*
X1331005Y356670D03*
X1320903Y370995D03*
X1333331Y370905D03*
X1329064Y370951D03*
X1333049Y399268D03*
Y401768D03*
Y396768D03*
X1321016Y399161D03*
Y401661D03*
Y396661D03*
X1325941Y408240D03*
X1328441D03*
X1323441D03*
X1326059Y420393D03*
X1326020Y424240D03*
X1323559Y420393D03*
X1328559D03*
X1326020Y426740D03*
X1329626Y455039D03*
X1332927Y468607D03*
X1325927Y474513D03*
X1326912Y493153D03*
X1325630Y513238D03*
X1335000Y594500D03*
Y641000D03*
Y685500D03*
X1329000Y796000D03*
X1325000Y799000D03*
X1337000Y796000D03*
X1333000Y799000D03*
Y788000D03*
X1329000D03*
X1321000D03*
X1325000D03*
X1329000Y804000D03*
X1324000Y901000D03*
X1328457Y959986D03*
X1321104Y964398D03*
X1323554Y967623D03*
X1333974Y1033483D03*
X1331890Y1051919D03*
X1331359Y1098898D03*
X1334161Y1098518D03*
X1331162Y1104792D03*
X1333905Y1123101D03*
X1331405D03*
X1323405D03*
X1320279Y1131935D03*
Y1134435D03*
Y1136935D03*
Y1139435D03*
X1334305Y1129301D03*
X1331805D03*
X1329305D03*
X1326805D03*
X1324305D03*
X1321805D03*
X1334305Y1125801D03*
X1331805D03*
X1323405D03*
X1320279Y1141935D03*
Y1146935D03*
Y1144435D03*
X1326269Y1152713D03*
Y1155213D03*
X1320493Y1204405D03*
X1334793Y1204617D03*
X1331643Y1200821D03*
Y1198321D03*
X1320493Y1206905D03*
Y1211905D03*
Y1209405D03*
X1334793Y1207117D03*
Y1209617D03*
Y1212117D03*
X1330070Y1297498D03*
X1335470D03*
X1320189Y1589522D03*
Y1594253D03*
X1328850Y1593853D03*
Y1603315D03*
X1320189Y1609607D03*
Y1604876D03*
Y1598984D03*
X1328850Y1609207D03*
Y1598584D03*
Y1613938D03*
Y1618669D03*
X1320189Y1614338D03*
X1332000Y1644980D03*
X1342232Y3000D03*
X1340320Y151540D03*
X1348419Y265222D03*
X1340104Y279117D03*
X1344007Y279054D03*
X1338288Y313058D03*
X1346009Y336080D03*
X1346065Y347106D03*
X1338471Y356959D03*
X1338287Y370905D03*
X1347897Y433975D03*
X1346483Y436164D03*
X1341000Y799000D03*
X1345000Y796000D03*
X1341000Y788000D03*
X1345000D03*
X1337000D03*
X1348917Y796000D03*
X1352817D03*
X1349000Y804000D03*
X1337000D03*
X1345000D03*
X1353948Y943603D03*
X1345948D03*
X1349848Y936755D03*
X1343465Y1026123D03*
X1340665D03*
X1343465Y1028923D03*
X1340665D03*
X1347380Y1057998D03*
Y1055498D03*
X1344880D03*
Y1057998D03*
X1347380Y1060498D03*
Y1062998D03*
X1344880D03*
Y1060498D03*
X1339349Y1098767D03*
X1344241Y1106298D03*
X1345650Y1118396D03*
X1339305Y1129301D03*
X1336805D03*
X1339305Y1125801D03*
X1336805D03*
X1343505Y1136935D03*
Y1134435D03*
Y1139435D03*
Y1131935D03*
X1349907D03*
Y1134435D03*
Y1136935D03*
Y1139435D03*
X1352407Y1131935D03*
Y1134435D03*
Y1136935D03*
Y1139435D03*
X1347300Y1128332D03*
X1343505Y1146935D03*
Y1144435D03*
Y1141935D03*
X1349907D03*
Y1146935D03*
Y1144435D03*
X1352407Y1141935D03*
Y1146935D03*
Y1144435D03*
X1336669Y1152713D03*
Y1155213D03*
X1351405Y1154902D03*
Y1152402D03*
X1341405Y1162384D03*
X1347423Y1204405D03*
X1337108Y1200821D03*
Y1198321D03*
X1345108Y1200821D03*
Y1198321D03*
X1347423Y1209405D03*
Y1211905D03*
Y1206905D03*
X1340870Y1297498D03*
X1346270D03*
X1351670D03*
X1337512Y1589522D03*
Y1594253D03*
X1346173Y1593853D03*
X1337512Y1609607D03*
Y1604876D03*
Y1598984D03*
X1346173Y1609207D03*
Y1598584D03*
Y1603315D03*
X1337512Y1614338D03*
X1346173Y1613938D03*
Y1618669D03*
X1352000Y1644980D03*
X1362232Y3000D03*
X1355900Y146461D03*
X1360122Y141247D03*
X1354802Y152367D03*
X1361039Y327099D03*
Y332055D03*
X1364039Y334973D03*
Y339929D03*
X1361039Y342847D03*
X1364039Y350721D03*
X1361039Y347803D03*
X1364039Y355677D03*
X1360352Y447101D03*
X1363000Y811620D03*
X1353000Y804000D03*
X1359000Y811620D03*
X1357000Y804000D03*
X1361000D03*
X1354185Y906498D03*
X1357948Y938842D03*
X1363173Y994483D03*
X1363905Y1000855D03*
X1366493Y1000828D03*
X1367444Y1003763D03*
X1367884Y1018825D03*
X1357265Y1022766D03*
X1361265Y1019766D03*
X1364237Y1043140D03*
X1357265Y1030266D03*
Y1034266D03*
X1363941Y1047047D03*
X1364418Y1090568D03*
Y1093068D03*
X1366289Y1098518D03*
X1361037Y1098428D03*
X1363290Y1104792D03*
X1355533Y1123101D03*
X1363533D03*
X1366033D03*
X1366433Y1129301D03*
X1355533Y1125801D03*
X1363933D03*
X1366433D03*
X1353933Y1129301D03*
X1356433D03*
X1358933D03*
X1361433D03*
X1363933D03*
X1357397Y1155213D03*
Y1152713D03*
X1366797D03*
Y1155213D03*
X1361723Y1204617D03*
X1364038Y1198321D03*
Y1200821D03*
X1361723Y1212117D03*
Y1209617D03*
Y1207117D03*
X1357070Y1297498D03*
X1354834Y1589522D03*
Y1594253D03*
X1363496Y1593853D03*
X1354834Y1609607D03*
Y1604876D03*
Y1598984D03*
X1363496Y1609207D03*
Y1598584D03*
Y1603315D03*
X1354834Y1614338D03*
X1363496Y1613938D03*
Y1618669D03*
X1382232Y3000D03*
X1376262Y113394D03*
X1378911Y110784D03*
X1380480Y102249D03*
X1384480D03*
X1378505Y133298D03*
X1380652Y134579D03*
X1372354Y157370D03*
X1384280Y195176D03*
X1381780D03*
X1384140Y203393D03*
X1381640D03*
X1386399Y201683D03*
X1378227Y252371D03*
X1384265Y320871D03*
Y325371D03*
X1384253Y346826D03*
X1384447Y356871D03*
X1372232Y361298D03*
X1384174Y362641D03*
X1373748Y397758D03*
X1375108Y420838D03*
X1375171Y424741D03*
X1375375Y428995D03*
X1381000Y804000D03*
X1373000D03*
X1369000D03*
X1373948Y940103D03*
X1371379Y986717D03*
X1381519Y996280D03*
X1370384Y1004680D03*
X1383669Y1011303D03*
Y1017303D03*
Y1023303D03*
X1376601Y1030218D03*
X1374451Y1090568D03*
Y1093068D03*
X1371477Y1098767D03*
X1377087Y1106365D03*
X1377778Y1118396D03*
X1375633Y1136935D03*
Y1134435D03*
Y1139435D03*
Y1131935D03*
X1383366D03*
Y1134435D03*
Y1136935D03*
Y1139435D03*
X1368933Y1125801D03*
X1371433D03*
X1368933Y1129301D03*
X1371433D03*
X1383024Y1152684D03*
X1376861D03*
X1375633Y1146935D03*
Y1144435D03*
Y1141935D03*
X1383366D03*
Y1146935D03*
Y1144435D03*
X1371733Y1162384D03*
X1375459Y1197471D03*
Y1193471D03*
X1379959Y1197471D03*
Y1193471D03*
X1377390Y1244055D03*
Y1250760D03*
Y1254164D03*
X1372157Y1589522D03*
Y1594253D03*
Y1604876D03*
Y1598984D03*
Y1609607D03*
Y1614338D03*
X1372000Y1644980D03*
X1398216Y4469D03*
X1399577Y24773D03*
Y44773D03*
X1388480Y102249D03*
X1391497Y109172D03*
X1394497D03*
X1393504Y106495D03*
X1397248Y116497D03*
X1386505Y133298D03*
X1397248Y130670D03*
Y123584D03*
X1391765Y125107D03*
X1393238Y146012D03*
X1395144Y141228D03*
X1397248Y137757D03*
X1400379Y143762D03*
X1398032Y150847D03*
X1389580Y195176D03*
X1386399Y198883D03*
X1386780Y195176D03*
X1390328Y206838D03*
X1387828D03*
X1393859Y228646D03*
X1400000Y247292D03*
X1399226Y238689D03*
X1392790Y236121D03*
X1389824Y238589D03*
X1392709Y253198D03*
X1385971Y327688D03*
X1386143Y331982D03*
X1386057Y341200D03*
X1385971Y336791D03*
X1386286Y350218D03*
X1399884Y367165D03*
X1387847Y366710D03*
X1397550Y390484D03*
X1400231Y390256D03*
X1387814Y397136D03*
X1389295Y408443D03*
X1391623Y409900D03*
X1386809Y414173D03*
X1388788Y428348D03*
X1393944Y507856D03*
X1394044Y510990D03*
X1397079Y531726D03*
Y536726D03*
Y540726D03*
Y544726D03*
X1395605Y556217D03*
X1400912Y581222D03*
Y591215D03*
X1398530Y811717D03*
X1402417Y811692D03*
X1401300Y820485D03*
X1402000Y876000D03*
Y884000D03*
Y892000D03*
X1387753Y912629D03*
X1394891Y914783D03*
X1402187Y908270D03*
X1387504Y899931D03*
X1390541Y900086D03*
X1389192Y992568D03*
X1395669Y1011303D03*
X1389669D03*
X1394885Y999941D03*
X1392031Y1004375D03*
X1395669Y1017303D03*
Y1023303D03*
X1389669D03*
X1390322Y1057998D03*
Y1055498D03*
X1392822D03*
Y1057998D03*
X1390322Y1060498D03*
Y1062998D03*
X1392822D03*
Y1060498D03*
X1399748Y1098518D03*
X1394496Y1098428D03*
X1396749Y1104792D03*
X1388992Y1123101D03*
X1396992D03*
X1399492D03*
X1385866Y1131935D03*
Y1134435D03*
Y1136935D03*
Y1139435D03*
X1388992Y1125801D03*
X1397392D03*
X1399892D03*
X1387392Y1129301D03*
X1389892D03*
X1392392D03*
X1394892D03*
X1397392D03*
X1399892D03*
X1391856Y1155213D03*
Y1152713D03*
X1385866Y1141935D03*
Y1146935D03*
Y1144435D03*
X1393695Y1204405D03*
X1391380Y1200821D03*
Y1198321D03*
X1393695Y1206905D03*
Y1211905D03*
Y1209405D03*
X1385821Y1260160D03*
X1391821Y1257160D03*
X1394821D03*
X1385821D03*
X1388821D03*
X1397821Y1260160D03*
Y1257160D03*
X1400821Y1260160D03*
Y1257160D03*
X1388821Y1260160D03*
X1394821D03*
X1391821D03*
X1385052Y1303139D03*
X1389052D03*
X1392000Y1644980D03*
X1406898Y53597D03*
X1417498Y90650D03*
X1417248Y95236D03*
X1402098Y95111D03*
X1417248Y102323D03*
X1409248Y109410D03*
Y102323D03*
X1404548Y116497D03*
X1402048D03*
X1404548Y109410D03*
X1409248Y116496D03*
X1406467Y106561D03*
X1402048Y130670D03*
Y123584D03*
X1404548Y123583D03*
X1409248Y130670D03*
Y123583D03*
X1404548Y130670D03*
X1409248Y137756D03*
X1402048Y137757D03*
X1405780Y213539D03*
X1407461Y238714D03*
X1405162Y244297D03*
X1408666Y324733D03*
X1404690Y362209D03*
X1416347Y384373D03*
X1402968Y390177D03*
X1416830Y407134D03*
X1411400Y398032D03*
X1414369Y398056D03*
X1413889Y415642D03*
X1415610Y417644D03*
X1415674Y421278D03*
X1411950Y448466D03*
X1406910Y487982D03*
Y478982D03*
Y483982D03*
Y499982D03*
Y491982D03*
X1408103Y555194D03*
X1410903D03*
X1408103Y563194D03*
X1410903D03*
X1408103Y571194D03*
X1410903D03*
X1406512Y581222D03*
X1403712D03*
Y591215D03*
X1406512D03*
X1405514Y611091D03*
X1413452Y641817D03*
X1418000Y696000D03*
Y724000D03*
X1404249Y735858D03*
X1418000Y745000D03*
X1407482Y750853D03*
X1409115Y773520D03*
X1414597Y792375D03*
X1406483Y811717D03*
X1405402Y819917D03*
X1405500Y880000D03*
Y896000D03*
X1417284Y911009D03*
X1413322Y958908D03*
X1404317Y989436D03*
X1411038Y985379D03*
X1416618Y992307D03*
X1404936Y1098767D03*
X1410546Y1106298D03*
X1411237Y1118396D03*
X1415494Y1139435D03*
Y1136935D03*
Y1134435D03*
Y1131935D03*
X1409092Y1136935D03*
Y1134435D03*
Y1139435D03*
Y1131935D03*
X1402392Y1125801D03*
X1404892D03*
X1402392Y1129301D03*
X1404892D03*
X1409092Y1141935D03*
X1416736Y1152713D03*
Y1155213D03*
X1402256D03*
Y1152713D03*
X1415494Y1144435D03*
Y1146935D03*
Y1141935D03*
X1409092Y1146935D03*
Y1144435D03*
X1406992Y1162384D03*
X1407995Y1204617D03*
X1410310Y1200821D03*
Y1198321D03*
X1404845D03*
Y1200821D03*
X1407995Y1207117D03*
Y1209617D03*
Y1212117D03*
X1409821Y1260160D03*
X1412821D03*
Y1257160D03*
X1409821D03*
X1406821D03*
X1403821D03*
X1415821Y1260160D03*
Y1257160D03*
X1403821Y1260160D03*
X1406821D03*
X1414346Y1303020D03*
X1407825Y1426975D03*
X1404239Y1547755D03*
X1403747Y1570433D03*
X1412000Y1644980D03*
X1426898Y53597D03*
X1417710Y82984D03*
Y75184D03*
Y77784D03*
Y80384D03*
X1420264Y92849D03*
X1417710Y85584D03*
X1422810Y90615D03*
X1427131Y99961D03*
X1427181Y95236D03*
X1427224Y103037D03*
X1417500Y109410D03*
Y116496D03*
X1427358D03*
Y109410D03*
X1421700Y122900D03*
X1427358Y130670D03*
Y123583D03*
X1418725Y130670D03*
X1423515Y137756D03*
X1418720D03*
X1425993Y231226D03*
Y228726D03*
Y226226D03*
Y223726D03*
X1429247Y258880D03*
X1429539Y293796D03*
X1432039D03*
X1421005Y407616D03*
X1431019Y434508D03*
X1427019D03*
X1424196Y446352D03*
X1428782Y445874D03*
X1417856Y455466D03*
X1427484Y470045D03*
X1422903Y469905D03*
X1430930Y500086D03*
X1433310Y504699D03*
X1430810D03*
X1433012Y516979D03*
X1430512D03*
X1431493Y521804D03*
X1427800Y528578D03*
X1432955Y527449D03*
X1431493Y524304D03*
X1427800Y531378D03*
X1421099Y546830D03*
X1430944Y605443D03*
X1427233Y628183D03*
X1424389Y627948D03*
X1418000Y705000D03*
X1429059Y908579D03*
X1426085Y910281D03*
X1429907Y936998D03*
X1424897Y936777D03*
X1430839Y965546D03*
X1420740Y1004766D03*
Y1000766D03*
Y1016266D03*
Y1030766D03*
X1420107Y1052514D03*
X1430005Y1090568D03*
Y1093068D03*
X1431876Y1098518D03*
X1426624Y1098428D03*
X1428877Y1104792D03*
X1421120Y1123101D03*
X1429120D03*
X1431620D03*
X1422020Y1129301D03*
X1424520D03*
X1427020D03*
X1429520D03*
X1432020D03*
X1417994Y1139435D03*
Y1136935D03*
Y1134435D03*
Y1131935D03*
X1421120Y1125801D03*
X1429520D03*
X1432020D03*
X1419520Y1129301D03*
X1432384Y1155213D03*
Y1152713D03*
X1422984D03*
Y1155213D03*
X1417994Y1144435D03*
Y1146935D03*
Y1141935D03*
X1420625Y1204405D03*
X1418310Y1198321D03*
Y1200821D03*
X1420625Y1206905D03*
Y1209405D03*
X1421821Y1257160D03*
X1418821D03*
Y1260160D03*
X1421821D03*
X1431080Y1301702D03*
X1433386Y1343309D03*
X1428840Y1407740D03*
X1422176Y1491198D03*
X1423065Y1508327D03*
X1432499Y1512175D03*
X1423806Y1524252D03*
X1424245Y1543338D03*
X1425558Y1537432D03*
X1425260Y1558072D03*
X1433558Y1555366D03*
X1423701Y1563978D03*
X1432000Y1644980D03*
X1445692Y5374D03*
X1445005Y24773D03*
Y44773D03*
X1435358Y116496D03*
Y109410D03*
X1449761Y115401D03*
Y110445D03*
X1444769D03*
Y115401D03*
X1435358Y102323D03*
X1449761Y124618D03*
X1444769D03*
Y129574D03*
X1435358Y130670D03*
Y123583D03*
X1449761Y129574D03*
X1435358Y137756D03*
X1442682Y151540D03*
X1446332Y191941D03*
X1446199Y188727D03*
X1436449Y228961D03*
X1444418Y229286D03*
X1442956Y226141D03*
X1436449Y226461D03*
X1440156Y226141D03*
X1436449Y223661D03*
X1448111Y222212D03*
Y224712D03*
X1436449Y231461D03*
X1440399Y236611D03*
X1442899D03*
X1444418Y231786D03*
X1445399Y236611D03*
X1448026Y256535D03*
X1440101Y248891D03*
X1442601D03*
X1445101D03*
X1440053Y285690D03*
X1437553D03*
X1440053Y288190D03*
X1442853D03*
Y285690D03*
X1447079Y290755D03*
X1437553Y288190D03*
X1434697Y347125D03*
X1439719Y350387D03*
X1440568Y369566D03*
X1449619Y363290D03*
X1437758Y362584D03*
X1438768Y371655D03*
X1442633Y371502D03*
X1440523Y382747D03*
X1435019Y434508D03*
X1435424Y430361D03*
X1437757Y447201D03*
X1437879Y444269D03*
X1435484Y470045D03*
X1442786Y480705D03*
X1437631Y482134D03*
Y484634D03*
X1449293Y476086D03*
X1445586Y480705D03*
X1441076Y475946D03*
Y478446D03*
X1449293Y478586D03*
Y481086D03*
Y483886D03*
X1435810Y504699D03*
X1447036Y519518D03*
X1435512Y516979D03*
X1439462Y522129D03*
X1444536Y519518D03*
X1439536D03*
X1442036D03*
X1439462Y529929D03*
X1435755Y527449D03*
X1439462Y527129D03*
Y524629D03*
X1443555Y532949D03*
X1446355D03*
X1438882Y572842D03*
X1447037Y585507D03*
X1442444D03*
X1442990Y579475D03*
X1435668Y572975D03*
X1442488Y590145D03*
X1447082Y590190D03*
X1435241Y593796D03*
X1434049Y608311D03*
X1446944Y605443D03*
X1434944D03*
X1438944Y605637D03*
X1437770Y628242D03*
X1440930Y636005D03*
Y633205D03*
Y638805D03*
X1446323Y673183D03*
X1438930Y716363D03*
X1446860Y730735D03*
X1446717Y735536D03*
X1441223Y891957D03*
X1447261Y898571D03*
X1441088Y976409D03*
X1440700Y981763D03*
X1440610Y1021567D03*
X1435266Y1031522D03*
X1437064Y1098767D03*
X1442674Y1106365D03*
X1443365Y1118396D03*
X1441220Y1131935D03*
Y1139435D03*
Y1134435D03*
Y1136935D03*
X1434520Y1125801D03*
X1437020D03*
X1434520Y1129301D03*
X1437020D03*
X1441220Y1141935D03*
Y1144435D03*
Y1146935D03*
X1442448Y1152684D03*
X1437320Y1162384D03*
X1434925Y1204617D03*
X1437240Y1200821D03*
Y1198321D03*
X1434925Y1207117D03*
Y1209617D03*
Y1212117D03*
X1437293Y1546125D03*
X1436801Y1568803D03*
X1464594Y3000D03*
X1462675Y14334D03*
X1457718Y76140D03*
Y80140D03*
X1460466Y76587D03*
Y72615D03*
X1454924Y97475D03*
X1460163Y117557D03*
X1455171D03*
Y122513D03*
X1460163Y131731D03*
Y122513D03*
X1455171Y131731D03*
X1458262Y146461D03*
X1460163Y136687D03*
X1455171D03*
X1462484Y141247D03*
X1457164Y152367D03*
X1463547Y180527D03*
X1458864Y180572D03*
X1464628Y171523D03*
X1458864Y185165D03*
X1463502Y185121D03*
X1452832Y184619D03*
X1464158Y192490D03*
X1454812Y206760D03*
X1456026Y256535D03*
X1452026Y256303D03*
X1457056Y279208D03*
X1461160Y281307D03*
X1465650Y293645D03*
X1455079Y290755D03*
X1451079D03*
X1465650Y288345D03*
Y290845D03*
X1463150Y288345D03*
Y290845D03*
Y293645D03*
X1451215Y323193D03*
X1451330Y327588D03*
X1451272Y340971D03*
X1451344Y336620D03*
X1451300Y332225D03*
X1451387Y345609D03*
X1451186Y350447D03*
X1458982Y356861D03*
X1459873Y391705D03*
X1463145Y391579D03*
X1458214Y406231D03*
X1464536Y433114D03*
X1454944Y605443D03*
X1453000Y633450D03*
Y636250D03*
Y639050D03*
X1461474Y655807D03*
X1451428Y673252D03*
X1454504Y777575D03*
X1461113Y871389D03*
X1452641Y888033D03*
X1460655Y964253D03*
X1457352Y976277D03*
X1452000Y1644980D03*
X1476822Y40780D03*
X1480460Y60922D03*
X1475296Y55513D03*
X1474874Y85731D03*
X1472489Y91951D03*
X1478428Y86046D03*
X1470567Y103621D03*
X1478624Y113394D03*
X1481273Y110784D03*
X1466278Y112083D03*
X1481368Y130898D03*
X1474716Y157370D03*
X1478800Y180665D03*
Y172665D03*
X1478832Y200864D03*
Y212864D03*
Y208864D03*
Y216864D03*
Y221864D03*
X1475101Y228631D03*
X1480589Y252371D03*
X1468309Y408861D03*
X1475236Y412482D03*
X1466231Y423671D03*
X1469538Y416795D03*
X1466653Y428582D03*
X1471375Y433115D03*
X1474713Y685247D03*
X1473489Y861354D03*
X1480343Y914776D03*
X1476094Y1578898D03*
Y1574167D03*
Y1583629D03*
Y1594253D03*
Y1589522D03*
Y1609607D03*
Y1598984D03*
Y1604876D03*
Y1614338D03*
X1472000Y1644980D03*
X1484594Y3000D03*
X1498621Y15043D03*
Y35043D03*
Y27043D03*
X1490842Y102249D03*
X1486842D03*
X1482842D03*
X1493859Y109172D03*
X1496859D03*
X1495866Y106495D03*
X1488867Y133298D03*
X1494127Y125107D03*
X1495600Y146012D03*
X1497506Y141228D03*
X1483014Y134579D03*
X1486642Y195176D03*
X1488761Y198883D03*
X1489142Y195176D03*
X1484142D03*
X1491942D03*
X1488761Y201683D03*
X1492690Y206838D03*
X1490190D03*
X1484002Y203393D03*
X1486502D03*
X1496221Y228646D03*
X1492186Y238589D03*
X1495152Y236121D03*
X1495071Y253198D03*
X1497446Y295877D03*
X1484796Y320359D03*
X1484968Y325025D03*
X1484876Y329377D03*
X1488255Y342921D03*
X1484682Y338394D03*
X1497760Y336543D03*
X1486360Y345200D03*
X1487926Y347387D03*
X1486360Y358700D03*
Y354200D03*
Y349700D03*
X1483813Y368516D03*
X1494286Y372699D03*
X1496473Y769000D03*
X1491062Y793003D03*
X1496500Y792000D03*
X1491425Y801575D03*
X1496845Y813000D03*
X1491425Y845575D03*
X1496500Y836000D03*
X1489650Y836985D03*
X1494954Y895264D03*
X1487240Y924453D03*
X1496072Y953981D03*
X1496140Y1117691D03*
Y1130291D03*
Y1155491D03*
Y1142891D03*
Y1168091D03*
Y1180691D03*
X1493417Y1578898D03*
X1484755Y1578498D03*
X1493417Y1574167D03*
X1484755Y1583229D03*
Y1593853D03*
Y1587960D03*
X1493417Y1583629D03*
Y1589522D03*
Y1594253D03*
X1484755Y1609207D03*
Y1598584D03*
Y1603315D03*
X1493417Y1609607D03*
Y1604876D03*
Y1598984D03*
X1484755Y1613938D03*
Y1618669D03*
X1493417Y1614338D03*
X1492000Y1644980D03*
X1500578Y4469D03*
X1501939Y24773D03*
Y44773D03*
X1509260Y53597D03*
X1504460Y95111D03*
X1511610Y116496D03*
Y109410D03*
Y102323D03*
X1499610Y116497D03*
X1506910D03*
X1504410D03*
X1506910Y109410D03*
X1508829Y106561D03*
X1511610Y123583D03*
X1499610Y130670D03*
Y123584D03*
X1506910Y130670D03*
X1504410D03*
Y123584D03*
X1506910Y123583D03*
X1511610Y130670D03*
Y137756D03*
X1499610Y137757D03*
X1504410D03*
X1502741Y143762D03*
X1500394Y150847D03*
X1508142Y213539D03*
X1509823Y238714D03*
X1502362Y247292D03*
X1501588Y238689D03*
X1507524Y244297D03*
X1503884Y295549D03*
X1509454Y402291D03*
X1514446D03*
X1509454Y397335D03*
X1514446D03*
X1512046Y411509D03*
X1507054Y416465D03*
Y411509D03*
X1512046Y425682D03*
X1507054D03*
X1512046Y416465D03*
X1507054Y430638D03*
X1507034Y888133D03*
X1501812Y938397D03*
X1503572Y1034538D03*
X1501640Y1117691D03*
Y1130291D03*
Y1142891D03*
Y1155491D03*
Y1168091D03*
Y1180691D03*
X1510740Y1578898D03*
X1502078Y1578498D03*
X1510740Y1574167D03*
X1502078Y1583229D03*
Y1593853D03*
Y1587960D03*
X1510740Y1583629D03*
Y1589522D03*
Y1594253D03*
X1502078Y1609207D03*
Y1598584D03*
Y1603315D03*
X1510740Y1609607D03*
Y1604876D03*
Y1598984D03*
X1502078Y1613938D03*
Y1618669D03*
X1510740Y1614338D03*
X1512000Y1644980D03*
X1529260Y53597D03*
X1520072Y82984D03*
Y75184D03*
Y77784D03*
Y80384D03*
X1522626Y92849D03*
X1520072Y85584D03*
X1525172Y90615D03*
X1519860Y90650D03*
X1529493Y99961D03*
X1529543Y95236D03*
X1519610D03*
X1529586Y103037D03*
X1519610Y102323D03*
X1519862Y109410D03*
Y116496D03*
X1529720D03*
Y109410D03*
X1520034Y124576D03*
X1529720Y130670D03*
Y123583D03*
X1521087Y130670D03*
X1526311Y137756D03*
X1521082D03*
X1528355Y228726D03*
Y223726D03*
Y226226D03*
Y231226D03*
X1515779Y351594D03*
X1517456Y390223D03*
X1522448D03*
X1517456Y395179D03*
Y404396D03*
Y409352D03*
X1522448Y395179D03*
Y404396D03*
Y409352D03*
X1517456Y418569D03*
Y423525D03*
X1522448Y418569D03*
X1519063Y876339D03*
X1517344Y896999D03*
X1515743Y888133D03*
X1522881Y901034D03*
X1522954Y897951D03*
X1521085Y921094D03*
X1527267Y932647D03*
X1522209Y937846D03*
X1529128Y952978D03*
X1521085Y957340D03*
X1519863Y977637D03*
X1527096Y997860D03*
X1521939Y1040818D03*
X1522099Y1035521D03*
X1524953Y1051037D03*
X1517855Y1053457D03*
X1528062Y1578898D03*
X1519401Y1578498D03*
X1528062Y1574167D03*
X1519401Y1587960D03*
X1528062Y1583629D03*
Y1589522D03*
Y1594253D03*
X1519401Y1583229D03*
Y1593853D03*
Y1609207D03*
Y1598584D03*
Y1603315D03*
X1528062Y1609607D03*
Y1604876D03*
Y1598984D03*
X1519401Y1613938D03*
Y1618669D03*
X1528062Y1614338D03*
X1547367Y44773D03*
X1547131Y110445D03*
Y115401D03*
X1537720Y116496D03*
Y109410D03*
Y102323D03*
X1547131Y129574D03*
X1537720Y130670D03*
Y123583D03*
X1547131Y124618D03*
X1537720Y137756D03*
X1545044Y151540D03*
X1548561Y188727D03*
X1538811Y226461D03*
X1542518Y226141D03*
X1538811Y228961D03*
Y231461D03*
X1546780Y229286D03*
X1538811Y223661D03*
X1545318Y226141D03*
X1542761Y236611D03*
X1545261D03*
X1546780Y231786D03*
X1542463Y248891D03*
X1544963D03*
X1531609Y258880D03*
X1531901Y293796D03*
X1539915Y288190D03*
X1542415Y285690D03*
X1539915D03*
X1542415Y288190D03*
X1545215D03*
Y285690D03*
X1534401Y293796D03*
X1544736Y305156D03*
X1541534Y322850D03*
X1541283Y354553D03*
X1532067Y1041832D03*
X1531947Y1046212D03*
X1531546Y1062769D03*
X1536724Y1578498D03*
X1545385Y1578898D03*
Y1574167D03*
Y1594253D03*
Y1589522D03*
X1536724Y1583229D03*
X1545385Y1583629D03*
X1536724Y1593853D03*
Y1587960D03*
Y1609207D03*
Y1598584D03*
Y1603315D03*
X1545385Y1609607D03*
Y1598984D03*
Y1604876D03*
Y1614338D03*
X1536724Y1613938D03*
Y1618669D03*
X1532000Y1644980D03*
X1560080Y76140D03*
Y80140D03*
X1562828Y72615D03*
Y76587D03*
X1557286Y97475D03*
X1562525Y117557D03*
X1557533D03*
X1552123Y115401D03*
Y110445D03*
X1562525Y122513D03*
X1552123Y129574D03*
Y124618D03*
X1557533Y131731D03*
Y122513D03*
X1562525Y131731D03*
X1560624Y146461D03*
X1557533Y136687D03*
X1562525D03*
X1564846Y141247D03*
X1559526Y152367D03*
X1561226Y180572D03*
X1548694Y191941D03*
X1555194Y184619D03*
X1561226Y185165D03*
X1557174Y206760D03*
X1550473Y222212D03*
Y224712D03*
X1547761Y236611D03*
X1547463Y248891D03*
X1554388Y256303D03*
X1559418Y279208D03*
X1563522Y281307D03*
X1549441Y290755D03*
X1553441D03*
X1557441D03*
X1550931Y305158D03*
X1556151Y318596D03*
X1556294Y327814D03*
X1556437Y332022D03*
X1556380Y336917D03*
X1556498Y340958D03*
X1553862Y344867D03*
X1551175Y347283D03*
X1556353Y345636D03*
X1554403Y352363D03*
X1556429Y389154D03*
X1563248D03*
X1548629D03*
Y396240D03*
X1562385Y598400D03*
Y602400D03*
Y594400D03*
Y614400D03*
Y606400D03*
Y610400D03*
X1561535Y653161D03*
X1564670Y650122D03*
X1547813Y906581D03*
X1548629Y927836D03*
X1548504Y915689D03*
X1548616Y931602D03*
X1551099Y959096D03*
X1552000Y1644980D03*
X1577236Y85731D03*
X1574851Y91951D03*
X1572929Y103621D03*
X1568640Y112083D03*
X1577078Y157370D03*
X1565909Y180527D03*
X1566990Y171523D03*
X1565864Y185121D03*
X1566520Y192490D03*
X1581194Y208864D03*
X1577463Y228631D03*
X1565512Y288345D03*
X1568012Y293645D03*
Y290845D03*
Y288345D03*
X1565512Y293645D03*
Y290845D03*
X1574845Y338843D03*
X1571625Y333549D03*
X1576940Y398082D03*
Y401482D03*
Y415655D03*
Y412255D03*
Y426428D03*
Y440602D03*
Y429828D03*
Y444002D03*
Y476468D03*
Y490641D03*
Y479868D03*
Y494041D03*
Y520602D03*
Y524002D03*
Y534775D03*
Y538175D03*
X1575000Y565414D03*
Y567914D03*
Y570414D03*
Y572914D03*
Y575414D03*
X1574540Y602205D03*
Y595118D03*
X1579753Y599100D03*
X1578679Y613047D03*
X1578114Y607563D03*
X1574222Y629872D03*
X1569926Y668885D03*
X1575950Y662981D03*
X1570331Y691851D03*
X1575942Y705043D03*
X1572000Y1644980D03*
X1582822Y60922D03*
X1580327Y57448D03*
X1593204Y102249D03*
X1580790Y86046D03*
X1585204Y102249D03*
X1589204D03*
X1580986Y113394D03*
X1583635Y110784D03*
X1591229Y133298D03*
X1583229D03*
X1596489Y125107D03*
X1585376Y134579D03*
X1581162Y180665D03*
Y172665D03*
X1586504Y195176D03*
X1594304D03*
X1589004D03*
X1591123Y198883D03*
X1591504Y195176D03*
X1581194Y212864D03*
Y200864D03*
X1586364Y203393D03*
X1588864D03*
X1591123Y201683D03*
X1595052Y206838D03*
X1592552D03*
X1581194Y221864D03*
Y216864D03*
X1594548Y238589D03*
X1582951Y252371D03*
X1593290Y339876D03*
X1594466Y350984D03*
X1584240Y390995D03*
Y408568D03*
Y405168D03*
Y394395D03*
Y419341D03*
Y422741D03*
Y433515D03*
Y436915D03*
Y472781D03*
Y469381D03*
Y483554D03*
Y486954D03*
Y516915D03*
Y513515D03*
Y531088D03*
Y527688D03*
X1595185Y543925D03*
X1595760Y555000D03*
X1583720Y560500D03*
X1604301Y44773D03*
X1611622Y53597D03*
X1606822Y95111D03*
X1609272Y109410D03*
X1601972Y116497D03*
X1609272D03*
X1606772D03*
X1596221Y109172D03*
X1599221D03*
X1598228Y106495D03*
X1611191Y106561D03*
X1601972Y123584D03*
Y130670D03*
X1606772Y123584D03*
X1609272Y123583D03*
Y130670D03*
X1606772D03*
Y137757D03*
X1597962Y146012D03*
X1599868Y141228D03*
X1601972Y137757D03*
X1605103Y143762D03*
X1602756Y150847D03*
X1610504Y213539D03*
X1598583Y228646D03*
X1604724Y247292D03*
X1597514Y236121D03*
X1612185Y238714D03*
X1603950Y238689D03*
X1609886Y244297D03*
X1597433Y253198D03*
X1596691Y287397D03*
X1596197Y293477D03*
X1608240Y329000D03*
X1603664Y342596D03*
X1605966Y343794D03*
X1598223Y351003D03*
X1602138Y351047D03*
X1599127Y375587D03*
X1596253Y375633D03*
X1596714Y383003D03*
X1599527Y392718D03*
X1596534Y379760D03*
X1599527Y408718D03*
Y400718D03*
Y404718D03*
Y412718D03*
X1614338Y636842D03*
X1622434Y82984D03*
Y80384D03*
Y75184D03*
Y77784D03*
X1624988Y92849D03*
X1622434Y85584D03*
X1622222Y90650D03*
X1627534Y90615D03*
X1621972Y95236D03*
Y102323D03*
X1622224Y109410D03*
Y116496D03*
X1613972D03*
Y102323D03*
Y109410D03*
X1622396Y124576D03*
X1623449Y130670D03*
X1613972D03*
Y123583D03*
X1623444Y137756D03*
X1613972D03*
X1626147Y351033D03*
X1625952Y431029D03*
X1626260Y427017D03*
X1625018Y435029D03*
X1625938Y449873D03*
Y445873D03*
X1627965Y474424D03*
Y488597D03*
Y477824D03*
Y491997D03*
Y521958D03*
Y518558D03*
Y536131D03*
Y532731D03*
Y571997D03*
Y568597D03*
Y582771D03*
Y586171D03*
Y596944D03*
Y600344D03*
Y614517D03*
Y611117D03*
X1618538Y618288D03*
X1620244Y638125D03*
X1627224Y643252D03*
X1617843Y665140D03*
X1613110Y678462D03*
X1624148Y708258D03*
X1627455Y759489D03*
X1619612Y783152D03*
X1620359Y774830D03*
X1619569Y796035D03*
X1620755Y787530D03*
X1613235Y808466D03*
X1620479Y815730D03*
X1620072Y801630D03*
X1616255Y824405D03*
X1619859Y839519D03*
X1614360Y1542860D03*
X1631622Y53597D03*
X1631905Y95236D03*
X1631855Y99961D03*
X1631948Y103037D03*
X1632082Y116496D03*
Y109410D03*
X1640082Y116496D03*
Y109410D03*
Y102323D03*
X1632082Y130670D03*
Y123583D03*
X1640082Y130670D03*
Y123583D03*
X1628673Y137756D03*
X1640082D03*
X1641173Y231461D03*
X1630717Y223726D03*
Y226226D03*
Y231226D03*
Y228726D03*
X1641173Y223661D03*
Y226461D03*
X1644880Y226141D03*
X1641173Y228961D03*
X1644825Y248891D03*
X1633971Y258880D03*
X1644777Y288190D03*
X1642277Y285690D03*
X1644777D03*
X1642277Y288190D03*
X1636763Y293796D03*
X1634263D03*
X1632230Y330400D03*
X1640030Y335550D03*
X1636561Y343072D03*
X1630691Y347432D03*
X1640197Y374690D03*
X1638340Y379536D03*
X1641615Y379600D03*
X1636271Y410394D03*
Y403307D03*
X1637205Y440098D03*
Y437598D03*
Y435098D03*
Y432598D03*
Y430098D03*
X1637665Y458406D03*
Y451319D03*
X1637489Y462264D03*
X1635265Y470737D03*
Y467337D03*
Y484910D03*
Y481510D03*
Y514871D03*
Y511471D03*
Y529044D03*
Y525644D03*
Y564910D03*
Y561510D03*
Y575684D03*
Y579084D03*
Y593257D03*
Y604030D03*
Y589857D03*
Y607430D03*
X1637526Y699930D03*
X1637472Y717830D03*
X1631031Y732430D03*
X1628813Y727045D03*
X1631187Y750630D03*
X1629969Y740826D03*
X1644304Y891353D03*
X1650417Y5374D03*
X1649730Y24773D03*
Y44773D03*
X1659648Y97475D03*
X1659895Y117557D03*
X1654485Y110445D03*
Y115401D03*
X1649493Y110445D03*
Y115401D03*
X1659895Y122513D03*
Y131731D03*
X1654485Y124618D03*
Y129574D03*
X1649493Y124618D03*
Y129574D03*
X1659895Y136687D03*
X1647406Y151540D03*
X1651056Y191941D03*
X1657556Y184619D03*
X1650923Y188727D03*
X1659536Y206760D03*
X1647680Y226141D03*
X1649142Y229286D03*
X1652835Y222212D03*
Y224712D03*
X1645123Y236611D03*
X1650123D03*
X1647623D03*
X1649142Y231786D03*
X1647325Y248891D03*
X1649825D03*
X1652750Y256535D03*
X1656750Y256303D03*
X1647577Y285690D03*
Y288190D03*
X1655803Y290755D03*
X1651803D03*
X1659803D03*
X1654771Y352088D03*
X1645685Y390500D03*
X1655335Y381500D03*
X1655555Y430760D03*
X1655576Y433570D03*
X1655392Y437072D03*
X1655433Y439963D03*
X1655677Y443180D03*
X1655697Y454744D03*
X1655639Y452018D03*
X1653507Y470136D03*
X1655776Y465492D03*
X1655742Y460250D03*
X1645128Y929263D03*
X1645342Y962120D03*
X1657091Y990823D03*
X1649571Y983857D03*
X1649322Y1609607D03*
X1657983Y1609207D03*
X1649322Y1604876D03*
Y1614338D03*
X1657983Y1613938D03*
Y1618669D03*
X1652000Y1644980D03*
X1669319Y3001D03*
X1662442Y76140D03*
Y80140D03*
X1665190Y76587D03*
Y72615D03*
X1679598Y85731D03*
X1677213Y91951D03*
X1675291Y103621D03*
X1664887Y117557D03*
X1671002Y112083D03*
X1664887Y122513D03*
Y131731D03*
X1662986Y146461D03*
X1664887Y136687D03*
X1667208Y141247D03*
X1661888Y152367D03*
X1663588Y180572D03*
X1668271Y180527D03*
X1669352Y171523D03*
X1663588Y185165D03*
X1668226Y185121D03*
X1668882Y192490D03*
X1661780Y279208D03*
X1665884Y281307D03*
X1670374Y290845D03*
Y288345D03*
X1667874Y290845D03*
Y288345D03*
X1670374Y293645D03*
X1667874D03*
X1674226Y324139D03*
X1673203Y332017D03*
X1666860Y353661D03*
X1663650Y353283D03*
X1673723Y353881D03*
X1670323Y353534D03*
X1663760Y410394D03*
Y403307D03*
X1663576Y458406D03*
X1669767Y445908D03*
X1673717Y445787D03*
X1663576Y465492D03*
Y472579D03*
X1666645Y1604876D03*
X1675306Y1609207D03*
X1666645Y1609607D03*
Y1614338D03*
X1675306Y1613938D03*
Y1618669D03*
X1672000Y1644980D03*
X1689319Y3001D03*
X1685184Y60922D03*
X1680020Y55513D03*
X1695566Y102249D03*
X1683152Y86046D03*
X1683348Y113394D03*
X1685997Y110784D03*
X1687566Y102249D03*
X1691566D03*
X1686171Y130898D03*
X1693591Y133298D03*
X1687738Y134579D03*
X1679440Y157370D03*
X1683524Y172665D03*
Y180665D03*
X1691366Y195176D03*
X1688866D03*
X1693485Y198883D03*
X1683556Y200864D03*
Y212864D03*
X1691226Y203393D03*
X1693485Y201683D03*
X1688726Y203393D03*
X1683556Y208864D03*
Y221864D03*
Y216864D03*
X1679825Y228631D03*
X1685313Y252371D03*
X1691117Y321649D03*
X1687164Y336324D03*
X1686408Y332584D03*
X1691743Y353506D03*
X1691182Y357016D03*
X1680518Y385912D03*
Y393924D03*
Y389912D03*
Y409924D03*
Y405924D03*
Y401924D03*
X1677933Y418838D03*
X1689757Y466528D03*
Y471484D03*
Y480701D03*
Y485657D03*
X1692629Y1609207D03*
X1683968Y1609607D03*
Y1604876D03*
Y1614338D03*
X1692629Y1613938D03*
Y1618669D03*
X1692000Y1644980D03*
X1705303Y4470D03*
X1706664Y24774D03*
Y44774D03*
X1709184Y95111D03*
X1698583Y109172D03*
X1701583D03*
X1700590Y106495D03*
X1709134Y116497D03*
X1704334D03*
X1709134Y123584D03*
Y130670D03*
X1704334Y123584D03*
Y130670D03*
X1698851Y125107D03*
X1700324Y146012D03*
X1702230Y141228D03*
X1709134Y137757D03*
X1704334D03*
X1707465Y143762D03*
X1705118Y150847D03*
X1696666Y195176D03*
X1693866D03*
X1697414Y206838D03*
X1694914D03*
X1700945Y228646D03*
X1707086Y247292D03*
X1699876Y236121D03*
X1696910Y238589D03*
X1706312Y238689D03*
X1699795Y253198D03*
X1700223Y292141D03*
X1703609Y287320D03*
X1695142Y303839D03*
X1694749Y466528D03*
Y471484D03*
X1700159Y473640D03*
X1705151D03*
Y487813D03*
X1700159D03*
X1705151Y478596D03*
X1694749Y480701D03*
X1700159Y478596D03*
X1694749Y485657D03*
X1700159Y492769D03*
X1705151D03*
X1706450Y1173065D03*
X1701290Y1609607D03*
Y1604876D03*
Y1614338D03*
X1713985Y53598D03*
X1724796Y82984D03*
Y77784D03*
Y80384D03*
Y75184D03*
Y85584D03*
X1724584Y90650D03*
X1724334Y95236D03*
X1716334Y116496D03*
Y109410D03*
Y102323D03*
X1711634Y116497D03*
Y109410D03*
X1724334Y102323D03*
X1724586Y109410D03*
Y116496D03*
X1713553Y106561D03*
X1724758Y124576D03*
X1725811Y130670D03*
X1716334D03*
Y123583D03*
X1711634D03*
Y130670D03*
X1725806Y137756D03*
X1716334D03*
X1712866Y213539D03*
X1714547Y238714D03*
X1712248Y244297D03*
X1715705Y328692D03*
X1716755Y326179D03*
X1712734Y340534D03*
X1712226Y344028D03*
X1715930Y340969D03*
X1715590Y331719D03*
X1725746Y377173D03*
X1718710Y447486D03*
X1716310Y458334D03*
Y454334D03*
X1724930Y491118D03*
Y488618D03*
Y493618D03*
Y496118D03*
X1713239Y1176038D03*
X1728343Y1185205D03*
X1719692Y1187215D03*
X1718613Y1609607D03*
Y1604876D03*
X1709952Y1609207D03*
Y1618669D03*
X1718613Y1614338D03*
X1709952Y1613938D03*
X1712000Y1644980D03*
X1733985Y53598D03*
X1727350Y92849D03*
X1729896Y90615D03*
X1734267Y95236D03*
X1734217Y99961D03*
X1734310Y103037D03*
X1734444Y116496D03*
Y109410D03*
Y130670D03*
Y123583D03*
X1730647Y137756D03*
X1733079Y223726D03*
Y226226D03*
Y231226D03*
Y228726D03*
X1743535Y223661D03*
X1736333Y258880D03*
X1739125Y293796D03*
X1736625D03*
X1734826Y376499D03*
X1737786Y377173D03*
X1729751D03*
X1733027Y392228D03*
X1728433Y392183D03*
X1739847Y409016D03*
X1735811Y409032D03*
X1732494Y402867D03*
X1728478Y396866D03*
X1733071D03*
X1729302Y439718D03*
Y442518D03*
X1739179Y449118D03*
Y446318D03*
X1738824Y452740D03*
X1736214Y450091D03*
X1737703Y472189D03*
X1740542Y468088D03*
Y465288D03*
X1736592Y487570D03*
Y490070D03*
X1728038Y491870D03*
X1730538D03*
X1733147Y493758D03*
Y496258D03*
X1737393Y1170767D03*
X1728333Y1178240D03*
X1733052Y1187310D03*
X1737689Y1185238D03*
X1737781Y1208993D03*
X1732000Y1644980D03*
X1752778Y5374D03*
X1752091Y24773D03*
Y44773D03*
X1742444Y102323D03*
Y116496D03*
Y109410D03*
X1751855Y110445D03*
Y115401D03*
X1756847D03*
Y110445D03*
X1742444Y130670D03*
Y123583D03*
X1751855Y129574D03*
Y124618D03*
X1756847D03*
Y129574D03*
X1742444Y137756D03*
X1753418Y191941D03*
X1753285Y188727D03*
X1743535Y226461D03*
X1747242Y226141D03*
X1755197Y224712D03*
X1743535Y228961D03*
Y231461D03*
X1751504Y229286D03*
X1755197Y222212D03*
X1750042Y226141D03*
X1752485Y236611D03*
X1749985D03*
X1751504Y231786D03*
X1747485Y236611D03*
X1747187Y248891D03*
X1749687D03*
X1752187D03*
X1755112Y256535D03*
X1749939Y288190D03*
X1747139D03*
X1744639D03*
X1749939Y285690D03*
X1744639D03*
X1747139D03*
X1758165Y290755D03*
X1754165D03*
X1744524Y370010D03*
X1756497Y370976D03*
X1747561Y385161D03*
X1744180Y383966D03*
X1748252Y395248D03*
X1756844Y450041D03*
Y452841D03*
Y455641D03*
X1747179Y449118D03*
Y446318D03*
X1747359Y454309D03*
Y458309D03*
Y462309D03*
X1756391Y487382D03*
X1756089Y542952D03*
X1750879Y541940D03*
X1757402Y825111D03*
Y820155D03*
X1744937Y912517D03*
X1747937D03*
X1750751Y910785D03*
X1758583Y1581027D03*
X1750685Y1621654D03*
X1752000Y1644980D03*
X1765559Y3001D03*
X1764804Y76140D03*
Y80140D03*
X1767552Y76587D03*
Y72615D03*
X1762010Y97475D03*
X1767249Y117557D03*
X1762257D03*
X1773364Y112083D03*
X1762257Y122513D03*
Y131731D03*
X1767249Y122513D03*
Y131731D03*
X1762257Y136687D03*
X1767249D03*
X1765950Y180572D03*
X1770633Y180527D03*
X1771714Y171523D03*
X1759918Y184619D03*
X1770588Y185121D03*
X1765950Y185165D03*
X1771244Y192490D03*
X1761898Y206760D03*
X1759112Y256303D03*
X1764142Y279208D03*
X1768246Y281307D03*
X1772736Y293645D03*
X1770236D03*
Y290845D03*
Y288345D03*
X1772736Y290845D03*
Y288345D03*
X1762165Y290755D03*
X1760497Y371070D03*
X1765497Y370899D03*
X1766204Y398949D03*
X1770778Y402642D03*
X1773278D03*
X1767633Y409904D03*
Y407104D03*
X1763704Y401949D03*
X1767953Y413611D03*
X1770453D03*
X1772953D03*
X1772893Y423944D03*
X1770393D03*
X1767893D03*
X1765093D03*
X1765153Y413611D03*
X1766837Y450041D03*
Y452841D03*
Y455641D03*
X1765097Y466409D03*
X1765083Y487382D03*
X1764912Y482382D03*
X1768575Y479560D03*
X1765006Y478382D03*
X1758957Y543036D03*
X1761953Y706827D03*
X1772768Y818696D03*
X1761953Y865160D03*
X1773600Y888100D03*
X1773614Y895275D03*
X1773600Y902800D03*
X1770680Y926322D03*
X1763818Y926241D03*
X1766313Y1580198D03*
X1761072Y1590719D03*
X1760422Y1640303D03*
X1768422D03*
X1772422D03*
X1772000Y1644980D03*
X1788884Y59871D03*
X1782382Y55513D03*
X1781960Y85731D03*
X1779575Y91951D03*
X1786466Y85923D03*
X1777653Y103621D03*
X1785886Y172665D03*
Y180665D03*
X1785779Y192665D03*
X1785918Y200864D03*
Y208864D03*
X1782187Y228631D03*
X1790136Y399161D03*
Y401661D03*
Y396661D03*
X1778103Y399161D03*
Y401661D03*
Y396661D03*
X1783028Y408240D03*
X1785528D03*
X1780528D03*
X1783107Y424240D03*
X1780646Y420393D03*
X1785646D03*
X1783146D03*
X1783107Y426740D03*
X1786713Y455039D03*
X1790014Y468607D03*
X1783014Y474513D03*
X1784602Y564092D03*
X1778801Y836469D03*
X1782600Y874500D03*
X1788400Y888100D03*
X1781000Y888087D03*
X1788396Y895066D03*
X1788300Y902800D03*
X1780665Y902796D03*
X1786256Y927626D03*
X1784306Y924601D03*
X1786256Y930626D03*
X1781263Y964660D03*
X1784763D03*
X1780662Y1108413D03*
X1783262D03*
X1778062D03*
X1775462D03*
X1785321Y1121122D03*
X1787921D03*
X1790521D03*
X1780566Y1111038D03*
X1783166D03*
X1777966D03*
X1775366D03*
X1774899Y1139822D03*
X1777399D03*
X1790521Y1130822D03*
X1781874Y1139822D03*
X1787921Y1130822D03*
X1785321D03*
X1784374Y1139822D03*
X1777399Y1147822D03*
X1774899D03*
X1779581Y1222200D03*
Y1219400D03*
Y1216600D03*
Y1213800D03*
X1782581Y1222200D03*
Y1219400D03*
Y1216600D03*
Y1213800D03*
X1780397Y1237469D03*
Y1230569D03*
Y1228069D03*
X1779581Y1225000D03*
X1782581D03*
X1785961Y1224892D03*
X1780397Y1234969D03*
Y1241869D03*
Y1244369D03*
Y1248769D03*
Y1251269D03*
X1791099Y1260421D03*
X1778227Y1438099D03*
X1778104Y1470289D03*
X1791570Y74535D03*
X1804758Y294429D03*
X1793524Y303343D03*
X1805196Y300952D03*
X1804984Y433975D03*
X1803570Y436164D03*
X1793149Y662810D03*
X1798705Y718793D03*
X1791302Y829031D03*
X1794163Y968760D03*
X1797963D03*
X1792263Y962960D03*
X1806206Y1114589D03*
X1803506D03*
X1800906D03*
X1798306D03*
X1798702Y1124328D03*
X1801302D03*
X1803902D03*
X1806602D03*
X1793221Y1121122D03*
Y1130822D03*
X1804532Y1133356D03*
X1807232D03*
X1807035Y1136912D03*
X1796607Y1200108D03*
X1801285Y1213373D03*
X1801147Y1208555D03*
X1802844Y1227695D03*
X1803885Y1435046D03*
X1806428Y1444543D03*
X1803762Y1467236D03*
X1792000Y1644980D03*
X1822983Y346053D03*
Y366053D03*
Y386053D03*
Y406053D03*
Y426053D03*
Y446053D03*
X1817439Y447101D03*
X1822983Y466053D03*
Y486053D03*
Y506053D03*
Y526053D03*
Y546053D03*
Y566053D03*
Y586053D03*
Y606053D03*
Y626053D03*
Y646053D03*
Y666053D03*
Y686053D03*
Y706053D03*
Y726053D03*
Y746053D03*
Y766053D03*
Y786053D03*
Y806053D03*
Y826053D03*
Y846053D03*
Y866053D03*
Y886053D03*
Y906053D03*
Y926053D03*
Y946053D03*
X1816322Y977215D03*
X1810346Y1082250D03*
X1809535Y1136912D03*
X1813885Y1144912D03*
X1816385D03*
X1809897Y1237285D03*
Y1230385D03*
Y1232885D03*
Y1239785D03*
Y1244185D03*
Y1246685D03*
X1810018Y1295944D03*
X1812818D03*
X1815618Y1298744D03*
Y1295944D03*
X1812818Y1298744D03*
X1810018D03*
X1809342Y1476733D03*
X1812000Y1644980D03*
X1825559Y3001D03*
X1836543Y4470D03*
X1837904Y24774D03*
Y44774D03*
Y64774D03*
Y84774D03*
Y104774D03*
Y124774D03*
Y144774D03*
Y164774D03*
Y184774D03*
Y204774D03*
Y224774D03*
Y244774D03*
Y264774D03*
Y284774D03*
Y304774D03*
X1837728Y324733D03*
X1830094Y333210D03*
X1830472Y960970D03*
X1837937Y973244D03*
X1831511Y978888D03*
X1837937Y993244D03*
Y1013244D03*
Y1033244D03*
Y1053244D03*
Y1073244D03*
Y1093244D03*
X1824706Y1100185D03*
X1828272Y1095968D03*
X1837937Y1113244D03*
Y1133244D03*
Y1153244D03*
Y1173244D03*
Y1193244D03*
Y1213244D03*
Y1253244D03*
Y1273244D03*
Y1293244D03*
Y1313244D03*
Y1333244D03*
Y1353244D03*
Y1373244D03*
Y1393244D03*
Y1433244D03*
Y1453244D03*
Y1473244D03*
Y1493244D03*
Y1513244D03*
Y1533244D03*
Y1553244D03*
Y1573244D03*
X1837933Y1636171D03*
X1832000Y1644980D03*
G54D11*
X13780Y1226024D03*
X1304528Y1141024D03*
X1761614Y1215000D03*
X1827165Y1235630D03*
G54D20*
X266841Y421555D03*
X295856D03*
X723927D03*
X752942D03*
X1117017Y583957D03*
X1181014Y421555D03*
X1210029D03*
X1574104Y583957D03*
X1638101Y421555D03*
X1667116D03*
G54D30*
G01X-20602Y-468335D02*
Y-543335D01*
X479398D01*
Y-468335D01*
X-20602D01*
G01X-8602Y-533335D02*
Y-538335D01*
G01X-10059Y-533335D02*
X-7145D01*
G01X-2235Y-538335D02*
X-4769D01*
Y-533335D01*
X-2235D01*
G01X-3249Y-535752D02*
X-4769D01*
G01X331Y-533335D02*
Y-538335D01*
X2865D01*
G01X6698Y-538502D02*
X6571Y-538418D01*
Y-538252D01*
X6698Y-538168D01*
X6825Y-538252D01*
Y-538418D01*
X6698Y-538502D01*
G01Y-536252D02*
X6571Y-536168D01*
Y-536002D01*
X6698Y-535918D01*
X6825Y-536002D01*
Y-536168D01*
X6698Y-536252D01*
G01X11481Y-540002D02*
X10848Y-539168D01*
X10531Y-538335D01*
Y-535002D01*
X10848Y-534168D01*
X11481Y-533335D01*
G01X16898D02*
X16391Y-533502D01*
X16011Y-533918D01*
X15758Y-534418D01*
X15568Y-535085D01*
X15505Y-535835D01*
X15568Y-536585D01*
X15758Y-537252D01*
X16011Y-537752D01*
X16391Y-538168D01*
X16898Y-538335D01*
X17405Y-538168D01*
X17785Y-537752D01*
X18038Y-537252D01*
X18228Y-536585D01*
X18291Y-535835D01*
X18228Y-535085D01*
X18038Y-534418D01*
X17785Y-533918D01*
X17405Y-533502D01*
X16898Y-533335D01*
G01X20605Y-537335D02*
X20985Y-537918D01*
X21491Y-538252D01*
X22061Y-538335D01*
X22568Y-538252D01*
X23075Y-537835D01*
X23391Y-537335D01*
X23455Y-536835D01*
X23328Y-536252D01*
X22885Y-535835D01*
X22441Y-535668D01*
X21871D01*
G01X22441D02*
X22821Y-535418D01*
X23138Y-535002D01*
X23265Y-534502D01*
X23138Y-534002D01*
X22821Y-533585D01*
X22251Y-533335D01*
X21681Y-533418D01*
X21111Y-533752D01*
G01X27415Y-540002D02*
X28048Y-539168D01*
X28365Y-538335D01*
Y-535002D01*
X28048Y-534168D01*
X27415Y-533335D01*
G01X30805Y-537335D02*
X31185Y-537918D01*
X31691Y-538252D01*
X32261Y-538335D01*
X32768Y-538252D01*
X33275Y-537835D01*
X33591Y-537335D01*
X33655Y-536835D01*
X33528Y-536252D01*
X33085Y-535835D01*
X32641Y-535668D01*
X32071D01*
G01X32641D02*
X33021Y-535418D01*
X33338Y-535002D01*
X33465Y-534502D01*
X33338Y-534002D01*
X33021Y-533585D01*
X32451Y-533335D01*
X31881Y-533418D01*
X31311Y-533752D01*
G01X36095Y-534168D02*
X36475Y-533668D01*
X36918Y-533418D01*
X37425Y-533335D01*
X38058Y-533502D01*
X38501Y-533918D01*
X38628Y-534418D01*
X38565Y-534918D01*
X38311Y-535335D01*
X37045Y-536168D01*
X36475Y-536752D01*
X36095Y-537585D01*
X35968Y-538335D01*
X38628D01*
G01X42271D02*
X42398Y-537252D01*
X42588Y-536335D01*
X42841Y-535502D01*
X43158Y-534585D01*
X43665Y-533335D01*
X41131D01*
G01X46675Y-536668D02*
X48321D01*
G01X51395Y-534168D02*
X51775Y-533668D01*
X52218Y-533418D01*
X52725Y-533335D01*
X53358Y-533502D01*
X53801Y-533918D01*
X53928Y-534418D01*
X53865Y-534918D01*
X53611Y-535335D01*
X52345Y-536168D01*
X51775Y-536752D01*
X51395Y-537585D01*
X51268Y-538335D01*
X53928D01*
G01X56305Y-537335D02*
X56685Y-537918D01*
X57191Y-538252D01*
X57761Y-538335D01*
X58268Y-538252D01*
X58775Y-537835D01*
X59091Y-537335D01*
X59155Y-536835D01*
X59028Y-536252D01*
X58585Y-535835D01*
X58141Y-535668D01*
X57571D01*
G01X58141D02*
X58521Y-535418D01*
X58838Y-535002D01*
X58965Y-534502D01*
X58838Y-534002D01*
X58521Y-533585D01*
X57951Y-533335D01*
X57381Y-533418D01*
X56811Y-533752D01*
G01X63558Y-538335D02*
Y-533335D01*
X61215Y-536918D01*
X64381D01*
G01X66505Y-537585D02*
X66885Y-538002D01*
X67328Y-538252D01*
X67898Y-538335D01*
X68468Y-538168D01*
X68911Y-537835D01*
X69228Y-537252D01*
X69291Y-536585D01*
X69165Y-535918D01*
X68848Y-535502D01*
X68405Y-535168D01*
X67961Y-535085D01*
X67518Y-535168D01*
X66948Y-535502D01*
X67138Y-533335D01*
X68848D01*
G01X76895Y-538335D02*
Y-533335D01*
X79301D01*
G01X78415Y-535752D02*
X76895D01*
G01X81615Y-538335D02*
X83198Y-533335D01*
X84781Y-538335D01*
G01X84211Y-536585D02*
X82185D01*
G01X86968Y-538335D02*
X89628Y-533335D01*
G01X86968D02*
X89628Y-538335D01*
G01X93398Y-538502D02*
X93271Y-538418D01*
Y-538252D01*
X93398Y-538168D01*
X93525Y-538252D01*
Y-538418D01*
X93398Y-538502D01*
G01Y-536252D02*
X93271Y-536168D01*
Y-536002D01*
X93398Y-535918D01*
X93525Y-536002D01*
Y-536168D01*
X93398Y-536252D01*
G01X98181Y-540002D02*
X97548Y-539168D01*
X97231Y-538335D01*
Y-535002D01*
X97548Y-534168D01*
X98181Y-533335D01*
G01X103598D02*
X103091Y-533502D01*
X102711Y-533918D01*
X102458Y-534418D01*
X102268Y-535085D01*
X102205Y-535835D01*
X102268Y-536585D01*
X102458Y-537252D01*
X102711Y-537752D01*
X103091Y-538168D01*
X103598Y-538335D01*
X104105Y-538168D01*
X104485Y-537752D01*
X104738Y-537252D01*
X104928Y-536585D01*
X104991Y-535835D01*
X104928Y-535085D01*
X104738Y-534418D01*
X104485Y-533918D01*
X104105Y-533502D01*
X103598Y-533335D01*
G01X107305Y-537335D02*
X107685Y-537918D01*
X108191Y-538252D01*
X108761Y-538335D01*
X109268Y-538252D01*
X109775Y-537835D01*
X110091Y-537335D01*
X110155Y-536835D01*
X110028Y-536252D01*
X109585Y-535835D01*
X109141Y-535668D01*
X108571D01*
G01X109141D02*
X109521Y-535418D01*
X109838Y-535002D01*
X109965Y-534502D01*
X109838Y-534002D01*
X109521Y-533585D01*
X108951Y-533335D01*
X108381Y-533418D01*
X107811Y-533752D01*
G01X114115Y-540002D02*
X114748Y-539168D01*
X115065Y-538335D01*
Y-535002D01*
X114748Y-534168D01*
X114115Y-533335D01*
G01X117505Y-537335D02*
X117885Y-537918D01*
X118391Y-538252D01*
X118961Y-538335D01*
X119468Y-538252D01*
X119975Y-537835D01*
X120291Y-537335D01*
X120355Y-536835D01*
X120228Y-536252D01*
X119785Y-535835D01*
X119341Y-535668D01*
X118771D01*
G01X119341D02*
X119721Y-535418D01*
X120038Y-535002D01*
X120165Y-534502D01*
X120038Y-534002D01*
X119721Y-533585D01*
X119151Y-533335D01*
X118581Y-533418D01*
X118011Y-533752D01*
G01X122921Y-537752D02*
X123365Y-538168D01*
X123871Y-538335D01*
X124378Y-538168D01*
X124821Y-537668D01*
X125138Y-536918D01*
X125265Y-536168D01*
Y-535252D01*
X125138Y-534502D01*
X124821Y-533835D01*
X124441Y-533502D01*
X123998Y-533335D01*
X123491Y-533502D01*
X123111Y-533835D01*
X122858Y-534335D01*
X122731Y-535002D01*
X122858Y-535585D01*
X123175Y-536168D01*
X123555Y-536502D01*
X123998Y-536585D01*
X124505Y-536418D01*
X124885Y-536002D01*
X125265Y-535252D01*
G01X128971Y-538335D02*
X129098Y-537252D01*
X129288Y-536335D01*
X129541Y-535502D01*
X129858Y-534585D01*
X130365Y-533335D01*
X127831D01*
G01X133375Y-536668D02*
X135021D01*
G01X137905Y-537335D02*
X138285Y-537918D01*
X138791Y-538252D01*
X139361Y-538335D01*
X139868Y-538252D01*
X140375Y-537835D01*
X140691Y-537335D01*
X140755Y-536835D01*
X140628Y-536252D01*
X140185Y-535835D01*
X139741Y-535668D01*
X139171D01*
G01X139741D02*
X140121Y-535418D01*
X140438Y-535002D01*
X140565Y-534502D01*
X140438Y-534002D01*
X140121Y-533585D01*
X139551Y-533335D01*
X138981Y-533418D01*
X138411Y-533752D01*
G01X143195Y-536252D02*
X143638Y-535668D01*
X144018Y-535335D01*
X144525Y-535168D01*
X144968Y-535335D01*
X145285Y-535668D01*
X145538Y-536168D01*
X145601Y-536752D01*
X145538Y-537252D01*
X145285Y-537752D01*
X144905Y-538168D01*
X144461Y-538335D01*
X143955Y-538168D01*
X143511Y-537668D01*
X143258Y-536918D01*
X143195Y-536085D01*
X143321Y-535002D01*
X143511Y-534418D01*
X143828Y-533835D01*
X144271Y-533418D01*
X144715Y-533335D01*
X145158Y-533502D01*
X145475Y-533918D01*
G01X149498Y-538335D02*
Y-533335D01*
X148738Y-534335D01*
G01Y-538335D02*
X150258D01*
G01X155358D02*
Y-533335D01*
X153015Y-536918D01*
X156181D01*
G01X174398Y-468335D02*
Y-543335D01*
G01Y-518335D02*
X277398D01*
Y-493335D01*
G01X174398D02*
X277398D01*
G01Y-468335D02*
Y-543335D01*
G01X279398Y-468335D02*
Y-543335D01*
G01X284905Y-528335D02*
Y-523335D01*
X286171D01*
X286678Y-523585D01*
X287058Y-523918D01*
X287375Y-524418D01*
X287628Y-525002D01*
X287691Y-525835D01*
X287628Y-526668D01*
X287375Y-527252D01*
X287058Y-527752D01*
X286678Y-528085D01*
X286171Y-528335D01*
X284905D01*
G01X289815D02*
X291398Y-523335D01*
X292981Y-528335D01*
G01X292411Y-526585D02*
X290385D01*
G01X296498Y-523335D02*
Y-528335D01*
G01X295041Y-523335D02*
X297955D01*
G01X302865Y-528335D02*
X300331D01*
Y-523335D01*
X302865D01*
G01X301851Y-525752D02*
X300331D01*
G01X306698Y-528502D02*
X306571Y-528418D01*
Y-528252D01*
X306698Y-528168D01*
X306825Y-528252D01*
Y-528418D01*
X306698Y-528502D01*
G01Y-526252D02*
X306571Y-526168D01*
Y-526002D01*
X306698Y-525918D01*
X306825Y-526002D01*
Y-526168D01*
X306698Y-526252D01*
G01X279398Y-518335D02*
X479398D01*
G01X285031Y-503335D02*
Y-498335D01*
X286551D01*
X287058Y-498585D01*
X287438Y-499168D01*
X287565Y-499835D01*
X287438Y-500502D01*
X287121Y-501002D01*
X286551Y-501252D01*
X285031D01*
G01X290258Y-503502D02*
X292538Y-498335D01*
G01X295041Y-503335D02*
Y-498335D01*
X297955Y-503335D01*
Y-498335D01*
G01X301598Y-503502D02*
X301471Y-503418D01*
Y-503252D01*
X301598Y-503168D01*
X301725Y-503252D01*
Y-503418D01*
X301598Y-503502D01*
G01Y-501252D02*
X301471Y-501168D01*
Y-501002D01*
X301598Y-500918D01*
X301725Y-501002D01*
Y-501168D01*
X301598Y-501252D01*
G01X279398Y-493335D02*
X479398D01*
G01X285031Y-478335D02*
Y-473335D01*
X286551D01*
X287058Y-473585D01*
X287438Y-474168D01*
X287565Y-474835D01*
X287438Y-475502D01*
X287121Y-476002D01*
X286551Y-476252D01*
X285031D01*
G01X290131Y-478335D02*
Y-473335D01*
X291715D01*
X292221Y-473585D01*
X292538Y-473918D01*
X292665Y-474585D01*
X292538Y-475252D01*
X292158Y-475668D01*
X291715Y-475918D01*
X290131D01*
G01X291715D02*
X292665Y-478335D01*
G01X296498D02*
X295991Y-478252D01*
X295548Y-477918D01*
X295168Y-477418D01*
X294915Y-476835D01*
X294788Y-476168D01*
Y-475502D01*
X294915Y-474835D01*
X295168Y-474252D01*
X295548Y-473752D01*
X295991Y-473418D01*
X296498Y-473335D01*
X297005Y-473418D01*
X297448Y-473752D01*
X297828Y-474252D01*
X298081Y-474835D01*
X298208Y-475502D01*
Y-476168D01*
X298081Y-476835D01*
X297828Y-477418D01*
X297448Y-477918D01*
X297005Y-478252D01*
X296498Y-478335D01*
G01X300331Y-477335D02*
X300648Y-477835D01*
X301028Y-478168D01*
X301471Y-478335D01*
X301978Y-478168D01*
X302358Y-477835D01*
X302738Y-477335D01*
X302865Y-476668D01*
Y-473335D01*
G01X307965Y-478335D02*
X305431D01*
Y-473335D01*
X307965D01*
G01X306951Y-475752D02*
X305431D01*
G01X313191Y-473752D02*
X312811Y-473502D01*
X312368Y-473335D01*
X311861D01*
X311291Y-473585D01*
X310848Y-474002D01*
X310531Y-474502D01*
X310278Y-475335D01*
X310215Y-476085D01*
X310341Y-476835D01*
X310531Y-477335D01*
X310911Y-477835D01*
X311355Y-478168D01*
X311798Y-478335D01*
X312241D01*
X312685Y-478168D01*
X313065Y-477918D01*
X313381Y-477585D01*
G01X316898Y-473335D02*
Y-478335D01*
G01X315441Y-473335D02*
X318355D01*
G01X321998Y-478502D02*
X321871Y-478418D01*
Y-478252D01*
X321998Y-478168D01*
X322125Y-478252D01*
Y-478418D01*
X321998Y-478502D01*
G01Y-476252D02*
X321871Y-476168D01*
Y-476002D01*
X321998Y-475918D01*
X322125Y-476002D01*
Y-476168D01*
X321998Y-476252D01*
G01X394258Y-543563D02*
Y-518563D01*
G01X397031Y-520835D02*
Y-525835D01*
X399565D01*
G01X402638Y-520835D02*
X404158D01*
G01X403398D02*
Y-525835D01*
G01X402638D02*
X404158D01*
G01X409005Y-523168D02*
X409258Y-522918D01*
X409448Y-522502D01*
X409575Y-521918D01*
X409448Y-521418D01*
X409195Y-521085D01*
X408751Y-520835D01*
X407041D01*
Y-525835D01*
X409131D01*
X409575Y-525502D01*
X409828Y-525002D01*
X409955Y-524418D01*
X409828Y-523835D01*
X409448Y-523335D01*
X409005Y-523168D01*
X407041D01*
G01X413598Y-526002D02*
X413471Y-525918D01*
Y-525752D01*
X413598Y-525668D01*
X413725Y-525752D01*
Y-525918D01*
X413598Y-526002D01*
G01Y-523752D02*
X413471Y-523668D01*
Y-523502D01*
X413598Y-523418D01*
X413725Y-523502D01*
Y-523668D01*
X413598Y-523752D01*
G01X437258Y-518563D02*
Y-543563D01*
G01X437398Y-518335D02*
Y-543335D01*
G01X441298Y-520835D02*
Y-525835D01*
G01X439841Y-520835D02*
X442755D01*
G01X446398Y-525835D02*
X446018Y-525752D01*
X445638Y-525418D01*
X445385Y-524835D01*
X445258Y-524168D01*
X445385Y-523502D01*
X445638Y-522918D01*
X446018Y-522585D01*
X446398Y-522502D01*
X446778Y-522585D01*
X447158Y-522918D01*
X447411Y-523502D01*
X447475Y-524168D01*
X447411Y-524835D01*
X447158Y-525418D01*
X446778Y-525752D01*
X446398Y-525835D01*
G01X451498D02*
X451118Y-525752D01*
X450738Y-525418D01*
X450485Y-524835D01*
X450358Y-524168D01*
X450485Y-523502D01*
X450738Y-522918D01*
X451118Y-522585D01*
X451498Y-522502D01*
X451878Y-522585D01*
X452258Y-522918D01*
X452511Y-523502D01*
X452575Y-524168D01*
X452511Y-524835D01*
X452258Y-525418D01*
X451878Y-525752D01*
X451498Y-525835D01*
G01X456598D02*
Y-520835D01*
G01X461698Y-526002D02*
X461571Y-525918D01*
Y-525752D01*
X461698Y-525668D01*
X461825Y-525752D01*
Y-525918D01*
X461698Y-526002D01*
G01Y-523752D02*
X461571Y-523668D01*
Y-523502D01*
X461698Y-523418D01*
X461825Y-523502D01*
Y-523668D01*
X461698Y-523752D01*
G01X437398Y-493335D02*
Y-518335D01*
G01X440031Y-500835D02*
Y-495835D01*
X441615D01*
X442121Y-496085D01*
X442438Y-496418D01*
X442565Y-497085D01*
X442438Y-497752D01*
X442058Y-498168D01*
X441615Y-498418D01*
X440031D01*
G01X441615D02*
X442565Y-500835D01*
G01X447665D02*
X445131D01*
Y-495835D01*
X447665D01*
G01X446651Y-498252D02*
X445131D01*
G01X449915Y-495835D02*
X451498Y-500835D01*
X453081Y-495835D01*
G01X456598Y-501002D02*
X456471Y-500918D01*
Y-500752D01*
X456598Y-500668D01*
X456725Y-500752D01*
Y-500918D01*
X456598Y-501002D01*
G01Y-498752D02*
X456471Y-498668D01*
Y-498502D01*
X456598Y-498418D01*
X456725Y-498502D01*
Y-498668D01*
X456598Y-498752D01*
G01X445411Y-546502D02*
X445518Y-546377D01*
X445598Y-546168D01*
X445651Y-545877D01*
X445598Y-545627D01*
X445491Y-545460D01*
X445305Y-545335D01*
X444585D01*
Y-547835D01*
X445465D01*
X445651Y-547668D01*
X445758Y-547418D01*
X445811Y-547127D01*
X445758Y-546835D01*
X445598Y-546585D01*
X445411Y-546502D01*
X444585D01*
G01X447878Y-547835D02*
Y-546168D01*
G01Y-546460D02*
X447771Y-546293D01*
X447611Y-546210D01*
X447425Y-546168D01*
X447238Y-546252D01*
X447078Y-546418D01*
X446971Y-546668D01*
X446918Y-547002D01*
X446971Y-547335D01*
X447078Y-547585D01*
X447238Y-547752D01*
X447425Y-547835D01*
X447611Y-547793D01*
X447771Y-547668D01*
X447878Y-547502D01*
G01X449198Y-547543D02*
X449331Y-547710D01*
X449518Y-547835D01*
X449678D01*
X449838Y-547752D01*
X449945Y-547627D01*
X449998Y-547460D01*
X449971Y-547210D01*
X449865Y-547085D01*
X449385Y-546835D01*
X449278Y-546543D01*
X449331Y-546335D01*
X449438Y-546210D01*
X449598Y-546168D01*
X449758Y-546210D01*
X449918Y-546335D01*
G01X451398Y-546710D02*
X452251D01*
X452171Y-546418D01*
X452038Y-546252D01*
X451851Y-546168D01*
X451665Y-546210D01*
X451505Y-546335D01*
X451398Y-546627D01*
X451345Y-546877D01*
Y-547127D01*
X451398Y-547377D01*
X451531Y-547627D01*
X451691Y-547793D01*
X451878Y-547835D01*
X452065Y-547752D01*
X452251Y-547502D01*
G01X453518Y-547835D02*
Y-545335D01*
G01Y-546585D02*
X453651Y-546335D01*
X453811Y-546210D01*
X453971Y-546168D01*
X454211Y-546252D01*
X454371Y-546418D01*
X454478Y-546710D01*
Y-547043D01*
X454425Y-547377D01*
X454318Y-547627D01*
X454131Y-547793D01*
X453971Y-547835D01*
X453811Y-547793D01*
X453651Y-547668D01*
X453518Y-547460D01*
G01X456198Y-547835D02*
X456038Y-547793D01*
X455878Y-547627D01*
X455771Y-547335D01*
X455718Y-547002D01*
X455771Y-546668D01*
X455878Y-546377D01*
X456038Y-546210D01*
X456198Y-546168D01*
X456358Y-546210D01*
X456518Y-546377D01*
X456625Y-546668D01*
X456651Y-547002D01*
X456625Y-547335D01*
X456518Y-547627D01*
X456358Y-547793D01*
X456198Y-547835D01*
G01X458878D02*
Y-546168D01*
G01Y-546460D02*
X458771Y-546293D01*
X458611Y-546210D01*
X458425Y-546168D01*
X458238Y-546252D01*
X458078Y-546418D01*
X457971Y-546668D01*
X457918Y-547002D01*
X457971Y-547335D01*
X458078Y-547585D01*
X458238Y-547752D01*
X458425Y-547835D01*
X458611Y-547793D01*
X458771Y-547668D01*
X458878Y-547502D01*
G01X460225Y-547835D02*
Y-546168D01*
G01Y-546502D02*
X460358Y-546335D01*
X460491Y-546210D01*
X460678Y-546168D01*
X460811Y-546210D01*
X460971Y-546335D01*
G01X463278Y-545335D02*
Y-547835D01*
G01Y-547460D02*
X463171Y-547668D01*
X463011Y-547793D01*
X462825Y-547835D01*
X462611Y-547752D01*
X462451Y-547543D01*
X462345Y-547293D01*
X462318Y-547002D01*
X462345Y-546710D01*
X462451Y-546460D01*
X462611Y-546252D01*
X462825Y-546168D01*
X463011Y-546210D01*
X463145Y-546293D01*
X463278Y-546460D01*
G01X466665Y-547835D02*
Y-545335D01*
X467331D01*
X467545Y-545460D01*
X467678Y-545627D01*
X467731Y-545960D01*
X467678Y-546293D01*
X467518Y-546502D01*
X467331Y-546627D01*
X466665D01*
G01X467331D02*
X467731Y-547835D01*
G01X468998Y-546710D02*
X469851D01*
X469771Y-546418D01*
X469638Y-546252D01*
X469451Y-546168D01*
X469265Y-546210D01*
X469105Y-546335D01*
X468998Y-546627D01*
X468945Y-546877D01*
Y-547127D01*
X468998Y-547377D01*
X469131Y-547627D01*
X469291Y-547793D01*
X469478Y-547835D01*
X469665Y-547752D01*
X469851Y-547502D01*
G01X471118Y-546168D02*
X471598Y-547835D01*
X472078Y-546168D01*
G01X473798Y-547918D02*
X473745Y-547877D01*
Y-547793D01*
X473798Y-547752D01*
X473851Y-547793D01*
Y-547877D01*
X473798Y-547918D01*
G01X475545Y-547543D02*
X475731Y-547752D01*
X475945Y-547835D01*
X476158Y-547752D01*
X476345Y-547502D01*
X476478Y-547127D01*
X476531Y-546752D01*
Y-546293D01*
X476478Y-545918D01*
X476345Y-545585D01*
X476185Y-545418D01*
X475998Y-545335D01*
X475785Y-545418D01*
X475625Y-545585D01*
X475518Y-545835D01*
X475465Y-546168D01*
X475518Y-546460D01*
X475651Y-546752D01*
X475811Y-546918D01*
X475998Y-546960D01*
X476211Y-546877D01*
X476371Y-546668D01*
X476531Y-546293D01*
G01X478411Y-546502D02*
X478518Y-546377D01*
X478598Y-546168D01*
X478651Y-545877D01*
X478598Y-545627D01*
X478491Y-545460D01*
X478305Y-545335D01*
X477585D01*
Y-547835D01*
X478465D01*
X478651Y-547668D01*
X478758Y-547418D01*
X478811Y-547127D01*
X478758Y-546835D01*
X478598Y-546585D01*
X478411Y-546502D01*
X477585D01*
G01X-1490433Y-1677216D02*
Y3837819D01*
X4496476D01*
Y-1677216D01*
X-1490433D01*
G01X-7782Y-515685D02*
X-6215D01*
Y-517575D01*
X-6685Y-518205D01*
X-7234Y-518625D01*
X-8017Y-518835D01*
X-8800Y-518625D01*
X-9349Y-518205D01*
X-9819Y-517575D01*
X-10132Y-516840D01*
X-10289Y-516000D01*
Y-515265D01*
X-10132Y-514635D01*
X-9819Y-513900D01*
X-9349Y-513270D01*
X-8879Y-512850D01*
X-8252Y-512535D01*
X-7704D01*
X-7077Y-512745D01*
X-6607Y-513165D01*
G01X-3675Y-512535D02*
Y-517050D01*
X-3362Y-517995D01*
X-2735Y-518625D01*
X-1952Y-518835D01*
X-1169Y-518625D01*
X-542Y-517995D01*
X-229Y-517050D01*
Y-512535D01*
G01X3408D02*
X5288D01*
G01X4348D02*
Y-518835D01*
G01X3408D02*
X5288D01*
G01X9003Y-517995D02*
X9630Y-518520D01*
X10335Y-518835D01*
X10961D01*
X11588Y-518520D01*
X12058Y-517995D01*
X12293Y-517260D01*
X12136Y-516525D01*
X11745Y-515895D01*
X11040Y-515475D01*
X10100Y-515265D01*
X9551Y-514845D01*
X9316Y-514110D01*
X9473Y-513375D01*
X9865Y-512850D01*
X10413Y-512535D01*
X10961D01*
X11510Y-512745D01*
X11980Y-513270D01*
G01X15303Y-518835D02*
Y-512535D01*
G01X18593D02*
Y-518835D01*
G01Y-515685D02*
X15303D01*
G01X21290Y-518835D02*
X23248Y-512535D01*
X25206Y-518835D01*
G01X24501Y-516630D02*
X21995D01*
G01X27746Y-518835D02*
Y-512535D01*
X31350Y-518835D01*
Y-512535D01*
G01X40425Y-518835D02*
Y-512535D01*
X41991D01*
X42618Y-512850D01*
X43088Y-513270D01*
X43480Y-513900D01*
X43793Y-514635D01*
X43871Y-515685D01*
X43793Y-516735D01*
X43480Y-517470D01*
X43088Y-518100D01*
X42618Y-518520D01*
X41991Y-518835D01*
X40425D01*
G01X47508Y-512535D02*
X49388D01*
G01X48448D02*
Y-518835D01*
G01X47508D02*
X49388D01*
G01X53103Y-517995D02*
X53730Y-518520D01*
X54435Y-518835D01*
X55061D01*
X55688Y-518520D01*
X56158Y-517995D01*
X56393Y-517260D01*
X56236Y-516525D01*
X55845Y-515895D01*
X55140Y-515475D01*
X54200Y-515265D01*
X53651Y-514845D01*
X53416Y-514110D01*
X53573Y-513375D01*
X53965Y-512850D01*
X54513Y-512535D01*
X55061D01*
X55610Y-512745D01*
X56080Y-513270D01*
G01X61048Y-512535D02*
Y-518835D01*
G01X59246Y-512535D02*
X62850D01*
G01X67348Y-519045D02*
X67191Y-518940D01*
Y-518730D01*
X67348Y-518625D01*
X67505Y-518730D01*
Y-518940D01*
X67348Y-519045D01*
G01X73491Y-519990D02*
X73805Y-518625D01*
G01X79948Y-512535D02*
Y-518835D01*
G01X78146Y-512535D02*
X81750D01*
G01X84290Y-518835D02*
X86248Y-512535D01*
X88206Y-518835D01*
G01X87501Y-516630D02*
X84995D01*
G01X92548Y-518835D02*
X91921Y-518730D01*
X91373Y-518310D01*
X90903Y-517680D01*
X90590Y-516945D01*
X90433Y-516105D01*
Y-515265D01*
X90590Y-514425D01*
X90903Y-513690D01*
X91373Y-513060D01*
X91921Y-512640D01*
X92548Y-512535D01*
X93175Y-512640D01*
X93723Y-513060D01*
X94193Y-513690D01*
X94506Y-514425D01*
X94663Y-515265D01*
Y-516105D01*
X94506Y-516945D01*
X94193Y-517680D01*
X93723Y-518310D01*
X93175Y-518730D01*
X92548Y-518835D01*
G01X98848D02*
Y-516000D01*
X97281Y-512535D01*
G01X100415D02*
X98848Y-516000D01*
G01X103425Y-512535D02*
Y-517050D01*
X103738Y-517995D01*
X104365Y-518625D01*
X105148Y-518835D01*
X105931Y-518625D01*
X106558Y-517995D01*
X106871Y-517050D01*
Y-512535D01*
G01X109490Y-518835D02*
X111448Y-512535D01*
X113406Y-518835D01*
G01X112701Y-516630D02*
X110195D01*
G01X115946Y-518835D02*
Y-512535D01*
X119550Y-518835D01*
Y-512535D01*
G01X-6529Y-523060D02*
X-6999Y-522745D01*
X-7547Y-522535D01*
X-8174D01*
X-8879Y-522850D01*
X-9427Y-523375D01*
X-9819Y-524005D01*
X-10132Y-525055D01*
X-10210Y-526000D01*
X-10054Y-526945D01*
X-9819Y-527575D01*
X-9349Y-528205D01*
X-8800Y-528625D01*
X-8252Y-528835D01*
X-7704D01*
X-7155Y-528625D01*
X-6685Y-528310D01*
X-6294Y-527890D01*
G01X-2892Y-522535D02*
X-1012D01*
G01X-1952D02*
Y-528835D01*
G01X-2892D02*
X-1012D01*
G01X4348Y-522535D02*
Y-528835D01*
G01X2546Y-522535D02*
X6150D01*
G01X10648Y-528835D02*
Y-526000D01*
X9081Y-522535D01*
G01X12215D02*
X10648Y-526000D01*
G01X21525Y-527575D02*
X21995Y-528310D01*
X22621Y-528730D01*
X23326Y-528835D01*
X23953Y-528730D01*
X24580Y-528205D01*
X24971Y-527575D01*
X25050Y-526945D01*
X24893Y-526210D01*
X24345Y-525685D01*
X23796Y-525475D01*
X23091D01*
G01X23796D02*
X24266Y-525160D01*
X24658Y-524635D01*
X24815Y-524005D01*
X24658Y-523375D01*
X24266Y-522850D01*
X23561Y-522535D01*
X22856Y-522640D01*
X22151Y-523060D01*
G01X27825Y-527575D02*
X28295Y-528310D01*
X28921Y-528730D01*
X29626Y-528835D01*
X30253Y-528730D01*
X30880Y-528205D01*
X31271Y-527575D01*
X31350Y-526945D01*
X31193Y-526210D01*
X30645Y-525685D01*
X30096Y-525475D01*
X29391D01*
G01X30096D02*
X30566Y-525160D01*
X30958Y-524635D01*
X31115Y-524005D01*
X30958Y-523375D01*
X30566Y-522850D01*
X29861Y-522535D01*
X29156Y-522640D01*
X28451Y-523060D01*
G01X34125Y-527575D02*
X34595Y-528310D01*
X35221Y-528730D01*
X35926Y-528835D01*
X36553Y-528730D01*
X37180Y-528205D01*
X37571Y-527575D01*
X37650Y-526945D01*
X37493Y-526210D01*
X36945Y-525685D01*
X36396Y-525475D01*
X35691D01*
G01X36396D02*
X36866Y-525160D01*
X37258Y-524635D01*
X37415Y-524005D01*
X37258Y-523375D01*
X36866Y-522850D01*
X36161Y-522535D01*
X35456Y-522640D01*
X34751Y-523060D01*
G01X41991Y-528835D02*
X42148Y-527470D01*
X42383Y-526315D01*
X42696Y-525265D01*
X43088Y-524110D01*
X43715Y-522535D01*
X40581D01*
G01X48291Y-528835D02*
X48448Y-527470D01*
X48683Y-526315D01*
X48996Y-525265D01*
X49388Y-524110D01*
X50015Y-522535D01*
X46881D01*
G01X54591Y-529990D02*
X54905Y-528625D01*
G01X61048Y-522535D02*
Y-528835D01*
G01X59246Y-522535D02*
X62850D01*
G01X65390Y-528835D02*
X67348Y-522535D01*
X69306Y-528835D01*
G01X68601Y-526630D02*
X66095D01*
G01X72708Y-522535D02*
X74588D01*
G01X73648D02*
Y-528835D01*
G01X72708D02*
X74588D01*
G01X77598Y-522535D02*
X78695Y-528835D01*
X79948Y-522535D01*
X81201Y-528835D01*
X82298Y-522535D01*
G01X84290Y-528835D02*
X86248Y-522535D01*
X88206Y-528835D01*
G01X87501Y-526630D02*
X84995D01*
G01X90746Y-528835D02*
Y-522535D01*
X94350Y-528835D01*
Y-522535D01*
G01X104756Y-530935D02*
X103973Y-529885D01*
X103581Y-528835D01*
Y-524635D01*
X103973Y-523585D01*
X104756Y-522535D01*
G01X116181Y-528835D02*
Y-522535D01*
X118140D01*
X118766Y-522850D01*
X119158Y-523270D01*
X119315Y-524110D01*
X119158Y-524950D01*
X118688Y-525475D01*
X118140Y-525790D01*
X116181D01*
G01X118140D02*
X119315Y-528835D01*
G01X124048Y-529045D02*
X123891Y-528940D01*
Y-528730D01*
X124048Y-528625D01*
X124205Y-528730D01*
Y-528940D01*
X124048Y-529045D01*
G01X130348Y-528835D02*
X129721Y-528730D01*
X129173Y-528310D01*
X128703Y-527680D01*
X128390Y-526945D01*
X128233Y-526105D01*
Y-525265D01*
X128390Y-524425D01*
X128703Y-523690D01*
X129173Y-523060D01*
X129721Y-522640D01*
X130348Y-522535D01*
X130975Y-522640D01*
X131523Y-523060D01*
X131993Y-523690D01*
X132306Y-524425D01*
X132463Y-525265D01*
Y-526105D01*
X132306Y-526945D01*
X131993Y-527680D01*
X131523Y-528310D01*
X130975Y-528730D01*
X130348Y-528835D01*
G01X136648Y-529045D02*
X136491Y-528940D01*
Y-528730D01*
X136648Y-528625D01*
X136805Y-528730D01*
Y-528940D01*
X136648Y-529045D01*
G01X144671Y-523060D02*
X144201Y-522745D01*
X143653Y-522535D01*
X143026D01*
X142321Y-522850D01*
X141773Y-523375D01*
X141381Y-524005D01*
X141068Y-525055D01*
X140990Y-526000D01*
X141146Y-526945D01*
X141381Y-527575D01*
X141851Y-528205D01*
X142400Y-528625D01*
X142948Y-528835D01*
X143496D01*
X144045Y-528625D01*
X144515Y-528310D01*
X144906Y-527890D01*
G01X149248Y-529045D02*
X149091Y-528940D01*
Y-528730D01*
X149248Y-528625D01*
X149405Y-528730D01*
Y-528940D01*
X149248Y-529045D01*
G01X155940Y-530935D02*
X156723Y-529885D01*
X157115Y-528835D01*
Y-524635D01*
X156723Y-523585D01*
X155940Y-522535D01*
G01X-10054Y-508835D02*
Y-502535D01*
X-6450Y-508835D01*
Y-502535D01*
G01X-1952Y-508835D02*
X-2579Y-508730D01*
X-3127Y-508310D01*
X-3597Y-507680D01*
X-3910Y-506945D01*
X-4067Y-506105D01*
Y-505265D01*
X-3910Y-504425D01*
X-3597Y-503690D01*
X-3127Y-503060D01*
X-2579Y-502640D01*
X-1952Y-502535D01*
X-1325Y-502640D01*
X-777Y-503060D01*
X-307Y-503690D01*
X6Y-504425D01*
X163Y-505265D01*
Y-506105D01*
X6Y-506945D01*
X-307Y-507680D01*
X-777Y-508310D01*
X-1325Y-508730D01*
X-1952Y-508835D01*
G01X4348Y-509045D02*
X4191Y-508940D01*
Y-508730D01*
X4348Y-508625D01*
X4505Y-508730D01*
Y-508940D01*
X4348Y-509045D01*
G01X9160Y-503585D02*
X9630Y-502955D01*
X10178Y-502640D01*
X10805Y-502535D01*
X11588Y-502745D01*
X12136Y-503270D01*
X12293Y-503900D01*
X12215Y-504530D01*
X11901Y-505055D01*
X10335Y-506105D01*
X9630Y-506840D01*
X9160Y-507890D01*
X9003Y-508835D01*
X12293D01*
G01X16948D02*
Y-502535D01*
X16008Y-503795D01*
G01Y-508835D02*
X17888D01*
G01X23248D02*
Y-502535D01*
X22308Y-503795D01*
G01Y-508835D02*
X24188D01*
G01X29391Y-509990D02*
X29705Y-508625D01*
G01X33498Y-502535D02*
X34595Y-508835D01*
X35848Y-502535D01*
X37101Y-508835D01*
X38198Y-502535D01*
G01X43715Y-508835D02*
X40581D01*
Y-502535D01*
X43715D01*
G01X42461Y-505580D02*
X40581D01*
G01X46646Y-508835D02*
Y-502535D01*
X50250Y-508835D01*
Y-502535D01*
G01X53103Y-508835D02*
Y-502535D01*
G01X56393D02*
Y-508835D01*
G01Y-505685D02*
X53103D01*
G01X59325Y-502535D02*
Y-507050D01*
X59638Y-507995D01*
X60265Y-508625D01*
X61048Y-508835D01*
X61831Y-508625D01*
X62458Y-507995D01*
X62771Y-507050D01*
Y-502535D01*
G01X65390Y-508835D02*
X67348Y-502535D01*
X69306Y-508835D01*
G01X68601Y-506630D02*
X66095D01*
G01X78460Y-503585D02*
X78930Y-502955D01*
X79478Y-502640D01*
X80105Y-502535D01*
X80888Y-502745D01*
X81436Y-503270D01*
X81593Y-503900D01*
X81515Y-504530D01*
X81201Y-505055D01*
X79635Y-506105D01*
X78930Y-506840D01*
X78460Y-507890D01*
X78303Y-508835D01*
X81593D01*
G01X84446D02*
Y-502535D01*
X88050Y-508835D01*
Y-502535D01*
G01X90825Y-508835D02*
Y-502535D01*
X92391D01*
X93018Y-502850D01*
X93488Y-503270D01*
X93880Y-503900D01*
X94193Y-504635D01*
X94271Y-505685D01*
X94193Y-506735D01*
X93880Y-507470D01*
X93488Y-508100D01*
X93018Y-508520D01*
X92391Y-508835D01*
X90825D01*
G01X103581D02*
Y-502535D01*
X105540D01*
X106166Y-502850D01*
X106558Y-503270D01*
X106715Y-504110D01*
X106558Y-504950D01*
X106088Y-505475D01*
X105540Y-505790D01*
X103581D01*
G01X105540D02*
X106715Y-508835D01*
G01X109725D02*
Y-502535D01*
X111291D01*
X111918Y-502850D01*
X112388Y-503270D01*
X112780Y-503900D01*
X113093Y-504635D01*
X113171Y-505685D01*
X113093Y-506735D01*
X112780Y-507470D01*
X112388Y-508100D01*
X111918Y-508520D01*
X111291Y-508835D01*
X109725D01*
G01X117748Y-509045D02*
X117591Y-508940D01*
Y-508730D01*
X117748Y-508625D01*
X117905Y-508730D01*
Y-508940D01*
X117748Y-509045D01*
G01X14048Y-498135D02*
X11528Y-497718D01*
X9323Y-496052D01*
X7433Y-493552D01*
X6173Y-490635D01*
X5543Y-487302D01*
Y-483968D01*
X6173Y-480635D01*
X7433Y-477718D01*
X9323Y-475219D01*
X11528Y-473552D01*
X14048Y-473135D01*
X16568Y-473552D01*
X18773Y-475219D01*
X20663Y-477718D01*
X21923Y-480635D01*
X22553Y-483968D01*
Y-487302D01*
X21923Y-490635D01*
X20663Y-493552D01*
X18773Y-496052D01*
X16568Y-497718D01*
X14048Y-498135D01*
G01X16568Y-491468D02*
X20348Y-498135D01*
G01X33893Y-481469D02*
Y-493135D01*
X35153Y-496052D01*
X37043Y-497718D01*
X39248Y-498135D01*
X41453Y-497718D01*
X43343Y-496052D01*
X44603Y-493135D01*
G01Y-498135D02*
Y-481469D01*
G01X70118Y-498135D02*
Y-481469D01*
G01Y-484385D02*
X68858Y-482719D01*
X66968Y-481885D01*
X64763Y-481469D01*
X62558Y-482302D01*
X60668Y-483968D01*
X59408Y-486469D01*
X58778Y-489802D01*
X59408Y-493135D01*
X60668Y-495636D01*
X62558Y-497302D01*
X64763Y-498135D01*
X66968Y-497718D01*
X68858Y-496469D01*
X70118Y-494802D01*
G01X84293Y-498135D02*
Y-481469D01*
G01Y-485635D02*
X85553Y-483552D01*
X87443Y-481885D01*
X89963Y-481469D01*
X92168Y-481885D01*
X94058Y-483552D01*
X95003Y-486469D01*
Y-498135D01*
G01X114848Y-473135D02*
Y-498135D01*
G01X110438Y-481469D02*
X119258D01*
G01X145718Y-498135D02*
Y-481469D01*
G01Y-484385D02*
X144458Y-482719D01*
X142568Y-481885D01*
X140363Y-481469D01*
X138158Y-482302D01*
X136268Y-483968D01*
X135008Y-486469D01*
X134378Y-489802D01*
X135008Y-493135D01*
X136268Y-495636D01*
X138158Y-497302D01*
X140363Y-498135D01*
X142568Y-497718D01*
X144458Y-496469D01*
X145718Y-494802D01*
G01X185398Y-477835D02*
Y-485835D01*
X189398D01*
G01X197198D02*
Y-480502D01*
G01Y-481435D02*
X196798Y-480902D01*
X196198Y-480635D01*
X195498Y-480502D01*
X194798Y-480768D01*
X194198Y-481302D01*
X193798Y-482102D01*
X193598Y-483168D01*
X193798Y-484235D01*
X194198Y-485035D01*
X194798Y-485568D01*
X195498Y-485835D01*
X196198Y-485702D01*
X196798Y-485302D01*
X197198Y-484769D01*
G01X201298Y-488235D02*
X201898Y-488502D01*
X202698Y-488235D01*
X203198Y-487702D01*
X203598Y-487035D01*
X204198Y-484902D01*
X205498Y-480502D01*
G01X202298D02*
X204198Y-484902D01*
G01X209898Y-482235D02*
X213098D01*
X212798Y-481302D01*
X212298Y-480768D01*
X211598Y-480502D01*
X210898Y-480635D01*
X210298Y-481035D01*
X209898Y-481968D01*
X209698Y-482769D01*
Y-483568D01*
X209898Y-484368D01*
X210398Y-485168D01*
X210998Y-485702D01*
X211698Y-485835D01*
X212398Y-485568D01*
X213098Y-484769D01*
G01X217998Y-485835D02*
Y-480502D01*
G01Y-481568D02*
X218498Y-481035D01*
X218998Y-480635D01*
X219698Y-480502D01*
X220198Y-480635D01*
X220798Y-481035D01*
G01X211398Y-535835D02*
Y-532235D01*
X209398Y-527835D01*
G01X213398D02*
X211398Y-532235D01*
G01X217698Y-530502D02*
Y-534235D01*
X218098Y-535168D01*
X218698Y-535702D01*
X219398Y-535835D01*
X220098Y-535702D01*
X220698Y-535168D01*
X221098Y-534235D01*
G01Y-535835D02*
Y-530502D01*
G01X225698Y-535835D02*
Y-530502D01*
G01Y-531835D02*
X226098Y-531168D01*
X226698Y-530635D01*
X227498Y-530502D01*
X228198Y-530635D01*
X228798Y-531168D01*
X229098Y-532102D01*
Y-535835D01*
G01X237198D02*
Y-530502D01*
G01Y-531435D02*
X236798Y-530902D01*
X236198Y-530635D01*
X235498Y-530502D01*
X234798Y-530768D01*
X234198Y-531302D01*
X233798Y-532102D01*
X233598Y-533168D01*
X233798Y-534235D01*
X234198Y-535035D01*
X234798Y-535568D01*
X235498Y-535835D01*
X236198Y-535702D01*
X236798Y-535302D01*
X237198Y-534769D01*
G01X215198Y-502835D02*
X217598D01*
G01X216398D02*
Y-510835D01*
G01X215198D02*
X217598D01*
G01X222098D02*
Y-502835D01*
X226698Y-510835D01*
Y-502835D01*
G01X232398Y-510835D02*
Y-502835D01*
X231198Y-504435D01*
G01Y-510835D02*
X233598D01*
G01X236998Y-482502D02*
X237698Y-481568D01*
X238298Y-481035D01*
X239098Y-480768D01*
X239798Y-481035D01*
X240298Y-481568D01*
X240698Y-482368D01*
X240798Y-483302D01*
X240698Y-484102D01*
X240298Y-484902D01*
X239698Y-485568D01*
X238998Y-485835D01*
X238198Y-485568D01*
X237498Y-484769D01*
X237098Y-483568D01*
X236998Y-482235D01*
X237198Y-480502D01*
X237498Y-479568D01*
X237998Y-478635D01*
X238698Y-477968D01*
X239398Y-477835D01*
X240098Y-478102D01*
X240598Y-478768D01*
G01X311998Y-529168D02*
X312598Y-528368D01*
X313298Y-527968D01*
X314098Y-527835D01*
X315098Y-528102D01*
X315798Y-528768D01*
X315998Y-529568D01*
X315898Y-530369D01*
X315498Y-531035D01*
X313498Y-532368D01*
X312598Y-533302D01*
X311998Y-534635D01*
X311798Y-535835D01*
X315998D01*
G01X321898Y-527835D02*
X321098Y-528102D01*
X320498Y-528768D01*
X320098Y-529568D01*
X319798Y-530635D01*
X319698Y-531835D01*
X319798Y-533035D01*
X320098Y-534102D01*
X320498Y-534902D01*
X321098Y-535568D01*
X321898Y-535835D01*
X322698Y-535568D01*
X323298Y-534902D01*
X323698Y-534102D01*
X323998Y-533035D01*
X324098Y-531835D01*
X323998Y-530635D01*
X323698Y-529568D01*
X323298Y-528768D01*
X322698Y-528102D01*
X321898Y-527835D01*
G01X327998Y-529168D02*
X328598Y-528368D01*
X329298Y-527968D01*
X330098Y-527835D01*
X331098Y-528102D01*
X331798Y-528768D01*
X331998Y-529568D01*
X331898Y-530369D01*
X331498Y-531035D01*
X329498Y-532368D01*
X328598Y-533302D01*
X327998Y-534635D01*
X327798Y-535835D01*
X331998D01*
G01X335698Y-534235D02*
X336298Y-535168D01*
X337098Y-535702D01*
X337998Y-535835D01*
X338798Y-535702D01*
X339598Y-535035D01*
X340098Y-534235D01*
X340198Y-533435D01*
X339998Y-532502D01*
X339298Y-531835D01*
X338598Y-531568D01*
X337698D01*
G01X338598D02*
X339198Y-531168D01*
X339698Y-530502D01*
X339898Y-529702D01*
X339698Y-528902D01*
X339198Y-528235D01*
X338298Y-527835D01*
X337398Y-527968D01*
X336498Y-528502D01*
G01X344098Y-536102D02*
X347698Y-527835D01*
G01X353898D02*
X353098Y-528102D01*
X352498Y-528768D01*
X352098Y-529568D01*
X351798Y-530635D01*
X351698Y-531835D01*
X351798Y-533035D01*
X352098Y-534102D01*
X352498Y-534902D01*
X353098Y-535568D01*
X353898Y-535835D01*
X354698Y-535568D01*
X355298Y-534902D01*
X355698Y-534102D01*
X355998Y-533035D01*
X356098Y-531835D01*
X355998Y-530635D01*
X355698Y-529568D01*
X355298Y-528768D01*
X354698Y-528102D01*
X353898Y-527835D01*
G01X361898Y-535835D02*
Y-527835D01*
X360698Y-529435D01*
G01Y-535835D02*
X363098D01*
G01X368098Y-536102D02*
X371698Y-527835D01*
G01X377898D02*
X377098Y-528102D01*
X376498Y-528768D01*
X376098Y-529568D01*
X375798Y-530635D01*
X375698Y-531835D01*
X375798Y-533035D01*
X376098Y-534102D01*
X376498Y-534902D01*
X377098Y-535568D01*
X377898Y-535835D01*
X378698Y-535568D01*
X379298Y-534902D01*
X379698Y-534102D01*
X379998Y-533035D01*
X380098Y-531835D01*
X379998Y-530635D01*
X379698Y-529568D01*
X379298Y-528768D01*
X378698Y-528102D01*
X377898Y-527835D01*
G01X384198Y-534902D02*
X384898Y-535568D01*
X385698Y-535835D01*
X386498Y-535568D01*
X387198Y-534769D01*
X387698Y-533568D01*
X387898Y-532368D01*
Y-530902D01*
X387698Y-529702D01*
X387198Y-528635D01*
X386598Y-528102D01*
X385898Y-527835D01*
X385098Y-528102D01*
X384498Y-528635D01*
X384098Y-529435D01*
X383898Y-530502D01*
X384098Y-531435D01*
X384598Y-532368D01*
X385198Y-532902D01*
X385898Y-533035D01*
X386698Y-532769D01*
X387298Y-532102D01*
X387898Y-530902D01*
G01X311698Y-510835D02*
Y-502835D01*
X313698D01*
X314498Y-503235D01*
X315098Y-503768D01*
X315598Y-504568D01*
X315998Y-505502D01*
X316098Y-506835D01*
X315998Y-508168D01*
X315598Y-509102D01*
X315098Y-509902D01*
X314498Y-510435D01*
X313698Y-510835D01*
X311698D01*
G01X319398D02*
X321898Y-502835D01*
X324398Y-510835D01*
G01X323498Y-508035D02*
X320298D01*
G01X329898Y-502835D02*
X329098Y-503102D01*
X328498Y-503768D01*
X328098Y-504568D01*
X327798Y-505635D01*
X327698Y-506835D01*
X327798Y-508035D01*
X328098Y-509102D01*
X328498Y-509902D01*
X329098Y-510568D01*
X329898Y-510835D01*
X330698Y-510568D01*
X331298Y-509902D01*
X331698Y-509102D01*
X331998Y-508035D01*
X332098Y-506835D01*
X331998Y-505635D01*
X331698Y-504568D01*
X331298Y-503768D01*
X330698Y-503102D01*
X329898Y-502835D01*
G01X335998Y-510835D02*
Y-502835D01*
X339798D01*
G01X338398Y-506702D02*
X335998D01*
G01X345898Y-502835D02*
X345098Y-503102D01*
X344498Y-503768D01*
X344098Y-504568D01*
X343798Y-505635D01*
X343698Y-506835D01*
X343798Y-508035D01*
X344098Y-509102D01*
X344498Y-509902D01*
X345098Y-510568D01*
X345898Y-510835D01*
X346698Y-510568D01*
X347298Y-509902D01*
X347698Y-509102D01*
X347998Y-508035D01*
X348098Y-506835D01*
X347998Y-505635D01*
X347698Y-504568D01*
X347298Y-503768D01*
X346698Y-503102D01*
X345898Y-502835D01*
G01X353898D02*
Y-510835D01*
G01X351598Y-502835D02*
X356198D01*
G01X363898Y-510835D02*
X359898D01*
Y-502835D01*
X363898D01*
G01X362298Y-506702D02*
X359898D01*
G01X370698Y-506568D02*
X371098Y-506168D01*
X371398Y-505502D01*
X371598Y-504568D01*
X371398Y-503768D01*
X370998Y-503235D01*
X370298Y-502835D01*
X367598D01*
Y-510835D01*
X370898D01*
X371598Y-510302D01*
X371998Y-509502D01*
X372198Y-508568D01*
X371998Y-507635D01*
X371398Y-506835D01*
X370698Y-506568D01*
X367598D01*
G01X376698Y-502835D02*
X379098D01*
G01X377898D02*
Y-510835D01*
G01X376698D02*
X379098D01*
G01X383998D02*
Y-502835D01*
X387798D01*
G01X386398Y-506702D02*
X383998D01*
G01X393898Y-502835D02*
X393098Y-503102D01*
X392498Y-503768D01*
X392098Y-504568D01*
X391798Y-505635D01*
X391698Y-506835D01*
X391798Y-508035D01*
X392098Y-509102D01*
X392498Y-509902D01*
X393098Y-510568D01*
X393898Y-510835D01*
X394698Y-510568D01*
X395298Y-509902D01*
X395698Y-509102D01*
X395998Y-508035D01*
X396098Y-506835D01*
X395998Y-505635D01*
X395698Y-504568D01*
X395298Y-503768D01*
X394698Y-503102D01*
X393898Y-502835D01*
G01X329498Y-485835D02*
Y-477835D01*
X333298D01*
G01X331898Y-481702D02*
X329498D01*
G01X339398Y-477835D02*
X338598Y-478102D01*
X337998Y-478768D01*
X337598Y-479568D01*
X337298Y-480635D01*
X337198Y-481835D01*
X337298Y-483035D01*
X337598Y-484102D01*
X337998Y-484902D01*
X338598Y-485568D01*
X339398Y-485835D01*
X340198Y-485568D01*
X340798Y-484902D01*
X341198Y-484102D01*
X341498Y-483035D01*
X341598Y-481835D01*
X341498Y-480635D01*
X341198Y-479568D01*
X340798Y-478768D01*
X340198Y-478102D01*
X339398Y-477835D01*
G01X347398D02*
Y-485835D01*
G01X345098Y-477835D02*
X349698D01*
G01X352398Y-488502D02*
X358398D01*
G01X361898Y-482235D02*
X365098D01*
X364798Y-481302D01*
X364298Y-480768D01*
X363598Y-480502D01*
X362898Y-480635D01*
X362298Y-481035D01*
X361898Y-481968D01*
X361698Y-482769D01*
Y-483568D01*
X361898Y-484368D01*
X362398Y-485168D01*
X362998Y-485702D01*
X363698Y-485835D01*
X364398Y-485568D01*
X365098Y-484769D01*
G01X369898Y-480502D02*
X372898Y-485835D01*
G01Y-480502D02*
X369898Y-485835D01*
G01X377598Y-488502D02*
Y-480502D01*
G01Y-481702D02*
X378098Y-481035D01*
X378598Y-480635D01*
X379398Y-480502D01*
X380098Y-480635D01*
X380798Y-481302D01*
X381098Y-482235D01*
X381198Y-483168D01*
X381098Y-484102D01*
X380798Y-485035D01*
X380198Y-485568D01*
X379398Y-485835D01*
X378698Y-485702D01*
X377998Y-485302D01*
X377598Y-484769D01*
G01X389198Y-485835D02*
Y-480502D01*
G01Y-481435D02*
X388798Y-480902D01*
X388198Y-480635D01*
X387498Y-480502D01*
X386798Y-480768D01*
X386198Y-481302D01*
X385798Y-482102D01*
X385598Y-483168D01*
X385798Y-484235D01*
X386198Y-485035D01*
X386798Y-485568D01*
X387498Y-485835D01*
X388198Y-485702D01*
X388798Y-485302D01*
X389198Y-484769D01*
G01X393698Y-485835D02*
Y-480502D01*
G01Y-481835D02*
X394098Y-481168D01*
X394698Y-480635D01*
X395498Y-480502D01*
X396198Y-480635D01*
X396798Y-481168D01*
X397098Y-482102D01*
Y-485835D01*
G01X405198Y-477835D02*
Y-485835D01*
G01Y-484635D02*
X404798Y-485302D01*
X404198Y-485702D01*
X403498Y-485835D01*
X402698Y-485568D01*
X402098Y-484902D01*
X401698Y-484102D01*
X401598Y-483168D01*
X401698Y-482235D01*
X402098Y-481435D01*
X402698Y-480768D01*
X403498Y-480502D01*
X404198Y-480635D01*
X404698Y-480902D01*
X405198Y-481435D01*
G01X409898Y-482235D02*
X413098D01*
X412798Y-481302D01*
X412298Y-480768D01*
X411598Y-480502D01*
X410898Y-480635D01*
X410298Y-481035D01*
X409898Y-481968D01*
X409698Y-482769D01*
Y-483568D01*
X409898Y-484368D01*
X410398Y-485168D01*
X410998Y-485702D01*
X411698Y-485835D01*
X412398Y-485568D01*
X413098Y-484769D01*
G01X417998Y-485835D02*
Y-480502D01*
G01Y-481568D02*
X418498Y-481035D01*
X418998Y-480635D01*
X419698Y-480502D01*
X420198Y-480635D01*
X420798Y-481035D01*
G01X424398Y-488502D02*
X430398D01*
G01X433598Y-485835D02*
Y-477835D01*
G01Y-481835D02*
X434098Y-481035D01*
X434698Y-480635D01*
X435298Y-480502D01*
X436198Y-480768D01*
X436798Y-481302D01*
X437198Y-482235D01*
Y-483302D01*
X436998Y-484368D01*
X436598Y-485168D01*
X435898Y-485702D01*
X435298Y-485835D01*
X434698Y-485702D01*
X434098Y-485302D01*
X433598Y-484635D01*
G01X445198Y-477835D02*
Y-485835D01*
G01Y-484635D02*
X444798Y-485302D01*
X444198Y-485702D01*
X443498Y-485835D01*
X442698Y-485568D01*
X442098Y-484902D01*
X441698Y-484102D01*
X441598Y-483168D01*
X441698Y-482235D01*
X442098Y-481435D01*
X442698Y-480768D01*
X443498Y-480502D01*
X444198Y-480635D01*
X444698Y-480902D01*
X445198Y-481435D01*
G01X400398Y-538835D02*
Y-530835D01*
X399198Y-532435D01*
G01Y-538835D02*
X401598D01*
G01X406498Y-535502D02*
X407198Y-534568D01*
X407798Y-534035D01*
X408598Y-533768D01*
X409298Y-534035D01*
X409798Y-534568D01*
X410198Y-535368D01*
X410298Y-536302D01*
X410198Y-537102D01*
X409798Y-537902D01*
X409198Y-538568D01*
X408498Y-538835D01*
X407698Y-538568D01*
X406998Y-537769D01*
X406598Y-536568D01*
X406498Y-535235D01*
X406698Y-533502D01*
X406998Y-532568D01*
X407498Y-531635D01*
X408198Y-530968D01*
X408898Y-530835D01*
X409598Y-531102D01*
X410098Y-531768D01*
G01X416398Y-539102D02*
X416198Y-538968D01*
Y-538702D01*
X416398Y-538568D01*
X416598Y-538702D01*
Y-538968D01*
X416398Y-539102D01*
G01X422498Y-535502D02*
X423198Y-534568D01*
X423798Y-534035D01*
X424598Y-533768D01*
X425298Y-534035D01*
X425798Y-534568D01*
X426198Y-535368D01*
X426298Y-536302D01*
X426198Y-537102D01*
X425798Y-537902D01*
X425198Y-538568D01*
X424498Y-538835D01*
X423698Y-538568D01*
X422998Y-537769D01*
X422598Y-536568D01*
X422498Y-535235D01*
X422698Y-533502D01*
X422998Y-532568D01*
X423498Y-531635D01*
X424198Y-530968D01*
X424898Y-530835D01*
X425598Y-531102D01*
X426098Y-531768D01*
G01X445398Y-538835D02*
Y-530835D01*
X444198Y-532435D01*
G01Y-538835D02*
X446598D01*
G01X453198D02*
X453398Y-537102D01*
X453698Y-535635D01*
X454098Y-534302D01*
X454598Y-532835D01*
X455398Y-530835D01*
X451398D01*
G01X461398Y-539102D02*
X461198Y-538968D01*
Y-538702D01*
X461398Y-538568D01*
X461598Y-538702D01*
Y-538968D01*
X461398Y-539102D01*
G01X467498Y-532168D02*
X468098Y-531368D01*
X468798Y-530968D01*
X469598Y-530835D01*
X470598Y-531102D01*
X471298Y-531768D01*
X471498Y-532568D01*
X471398Y-533369D01*
X470998Y-534035D01*
X468998Y-535368D01*
X468098Y-536302D01*
X467498Y-537635D01*
X467298Y-538835D01*
X471498D01*
G01X465498Y-513835D02*
Y-505835D01*
X469298D01*
G01X467898Y-509702D02*
X465498D01*
G54D12*
X51043Y60709D03*
Y150197D03*
X153405Y60709D03*
Y150197D03*
X255767Y60709D03*
Y150197D03*
X279360Y368760D03*
Y421555D03*
X358129Y60709D03*
Y150197D03*
X508130Y60709D03*
Y150197D03*
X610492Y60709D03*
Y150197D03*
X712854Y60709D03*
Y150197D03*
X736446Y368760D03*
Y421555D03*
X815216Y60709D03*
Y150197D03*
X965216Y60709D03*
Y150197D03*
X1067578Y60709D03*
Y150197D03*
X1104498Y583957D03*
X1169940Y60709D03*
Y150197D03*
X1193533Y368760D03*
Y421555D03*
X1272302Y60709D03*
Y150197D03*
X1422303Y60709D03*
Y150197D03*
X1524665Y60709D03*
Y150197D03*
X1561585Y583957D03*
Y636752D03*
X1627027Y60709D03*
Y150197D03*
X1650620Y368760D03*
Y421555D03*
X1729389Y60709D03*
Y150197D03*
G54D21*
X342840Y1253274D03*
X338652Y1263386D03*
X342840Y1273498D03*
X352952Y1249086D03*
Y1277686D03*
X363064Y1253274D03*
X367252Y1263386D03*
X363064Y1273498D03*
X810040Y378544D03*
X805881Y388583D03*
X810040Y398622D03*
X820079Y374385D03*
X830118Y378544D03*
X820079Y402781D03*
X830118Y398622D03*
X834277Y388583D03*
X1010827Y378544D03*
X1006668Y388583D03*
X1010827Y398622D03*
X1020866Y374385D03*
Y402781D03*
X1030905Y378544D03*
X1035064Y388583D03*
X1030905Y398622D03*
X1252825Y1263386D03*
X1267125Y1249086D03*
X1257013Y1253274D03*
Y1273498D03*
X1267125Y1277686D03*
X1277237Y1253274D03*
X1281425Y1263386D03*
X1277237Y1273498D03*
G54D31*
G01X164496Y309405D02*
X151400Y296309D01*
Y181103D01*
X103400Y133103D01*
Y110978D01*
X79500Y87078D01*
Y76000D01*
X74481Y70981D01*
X7271D01*
G01X14264Y94236D02*
X14548Y93952D01*
X42548D01*
X45988Y90512D01*
G01X51550Y90615D02*
Y92397D01*
X48185Y95762D01*
X19238D01*
X18000Y97000D01*
X13056D01*
X10292Y94236D01*
G01X37117Y279991D02*
Y281439D01*
X27556Y291000D01*
X14499D01*
X6303Y282804D01*
Y276659D01*
X8941Y274021D01*
Y265341D01*
X6303Y262703D01*
Y107197D01*
X10300Y103200D01*
Y97800D01*
X8000Y95500D01*
Y93200D01*
X11200Y90000D01*
X18000D01*
G01X26565Y177448D02*
Y169600D01*
X26065Y169100D01*
X9298D01*
X8500Y168302D01*
Y142200D01*
X11000Y139700D01*
Y135000D01*
X8200Y132200D01*
Y114682D01*
X10304Y112578D01*
X23693D01*
X29710Y106561D01*
X35207D01*
G01X125753Y365856D02*
X144420Y347189D01*
Y183800D01*
X94064Y133444D01*
Y114843D01*
X85221Y106000D01*
X72100D01*
X66285Y111815D01*
X55434D01*
X47638Y119611D01*
X44698D01*
X42832Y121477D01*
Y128522D01*
X31692Y139662D01*
X24714D01*
X21583Y136531D01*
X18493D01*
X14996Y133034D01*
G01X126131Y359511D02*
X129339D01*
X142610Y346240D01*
Y184551D01*
X91834Y133775D01*
Y115174D01*
X84860Y108200D01*
X72608D01*
X67002Y113806D01*
X62772D01*
X49941Y126637D01*
Y131525D01*
X39994Y141472D01*
X23427D01*
X20644Y138689D01*
X17520D01*
X11550Y132719D01*
X11442D01*
G01X16709Y175943D02*
X8354Y184298D01*
Y229697D01*
X9784Y231127D01*
X20118D01*
X22599Y228646D01*
G01X33902Y244297D02*
X27483D01*
X16780Y255000D01*
Y256316D01*
X13715Y259381D01*
G01D02*
X12720Y260376D01*
Y277480D01*
X10585Y279615D01*
Y283628D01*
X15499Y288542D01*
G01X8335Y280663D02*
Y278466D01*
X10910Y275891D01*
Y258154D01*
X26964Y242100D01*
X36201D01*
X38106Y240195D01*
Y173641D01*
X43347Y168400D01*
X47099D01*
X71399Y144100D01*
X75499D01*
X77044Y145645D01*
X83772D01*
X85245Y144172D01*
X92337D01*
G01X113505Y796856D02*
Y776216D01*
X97878Y760589D01*
Y655277D01*
X97202Y653645D01*
Y389471D01*
X107764Y378909D01*
Y308860D01*
X103854Y304950D01*
X75151D01*
X45401Y275200D01*
X34601D01*
X33700Y276101D01*
Y281769D01*
X26872Y288597D01*
X15554D01*
X15499Y288542D01*
G01X129666Y857514D02*
X125040Y852888D01*
Y805049D01*
X121782Y801791D01*
Y774401D01*
X104556Y757175D01*
Y656652D01*
X102842Y652514D01*
Y395843D01*
X114900Y383785D01*
Y379899D01*
X146230Y348569D01*
Y183049D01*
X96194Y133013D01*
Y114413D01*
X83659Y101878D01*
X75723D01*
X73995Y103606D01*
X72320D01*
X69132Y100418D01*
X61447D01*
X55304Y106561D01*
X35207D01*
G01X35650Y491982D02*
X26686D01*
X23172Y495496D01*
Y838481D01*
X38793Y854102D01*
X115764D01*
X122437Y860775D01*
G01X35650Y491982D02*
X37659Y489973D01*
Y477403D01*
X41643Y473419D01*
G01X25819Y527726D02*
Y496709D01*
X28518Y494010D01*
X39019D01*
X40112Y492917D01*
Y486616D01*
X44563Y482165D01*
G01D02*
X43700Y481302D01*
Y470822D01*
X44332Y470190D01*
X59369D01*
X62224Y473045D01*
G01X55871Y99961D02*
X57854Y97978D01*
X70621D01*
X72677Y95922D01*
X77761D01*
X77804Y95879D01*
G01X55921Y95236D02*
X60188Y90969D01*
X80830D01*
X101254Y111393D01*
Y133518D01*
X149450Y181714D01*
Y351849D01*
X119500Y381799D01*
Y385001D01*
X106062Y398439D01*
Y651870D01*
X107776Y656008D01*
Y754875D01*
X125002Y772101D01*
Y800455D01*
X128260Y803713D01*
Y848642D01*
X136862Y857244D01*
G01X57987Y258880D02*
X71725D01*
X76515Y254090D01*
X98488D01*
X99454Y253124D01*
Y216982D01*
X107572Y208864D01*
G01X59684Y605443D02*
X65630Y599497D01*
X65661D01*
X65668Y599490D01*
X88307D01*
X92172Y595625D01*
Y377876D01*
X95538Y374510D01*
X98255D01*
G01X63684Y605443D02*
X67827Y601300D01*
X89300D01*
X93982Y596618D01*
Y384036D01*
X100120Y377898D01*
G01X100066Y381976D02*
X95792Y386250D01*
Y597607D01*
X90289Y603110D01*
X70211D01*
X67684Y605637D01*
G01X68598Y859415D02*
X57000Y871013D01*
Y952241D01*
X65022Y960263D01*
Y1036423D01*
X84594Y1055995D01*
Y1071497D01*
X110566Y1097469D01*
X133579D01*
G01X59962Y910251D02*
Y951709D01*
X67222Y958973D01*
Y1034823D01*
X83299Y1050900D01*
X103000D01*
X111450Y1047400D01*
X132618D01*
X133218Y1048000D01*
Y1053058D01*
X133748Y1053588D01*
X136228D01*
X136758Y1053058D01*
Y1048000D01*
X137288Y1047470D01*
X140970D01*
X141735Y1048235D01*
Y1067966D01*
X140838Y1068863D01*
X138917D01*
X138468Y1069312D01*
Y1074483D01*
X139224Y1075239D01*
X145930D01*
X146595Y1074574D01*
Y1053457D01*
G01X159228Y1065613D02*
X149500Y1055885D01*
Y1052288D01*
X143329Y1046117D01*
X141332Y1045290D01*
X110348D01*
X103080Y1048300D01*
X84900D01*
X69732Y1033132D01*
Y952894D01*
X67510Y950672D01*
X62918D01*
X62388Y950142D01*
Y947672D01*
X62918Y947142D01*
X68480D01*
X69010Y946612D01*
Y944142D01*
X68480Y943612D01*
X62918D01*
X62388Y943082D01*
Y940612D01*
X62918Y940082D01*
X68480D01*
X69010Y939552D01*
Y937082D01*
X68480Y936552D01*
X62918D01*
X62388Y936022D01*
Y933552D01*
X62918Y933022D01*
X68480D01*
X69010Y932492D01*
Y930022D01*
X68480Y929492D01*
X62918D01*
X62388Y928962D01*
Y926492D01*
X62918Y925962D01*
X68480D01*
X69010Y925432D01*
Y915708D01*
X71528Y913190D01*
G01X133424Y857303D02*
X126450Y850329D01*
Y804464D01*
X123192Y801206D01*
Y772992D01*
X105966Y755766D01*
Y656370D01*
X104252Y652232D01*
Y397348D01*
X116934Y384666D01*
Y380666D01*
X147640Y349960D01*
Y182464D01*
X99024Y133848D01*
Y111723D01*
X83180Y95879D01*
X77804D01*
G01X103841Y228631D02*
X101842Y230630D01*
Y253296D01*
X99638Y255500D01*
X88496D01*
X85556Y258440D01*
X82903D01*
X80766Y256303D01*
G01X144640Y1039439D02*
X144009Y1040070D01*
X108937D01*
X103312Y1042400D01*
X87799D01*
X75034Y1029635D01*
Y961018D01*
X83604Y952448D01*
Y902400D01*
X84500Y901504D01*
Y897100D01*
X76465Y889065D01*
X74028D01*
G01X150952Y1040115D02*
X147471Y1036634D01*
X143478D01*
X142152Y1037960D01*
X108023D01*
X102856Y1040100D01*
X89300D01*
X77144Y1027944D01*
Y964155D01*
X87863Y953436D01*
Y902537D01*
X90618Y899782D01*
Y896054D01*
X83079Y888515D01*
G01X153693Y1051037D02*
Y1053748D01*
X153730D01*
X154532Y1054550D01*
X156597D01*
X157282Y1053865D01*
Y1051082D01*
X152540Y1046340D01*
Y1044613D01*
X151569Y1043642D01*
X144620D01*
X142297Y1042680D01*
X109773D01*
X103205Y1045400D01*
X87101D01*
X72424Y1030723D01*
Y947476D01*
X76203Y943697D01*
Y897910D01*
G01X160547Y1049283D02*
X173742D01*
X174242Y1048783D01*
Y1047294D01*
X173708Y1046760D01*
X159644D01*
X156299Y1043415D01*
Y1038402D01*
X152012Y1034115D01*
X141986D01*
X140301Y1035800D01*
X107440D01*
X102484Y1037853D01*
X90654D01*
X79254Y1026453D01*
Y966054D01*
X94266Y951042D01*
Y873633D01*
X92022Y871389D01*
X90000D01*
G01X88287Y1026537D02*
X82774Y1021024D01*
Y972435D01*
X98122Y957087D01*
Y921531D01*
X125653Y894000D01*
X128300D01*
X139327Y882973D01*
Y856027D01*
X130070Y846770D01*
Y802962D01*
X126812Y799704D01*
Y765403D01*
X120250Y758841D01*
G01X160807Y1043955D02*
Y1037697D01*
X154555Y1031445D01*
X129784D01*
X128059Y1033170D01*
X94133D01*
X92081Y1031118D01*
X89135D01*
X81364Y1023347D01*
Y969335D01*
X96376Y954323D01*
Y919011D01*
X123387Y892000D01*
G01X91224Y141247D02*
X96746D01*
X140800Y185301D01*
Y239563D01*
X138664Y241699D01*
G01X103841Y228631D02*
X103967Y228757D01*
Y261715D01*
X109808Y267556D01*
Y382892D01*
X98612Y394088D01*
Y653363D01*
X99288Y654995D01*
Y759361D01*
X116057Y776130D01*
Y800056D01*
X122162Y806161D01*
Y857270D01*
X122432Y857540D01*
G01X107572Y208864D02*
X110140Y211432D01*
Y217464D01*
X108209Y219395D01*
X106165D01*
X105539Y220021D01*
Y224767D01*
X106075Y225303D01*
Y260768D01*
X111460Y266153D01*
Y383235D01*
X100022Y394673D01*
Y653080D01*
X101488Y656620D01*
Y759166D01*
X118467Y776145D01*
Y796785D01*
G01X109591Y796905D02*
Y774425D01*
X95539Y760373D01*
Y664443D01*
G01X124961Y228646D02*
X138787Y214820D01*
Y186587D01*
X109570Y157370D01*
X103456D01*
G01X138664Y241699D02*
Y344161D01*
X113000Y369825D01*
Y383690D01*
X101432Y395258D01*
Y652795D01*
X103146Y656933D01*
Y758246D01*
X120372Y775472D01*
Y802376D01*
X123630Y805634D01*
Y855447D01*
X125698Y857515D01*
G01X131481Y143762D02*
X125053Y137334D01*
Y117098D01*
X135590Y106561D01*
X137569D01*
G01X122867Y125107D02*
Y116723D01*
X133200Y106390D01*
Y95111D01*
G01X170215Y311671D02*
X152810Y294266D01*
Y172811D01*
X131481Y151482D01*
Y143762D01*
G01X119099Y755052D02*
X119157D01*
X128222Y764117D01*
Y799119D01*
X131480Y802377D01*
Y845779D01*
X141500Y855799D01*
Y947753D01*
X157701Y986866D01*
Y995995D01*
X155836Y997860D01*
G01X191568Y76587D02*
Y84214D01*
X187582Y88200D01*
X151050D01*
X148600Y90650D01*
G01X148350Y95236D02*
X153771D01*
X156541Y92466D01*
X162100D01*
X165634Y96000D01*
X184551D01*
X186026Y97475D01*
G01X191568Y72615D02*
X193807Y74854D01*
Y85794D01*
X188986Y90615D01*
X153912D01*
G01X275123Y847874D02*
Y834224D01*
X264278Y823379D01*
Y810905D01*
X252328Y798955D01*
Y724529D01*
X232249Y704450D01*
Y614541D01*
X236200Y610590D01*
Y368499D01*
X231353Y363652D01*
Y336247D01*
X234986Y332614D01*
Y261314D01*
X247770Y248530D01*
Y179626D01*
X200290Y132146D01*
Y114988D01*
X201234Y114044D01*
Y111735D01*
X197590Y108091D01*
X185166D01*
X183175Y106100D01*
X177175D01*
X169226Y98151D01*
X161198D01*
X158283Y95236D01*
G01X158233Y99961D02*
X168475D01*
X176514Y108000D01*
X182515D01*
X184416Y109901D01*
X195198D01*
X197380Y112083D01*
G01X160349Y258880D02*
X173921D01*
X178403Y254398D01*
X202234D01*
X203716Y252916D01*
Y228282D01*
X201816Y226382D01*
Y216982D01*
X209934Y208864D01*
G01X234986Y336161D02*
X237351Y333796D01*
Y261849D01*
X249580Y249620D01*
Y178875D01*
X204201Y133496D01*
Y111410D01*
X197954Y105163D01*
Y89207D01*
X203861Y83300D01*
X206784D01*
X209530Y86046D01*
G01X197380Y112083D02*
X198480Y113183D01*
Y132897D01*
X245960Y180377D01*
Y247141D01*
X233121Y259980D01*
Y331478D01*
X229543Y335056D01*
Y364403D01*
X234300Y369160D01*
Y609799D01*
X230439Y613660D01*
Y705919D01*
X250198Y725678D01*
Y800479D01*
X256303Y806584D01*
Y812254D01*
G01X238626Y244297D02*
X243007D01*
X244550Y242754D01*
Y180962D01*
X204835Y141247D01*
X193586D01*
G01X206203Y228631D02*
X205446Y229388D01*
Y253746D01*
X203384Y255808D01*
X190551D01*
X187919Y258440D01*
X185265D01*
X183128Y256303D01*
G01X236264Y342494D02*
X239272Y339486D01*
Y262727D01*
X251390Y250609D01*
Y178124D01*
X206011Y132745D01*
Y110659D01*
X199764Y104412D01*
Y89958D01*
X203991Y85731D01*
X205976D01*
G01X257993Y307994D02*
Y302734D01*
X253200Y297941D01*
Y177373D01*
X207821Y131994D01*
Y109773D01*
X201669Y103621D01*
G01X227323Y228646D02*
X243140Y212829D01*
Y181548D01*
X218962Y157370D01*
X205818D01*
G01X209934Y208864D02*
X213118Y212048D01*
Y216658D01*
X210020Y219756D01*
X209179D01*
X207496Y221439D01*
Y227229D01*
X208631Y228364D01*
Y253827D01*
X213890Y259086D01*
X220016D01*
X224200Y263270D01*
Y378700D01*
X226002Y380502D01*
Y423274D01*
X229382Y426654D01*
Y606113D01*
X225800Y609695D01*
Y710801D01*
X241204Y726205D01*
Y814841D01*
G01X206203Y228631D02*
X207221Y229649D01*
Y255521D01*
X212318Y260618D01*
X218593D01*
X222600Y264625D01*
Y379799D01*
X224200Y381399D01*
Y425700D01*
X227652Y429152D01*
Y605848D01*
X224390Y609110D01*
Y712922D01*
X237695Y726227D01*
Y815162D01*
X237591Y815266D01*
G01X252305Y831018D02*
X249727D01*
X233000Y814291D01*
Y728035D01*
X218247Y713282D01*
Y640367D01*
X215266Y637386D01*
Y623122D01*
X213735Y621591D01*
X208540D01*
G01X239931Y106561D02*
X237952D01*
X227415Y117098D01*
Y137334D01*
X233843Y143762D01*
G01X225229Y125107D02*
Y116723D01*
X235562Y106390D01*
Y95111D01*
G01X248506Y812042D02*
X244751Y808287D01*
Y726619D01*
X227400Y709268D01*
Y611401D01*
X231000Y607801D01*
Y369851D01*
X225802Y364653D01*
Y264753D01*
X238626Y251929D01*
Y244297D01*
G01X254058Y819851D02*
Y807905D01*
X247730Y801577D01*
Y726723D01*
X229029Y708022D01*
Y612271D01*
X232500Y608800D01*
Y369355D01*
X228133Y364988D01*
Y333769D01*
X230842Y331060D01*
Y313888D01*
G01X233843Y143762D02*
X233882Y143801D01*
Y156059D01*
X255200Y177377D01*
Y295577D01*
X260000Y300377D01*
Y314452D01*
X241392Y333060D01*
Y341312D01*
X233258Y349446D01*
Y359186D01*
G01X274096Y820725D02*
Y813318D01*
X257166Y796388D01*
Y722123D01*
X235469Y700426D01*
Y615876D01*
X239800Y611545D01*
Y369536D01*
X316300Y293036D01*
Y246130D01*
X314635Y244465D01*
Y211147D01*
X312352Y208864D01*
X312296D01*
G01X308565Y228631D02*
X309221Y229287D01*
Y258381D01*
X310843Y260003D01*
Y296497D01*
X238100Y369240D01*
Y611250D01*
X234059Y615291D01*
Y702859D01*
X255200Y724000D01*
Y798533D01*
X266404Y809737D01*
Y822658D01*
X274697Y830951D01*
G01X254634Y698241D02*
X249854D01*
X238289Y686676D01*
Y617046D01*
X243400Y611935D01*
Y422222D01*
X270538Y395084D01*
X277575D01*
G01X244267Y696911D02*
X236879Y689523D01*
Y616461D01*
X241700Y611640D01*
Y420529D01*
X274425Y387804D01*
Y381500D01*
G01X248090Y691114D02*
X239945Y682969D01*
Y643362D01*
X240194Y643113D01*
G01X293930Y76587D02*
Y84214D01*
X289434Y88710D01*
X252902D01*
X250962Y90650D01*
G01X293930Y72615D02*
X296169Y74854D01*
Y84536D01*
X290090Y90615D01*
X256274D01*
G01X260595Y99961D02*
X270837D01*
X278876Y108000D01*
X284877D01*
X286778Y109901D01*
X297560D01*
X299742Y112083D01*
G01X260645Y95236D02*
X263560Y98151D01*
X271588D01*
X279537Y106100D01*
X285537D01*
X287528Y108091D01*
X299952D01*
X302124Y110263D01*
Y133424D01*
X351600Y182900D01*
Y305200D01*
X361900Y315500D01*
Y330600D01*
X392420Y361120D01*
X457772D01*
X468145Y371493D01*
Y397046D01*
X476360Y405261D01*
Y462626D01*
X478783Y465049D01*
Y496698D01*
X476040Y499441D01*
Y717340D01*
X490195Y731495D01*
Y785905D01*
X471261Y804839D01*
Y831739D01*
X467149Y835851D01*
Y841249D01*
X469459Y843559D01*
Y884660D01*
X478255Y893456D01*
Y950831D01*
X479613Y952189D01*
G01X250712Y95236D02*
X256133D01*
X258903Y92466D01*
X264266D01*
X267200Y95400D01*
X272400D01*
X273500Y96500D01*
X287413D01*
X288388Y97475D01*
G01X262711Y258880D02*
X276449D01*
X280931Y254398D01*
X304596D01*
X306078Y252916D01*
Y225778D01*
X304139Y223839D01*
Y216965D01*
X312240Y208864D01*
X312296D01*
G01X348432Y1187215D02*
X345525D01*
X342315Y1184005D01*
X334696D01*
X327489Y1191212D01*
X306788D01*
X305750Y1192250D01*
Y1195550D01*
X307900Y1197700D01*
Y1218200D01*
X306900Y1219200D01*
X289200D01*
X287166Y1217166D01*
Y1215146D01*
X285602Y1213582D01*
X283973D01*
X283477Y1213086D01*
Y1211055D01*
X282331Y1209909D01*
X280687D01*
X279758Y1210838D01*
Y1212467D01*
X278643Y1213582D01*
X249803D01*
X247932Y1211711D01*
G01X366429Y1185238D02*
X364011D01*
X360220Y1181447D01*
X352509D01*
X348734Y1177672D01*
X347471D01*
X347120Y1178023D01*
X330477D01*
X328513Y1179987D01*
X299335D01*
X292011Y1187311D01*
X288489D01*
X287200Y1188600D01*
Y1205500D01*
X286700Y1206000D01*
X284283D01*
X283632Y1205349D01*
Y1203029D01*
X283003Y1202400D01*
X276668D01*
X276009Y1203059D01*
Y1208851D01*
X275018Y1209842D01*
X253398D01*
X251673Y1211567D01*
Y1211711D01*
G01X358207Y836462D02*
Y780416D01*
X360500Y778123D01*
Y571346D01*
X353878Y564724D01*
X348429Y533146D01*
X342474Y515439D01*
X294432Y467397D01*
X276374D01*
X276344Y467367D01*
G01X361792Y1187310D02*
Y1185610D01*
X359482Y1183300D01*
X347816D01*
X344443Y1179927D01*
X331749D01*
X328011Y1183665D01*
X298935D01*
X295600Y1187000D01*
Y1189200D01*
X292900Y1191900D01*
Y1207400D01*
X292400Y1207900D01*
X288600D01*
X286500Y1210000D01*
X283942D01*
X283353Y1209411D01*
Y1206996D01*
X282299Y1205942D01*
X280595D01*
X279727Y1206810D01*
Y1209009D01*
X278736Y1210000D01*
X277394D01*
X275682Y1211712D01*
X274114D01*
G01X270374Y1215452D02*
X271896Y1216974D01*
X275400D01*
X278000Y1219574D01*
Y1229400D01*
X278900Y1230300D01*
X317500D01*
X319200Y1228600D01*
Y1208400D01*
X319700Y1207900D01*
X332780D01*
X336867Y1206207D01*
X339239Y1203835D01*
X359301D01*
X360325Y1202811D01*
Y1198863D01*
X362853Y1196335D01*
Y1191651D01*
X361519Y1190317D01*
X337597D01*
X335502Y1188222D01*
G01X308565Y228631D02*
X307808Y229388D01*
Y253746D01*
X305746Y255808D01*
X292913D01*
X290281Y258440D01*
X287627D01*
X285490Y256303D01*
G01X281594Y1200491D02*
X279900Y1198797D01*
Y1187800D01*
X280400Y1187300D01*
X282400D01*
X283800Y1185900D01*
Y1184400D01*
X284500Y1183700D01*
X286300D01*
X287100Y1182900D01*
Y1180299D01*
X287600Y1179799D01*
X289700D01*
X291100Y1178399D01*
Y1173840D01*
X292500Y1172440D01*
X332241D01*
X332866Y1173065D01*
X335190D01*
G01X342009Y1176100D02*
X341366Y1175457D01*
X337434D01*
X336686Y1176205D01*
X295495D01*
X290870Y1180830D01*
Y1183130D01*
X290300Y1183700D01*
X288600D01*
X287200Y1185100D01*
Y1186600D01*
X286500Y1187300D01*
X285000D01*
X283600Y1188700D01*
Y1201000D01*
X285334Y1202734D01*
Y1204232D01*
G01Y1211712D02*
X286912D01*
X290900Y1215700D01*
X299000D01*
X300300Y1214400D01*
Y1197865D01*
X302165Y1196000D01*
Y1188835D01*
X303547Y1187453D01*
X327571D01*
X333013Y1182011D01*
X343166D01*
X346360Y1185205D01*
X357083D01*
G01X281594Y1211712D02*
Y1213015D01*
X283538Y1214959D01*
Y1217500D01*
X285200Y1219162D01*
Y1221363D01*
X286637Y1222800D01*
X310599D01*
X311300Y1222099D01*
Y1204410D01*
X311800Y1203910D01*
X330513D01*
X331020Y1203403D01*
X336000D01*
X336511Y1202892D01*
Y1202184D01*
X336000Y1201673D01*
X331020D01*
X330513Y1201166D01*
Y1200450D01*
X331020Y1199943D01*
X336000D01*
X336511Y1199432D01*
Y1198724D01*
X336000Y1198213D01*
X331020D01*
X330513Y1197706D01*
Y1191234D01*
X331330Y1190417D01*
X332507D01*
X333014Y1190924D01*
Y1195854D01*
X333521Y1196361D01*
X334237D01*
X334744Y1195854D01*
Y1192854D01*
X335441Y1192157D01*
X336713D01*
X337243Y1192687D01*
Y1194069D01*
X337773Y1194599D01*
X338743D01*
X339273Y1194069D01*
Y1192687D01*
X339803Y1192157D01*
X343884D01*
X344385Y1192658D01*
Y1196459D01*
X344892Y1196966D01*
X345608D01*
X346115Y1196459D01*
Y1195154D01*
X346615Y1194654D01*
X347690D01*
X348220Y1195184D01*
Y1198295D01*
X348750Y1198825D01*
X349720D01*
X350250Y1198295D01*
Y1195184D01*
X350780Y1194654D01*
X351750D01*
X352280Y1195184D01*
Y1198295D01*
X352810Y1198825D01*
X353780D01*
X354310Y1198295D01*
Y1195184D01*
X354840Y1194654D01*
X355810D01*
X356340Y1195184D01*
Y1198295D01*
X356870Y1198825D01*
X357840D01*
X358370Y1198295D01*
Y1195184D01*
X358900Y1194654D01*
X360022D01*
X360523Y1194153D01*
Y1192282D01*
G01X469530Y366754D02*
Y365587D01*
X465430Y361487D01*
Y359153D01*
X468893Y355690D01*
Y328293D01*
X457348Y316748D01*
X416964D01*
X413232Y313016D01*
X363012D01*
X353410Y303414D01*
Y181311D01*
X306500Y134401D01*
Y111599D01*
X300300Y105399D01*
Y87999D01*
X304499Y83800D01*
X309646D01*
X311892Y86046D01*
G01X467335Y359944D02*
X470703Y356576D01*
Y327204D01*
X458437Y314938D01*
X417714D01*
X413982Y311206D01*
X369036D01*
X355642Y297812D01*
Y179510D01*
X308373Y132241D01*
Y110659D01*
X302126Y104412D01*
Y89574D01*
X305969Y85731D01*
X308338D01*
G01X299742Y112083D02*
Y133641D01*
X349700Y183599D01*
Y306599D01*
X360000Y316899D01*
Y331921D01*
X391479Y363400D01*
X456601D01*
X466100Y372899D01*
Y399407D01*
X474550Y407857D01*
Y463377D01*
X476973Y465800D01*
Y495947D01*
X474100Y498820D01*
Y718301D01*
X488000Y732201D01*
Y784501D01*
X468800Y803701D01*
Y831469D01*
X465000Y835269D01*
Y841801D01*
X467632Y844433D01*
Y885732D01*
X476445Y894545D01*
Y952219D01*
X476475Y952249D01*
G01X304031Y103621D02*
X310183Y109773D01*
Y131490D01*
X357800Y179107D01*
Y289016D01*
X359376Y290592D01*
G01X295948Y141247D02*
X304947D01*
X347600Y183900D01*
Y239689D01*
X342992Y244297D01*
X340988D01*
G01X329685Y228646D02*
X345658Y212673D01*
Y184557D01*
X318471Y157370D01*
X308180D01*
G01X318508Y324322D02*
X313180Y329650D01*
Y339955D01*
X306907Y346228D01*
Y361502D01*
X311163Y365758D01*
Y420752D01*
X306154Y425761D01*
Y454502D01*
X316275Y464623D01*
X327571D01*
X336190Y473242D01*
Y504765D01*
X348690Y517265D01*
Y529495D01*
X361910Y561411D01*
Y703485D01*
X367792Y709367D01*
Y735291D01*
X381500Y748999D01*
Y767800D01*
X383391Y769691D01*
Y804000D01*
G01X308952Y356875D02*
Y361309D01*
X312573Y364930D01*
Y421337D01*
X307564Y426346D01*
Y453917D01*
X316860Y463213D01*
X328156D01*
X337600Y472657D01*
Y504180D01*
X350100Y516680D01*
Y529214D01*
X363320Y561130D01*
Y702900D01*
X369202Y708782D01*
Y733395D01*
X383700Y747893D01*
Y762600D01*
X402147Y781047D01*
Y800094D01*
X399825Y802416D01*
X392883D01*
X382631Y812668D01*
Y813147D01*
X381631Y814147D01*
G01X312316Y356747D02*
Y362112D01*
X313983Y363779D01*
Y421922D01*
X308974Y426931D01*
Y453332D01*
X317445Y461803D01*
X328741D01*
X339010Y472072D01*
Y503595D01*
X351510Y516095D01*
Y528459D01*
X364730Y560375D01*
Y702315D01*
X370612Y708197D01*
Y732316D01*
X386000Y747704D01*
Y762400D01*
X403776Y780176D01*
Y802584D01*
X402005Y804355D01*
X392945D01*
X385666Y811634D01*
Y813103D01*
X384666Y814103D01*
G01X318500Y356519D02*
X316803Y358216D01*
Y423092D01*
X311794Y428101D01*
Y452162D01*
X318615Y458983D01*
X329911D01*
X341830Y470902D01*
Y502425D01*
X354330Y514925D01*
Y527896D01*
X367550Y559812D01*
Y701145D01*
X373432Y707027D01*
Y726432D01*
X390000Y743000D01*
Y761100D01*
X396400Y767500D01*
X402291D01*
X411715Y776924D01*
Y791715D01*
X450100Y830100D01*
Y874185D01*
X471110Y895195D01*
Y921577D01*
G01X315310Y356712D02*
Y362355D01*
X315393Y362438D01*
Y422507D01*
X310384Y427516D01*
Y452747D01*
X318030Y460393D01*
X329326D01*
X340420Y471487D01*
Y503010D01*
X352920Y515510D01*
Y528178D01*
X366140Y560094D01*
Y701730D01*
X372022Y707612D01*
Y727122D01*
X387900Y743000D01*
Y762304D01*
X410305Y784709D01*
Y792705D01*
X448417Y830817D01*
Y874498D01*
X469205Y895286D01*
Y922806D01*
X470600Y924201D01*
Y929767D01*
X471068Y930235D01*
G01X327591Y125107D02*
Y116721D01*
X337924Y106388D01*
Y95111D01*
G01X315944Y332584D02*
X323321Y339961D01*
Y354393D01*
X318613Y359101D01*
Y423845D01*
X313604Y428854D01*
Y451411D01*
X319366Y457173D01*
X330661D01*
X343640Y470152D01*
Y501675D01*
X356140Y514175D01*
Y527533D01*
X369360Y559449D01*
Y700395D01*
X375242Y706277D01*
Y725279D01*
X380963Y731000D01*
G01X349120Y336100D02*
X323243Y361977D01*
Y425765D01*
X318234Y430774D01*
Y449491D01*
X321286Y452543D01*
X332581D01*
X348270Y468232D01*
Y499755D01*
X360770Y512255D01*
Y526608D01*
X373990Y558524D01*
Y698475D01*
X379872Y704357D01*
Y721267D01*
X391470Y732865D01*
G01X348351Y319372D02*
X345523Y322200D01*
Y337702D01*
X321833Y361392D01*
Y425180D01*
X316824Y430189D01*
Y450076D01*
X320701Y453953D01*
X331996D01*
X346860Y468817D01*
Y500340D01*
X359360Y512840D01*
Y526890D01*
X372580Y558806D01*
Y699060D01*
X378462Y704942D01*
Y722962D01*
X393727Y738227D01*
Y754875D01*
X399372Y760520D01*
X410406D01*
X419602Y769716D01*
Y780209D01*
X415500Y784311D01*
Y791100D01*
X453400Y829000D01*
Y873495D01*
X474540Y894635D01*
Y927341D01*
G01X348806Y315427D02*
X343200Y321033D01*
Y338030D01*
X320423Y360807D01*
Y424595D01*
X315414Y429604D01*
Y450661D01*
X320116Y455363D01*
X331411D01*
X345450Y469402D01*
Y500925D01*
X357950Y513425D01*
Y527172D01*
X371170Y559088D01*
Y699645D01*
X377052Y705527D01*
Y724052D01*
X391900Y738900D01*
Y760900D01*
X396900Y765900D01*
X408848D01*
X413125Y770177D01*
Y791125D01*
X451600Y829600D01*
Y873690D01*
X473015Y895105D01*
Y923540D01*
X472300Y925266D01*
Y928385D01*
X473992Y930077D01*
Y952546D01*
G01X351132Y322202D02*
Y336783D01*
X324653Y363262D01*
Y426350D01*
X319644Y431359D01*
Y448906D01*
X321871Y451133D01*
X333166D01*
X349680Y467647D01*
Y499170D01*
X362180Y511670D01*
Y526325D01*
X375400Y558241D01*
Y697890D01*
X381282Y703772D01*
Y719282D01*
X396157Y734157D01*
Y754273D01*
X400437Y758553D01*
X417345D01*
X423400Y764608D01*
Y787900D01*
X426800Y791300D01*
X430800D01*
X454935Y815435D01*
Y864771D01*
X460498Y870334D01*
G01X463404Y846870D02*
X461900Y845366D01*
Y820100D01*
X431400Y789600D01*
X428200D01*
X425200Y786600D01*
Y761660D01*
X416404Y752864D01*
X401292D01*
X397576Y749148D01*
Y732675D01*
X382692Y717791D01*
Y703187D01*
X376810Y697305D01*
Y557959D01*
X363590Y526043D01*
Y511085D01*
X351090Y498585D01*
Y466985D01*
X347852Y463747D01*
Y457452D01*
X346700Y456300D01*
X340328D01*
X333751Y449723D01*
X323954D01*
X323454Y449223D01*
Y429646D01*
X326063Y427037D01*
Y363847D01*
X353800Y336110D01*
Y316782D01*
X336763Y299745D01*
Y253263D01*
X333921Y250421D01*
Y246379D01*
X335900Y244400D01*
X340885D01*
X340988Y244297D01*
G01X342293Y106561D02*
X340312D01*
X329777Y117096D01*
Y137334D01*
X336205Y143762D01*
G01X470796Y394592D02*
X476624D01*
X478823Y392393D01*
Y332205D01*
X459746Y313128D01*
X418465D01*
X414733Y309396D01*
X371329D01*
X361281Y299348D01*
Y289801D01*
X359600Y288120D01*
Y177155D01*
X336244Y153799D01*
Y143801D01*
X336205Y143762D01*
G01X383462Y860535D02*
X378800Y865197D01*
Y948200D01*
X374400Y952600D01*
Y979666D01*
X387233Y1010649D01*
X397200Y1060756D01*
Y1075809D01*
X395720Y1079382D01*
X385961Y1097639D01*
X363700Y1119900D01*
Y1135500D01*
X361070Y1138130D01*
X339251D01*
G01X358636Y90615D02*
X392452D01*
X398531Y84536D01*
Y47631D01*
X400714Y45448D01*
G01X353324Y90650D02*
X355264Y88710D01*
X391796D01*
X396292Y84214D01*
Y45948D01*
X399640Y42600D01*
X401838D01*
X404686Y45448D01*
G01X353074Y95236D02*
X358495D01*
X361265Y92466D01*
X366628D01*
X369562Y95400D01*
X374762D01*
X375762Y96400D01*
X389675D01*
X390750Y97475D01*
G01X385131Y487382D02*
X372844Y475095D01*
X365811D01*
X350158Y459442D01*
Y455458D01*
X349034Y454334D01*
X345050D01*
G01X586136Y908935D02*
X585100Y907899D01*
Y827161D01*
X586452Y825809D01*
Y810543D01*
X580195Y804286D01*
Y781995D01*
X550900Y752700D01*
Y682454D01*
X553400Y679954D01*
Y653100D01*
X550669Y650369D01*
Y436469D01*
X547600Y433400D01*
Y353983D01*
X489168Y295551D01*
Y274208D01*
X473802Y258842D01*
X463576D01*
X454062Y249328D01*
Y239142D01*
X425370Y210450D01*
Y165050D01*
X401097Y140777D01*
Y115786D01*
X404600Y112283D01*
Y111101D01*
X401590Y108091D01*
X389890D01*
X387899Y106100D01*
X381899D01*
X373950Y98151D01*
X365922D01*
X363007Y95236D01*
G01X362957Y99961D02*
X373199D01*
X381238Y108000D01*
X387239D01*
X389140Y109901D01*
X399922D01*
X402104Y112083D01*
G01X365073Y258880D02*
X378811D01*
X383293Y254398D01*
X406958D01*
X408394Y252962D01*
Y210606D01*
X410136Y208864D01*
X414658D01*
G01X393646Y474382D02*
X389046Y478982D01*
Y486162D01*
X365000Y510208D01*
Y525762D01*
X378220Y557678D01*
Y696720D01*
X384102Y702602D01*
Y716903D01*
X399500Y732301D01*
Y747966D01*
X402565Y751031D01*
X416571D01*
X427000Y761460D01*
Y785500D01*
X429600Y788100D01*
X432500D01*
X463437Y819037D01*
Y843237D01*
X465492Y845292D01*
Y861970D01*
G01X368964Y937738D02*
Y934936D01*
X370700Y933200D01*
Y833250D01*
X373703Y830247D01*
Y782555D01*
G01X372858Y935136D02*
Y834249D01*
X375900Y831207D01*
Y787058D01*
X380331Y782627D01*
G01X365691Y815127D02*
Y829282D01*
X364399Y830574D01*
Y927119D01*
X368626Y931346D01*
G01X362042Y814772D02*
Y929831D01*
X366761Y934550D01*
G01X371507Y815303D02*
Y827935D01*
X368067Y831375D01*
Y925136D01*
G01X370101Y953699D02*
X376945Y946855D01*
Y833418D01*
X377800Y832563D01*
Y789739D01*
X380607Y786932D01*
G01X410927Y228631D02*
X410170Y229388D01*
Y253746D01*
X407681Y256235D01*
X394848D01*
X392643Y258440D01*
X389989D01*
X387852Y256303D01*
G01X387958Y813700D02*
X388500Y814242D01*
Y822143D01*
X383462Y827181D01*
Y860535D01*
G01X414145Y27486D02*
X411965Y29666D01*
Y46928D01*
X409400Y49493D01*
Y74946D01*
X402447Y81899D01*
Y106147D01*
X406500Y110200D01*
Y115000D01*
X402907Y118593D01*
Y140027D01*
X427180Y164300D01*
Y209700D01*
X455993Y238513D01*
Y248192D01*
X464833Y257032D01*
X474553D01*
X490978Y273457D01*
Y294800D01*
X509982Y313804D01*
X511790D01*
G01X413904Y32569D02*
X413830D01*
Y48670D01*
X411665Y50835D01*
Y75920D01*
X404400Y83185D01*
Y104383D01*
X410398Y110381D01*
Y123740D01*
X404900Y129238D01*
Y139460D01*
X428990Y163550D01*
Y208950D01*
X466621Y246581D01*
Y250021D01*
X471305Y254705D01*
X474786D01*
X492788Y272707D01*
Y294049D01*
X495314Y296575D01*
X496064D01*
X497933Y294706D01*
X498683D01*
X500437Y296460D01*
Y297210D01*
X498568Y299079D01*
Y299829D01*
X500322Y301583D01*
X501072D01*
X502941Y299714D01*
X503691D01*
X505445Y301468D01*
Y302218D01*
X503576Y304087D01*
Y304837D01*
X507425Y308686D01*
X511742D01*
X514769Y311713D01*
Y312953D01*
G01X402104Y112083D02*
X399287Y114900D01*
Y141527D01*
X423560Y165800D01*
Y211200D01*
X452079Y239719D01*
Y250178D01*
X462553Y260652D01*
X473051D01*
X487358Y274959D01*
Y296302D01*
X544458Y353402D01*
Y434057D01*
X548369Y437968D01*
Y664668D01*
X551590Y667889D01*
Y679204D01*
X549000Y681794D01*
Y753360D01*
X576573Y780933D01*
Y803384D01*
X584642Y811453D01*
Y825058D01*
X583065Y826635D01*
Y903294D01*
G01X519638Y314346D02*
Y312838D01*
X495973Y289173D01*
Y273331D01*
X474819Y252177D01*
X471776D01*
X469213Y249614D01*
Y246613D01*
X430800Y208200D01*
Y162800D01*
X406710Y138710D01*
Y129989D01*
X412208Y124491D01*
Y109436D01*
X406393Y103621D01*
G01X414658Y208864D02*
X412400Y211122D01*
Y227422D01*
X414730Y229752D01*
Y260743D01*
X432421Y278434D01*
Y292114D01*
X450295Y309988D01*
X463040D01*
X488329Y335277D01*
Y404092D01*
X479580Y412841D01*
Y461290D01*
X485508Y467218D01*
Y494529D01*
X480200Y499837D01*
Y545634D01*
X479260Y547904D01*
Y713860D01*
X494700Y729300D01*
Y786700D01*
X477543Y803857D01*
Y860784D01*
X477574Y860815D01*
G01X410927Y228631D02*
X412891Y230595D01*
Y261445D01*
X430825Y279379D01*
Y292965D01*
X449578Y311718D01*
X461457D01*
X486100Y336361D01*
Y402500D01*
X478170Y410430D01*
Y461876D01*
X484098Y467804D01*
Y493943D01*
X477850Y500191D01*
Y715849D01*
X492300Y730299D01*
Y786499D01*
X475700Y803099D01*
Y830901D01*
X469312Y837289D01*
Y840611D01*
X471726Y843025D01*
Y883705D01*
G01X432303Y785067D02*
X449136Y801900D01*
X462900D01*
X486000Y778800D01*
Y733600D01*
X472690Y720290D01*
Y498235D01*
X475563Y495362D01*
Y466385D01*
X473140Y463962D01*
Y409615D01*
X448391Y384866D01*
Y382641D01*
G01X434424Y1286274D02*
Y1292290D01*
X431885Y1294829D01*
Y1313115D01*
G01X490989Y244297D02*
X490745Y244053D01*
X485585D01*
X482677Y246961D01*
X471556D01*
X444792Y220197D01*
Y142404D01*
X445949Y141247D01*
G01X458181Y157370D02*
X458401Y157590D01*
Y220289D01*
X466758Y228646D01*
X479686D01*
G01X477592Y125107D02*
Y116007D01*
X487925Y105674D01*
Y95111D01*
G01X486206Y143762D02*
X479778Y137334D01*
Y116822D01*
X490039Y106561D01*
X492294D01*
G01X562001Y732834D02*
X554389Y725222D01*
Y683521D01*
X557300Y680610D01*
Y647242D01*
X553889Y643831D01*
Y434511D01*
X555900Y432500D01*
Y344387D01*
X519902Y308389D01*
Y305050D01*
X518155Y303303D01*
X514816D01*
X500933Y289420D01*
Y168487D01*
X486245Y153799D01*
Y143801D01*
X486206Y143762D01*
G01X501649Y482165D02*
X497198Y486616D01*
Y499386D01*
X482905Y513679D01*
Y527726D01*
G01X484772Y625311D02*
X481000Y621539D01*
Y548308D01*
X482185Y545446D01*
X482905Y544726D01*
G01X484772Y625311D02*
X483000D01*
X482500Y625811D01*
Y635583D01*
X493518Y646601D01*
X535538D01*
X543378Y654441D01*
Y682567D01*
X545304Y684493D01*
Y696569D01*
X543101Y698772D01*
G01X479448Y828594D02*
Y804653D01*
X496900Y787201D01*
Y728700D01*
X482300Y714100D01*
Y663408D01*
X483059Y662649D01*
G01X494315Y941212D02*
Y857215D01*
X486900Y849800D01*
Y825477D01*
X489572Y822805D01*
G01X491616Y938771D02*
X492800Y937587D01*
Y857999D01*
X485100Y850299D01*
Y823401D01*
X518261Y790240D01*
Y787303D01*
X526861Y778703D01*
Y757627D01*
X543574Y740914D01*
Y703288D01*
X540867Y700581D01*
Y697546D01*
X542912Y695501D01*
Y684778D01*
X541611Y683477D01*
Y660266D01*
X539629Y658284D01*
X507431D01*
X499739Y665976D01*
X496070D01*
G01X489163Y977163D02*
Y950327D01*
X496400Y943090D01*
Y856599D01*
X488755Y848954D01*
Y834010D01*
X490686Y832079D01*
X493066D01*
X494677Y830468D01*
G01X498524Y997590D02*
Y989538D01*
X486604Y977618D01*
Y940241D01*
X485064Y938701D01*
Y864981D01*
X490706Y859339D01*
G01X546293Y76587D02*
Y84214D01*
X541797Y88710D01*
X505265D01*
X503325Y90650D01*
G01X503075Y95236D02*
X508496D01*
X511266Y92466D01*
X516629D01*
X519563Y95400D01*
X524763D01*
X525863Y96500D01*
X539776D01*
X540751Y97475D01*
G01X490989Y244297D02*
X498650Y251958D01*
Y289584D01*
X514417Y305351D01*
X516026D01*
X517203Y306528D01*
Y308137D01*
X549631Y340565D01*
Y432032D01*
X552479Y434880D01*
Y644416D01*
X555600Y647537D01*
Y680315D01*
X552979Y682936D01*
Y726893D01*
X558616Y732530D01*
G01X496729Y470419D02*
Y475419D01*
X494740Y477408D01*
Y489978D01*
X492736Y491982D01*
G01X496729Y470419D02*
Y466025D01*
X497860Y464894D01*
X530103D01*
X546900Y481691D01*
Y666200D01*
X544788Y668312D01*
Y681497D01*
X547100Y683809D01*
Y741380D01*
X529805Y758675D01*
Y780440D01*
X521617Y788628D01*
Y791184D01*
X514547Y798254D01*
Y832029D01*
X512777Y833799D01*
Y841781D01*
X515716Y844720D01*
Y901717D01*
X521900Y907901D01*
Y937806D01*
X523289Y939195D01*
G01X517310Y470045D02*
Y468329D01*
X515906Y466925D01*
X504683D01*
X502705Y468903D01*
Y473844D01*
X500860Y475689D01*
Y481376D01*
X501649Y482165D01*
G01X513504Y755804D02*
X503093D01*
X498790Y751501D01*
Y740429D01*
X526699Y712520D01*
Y706388D01*
G01X524598Y753387D02*
X521386D01*
X519099Y751100D01*
X504600D01*
X500200Y746700D01*
Y741065D01*
X531385Y709880D01*
Y704506D01*
X529501Y702622D01*
G01X504508Y783817D02*
X509372Y778953D01*
X515269D01*
X520833Y773389D01*
G01X513551Y773203D02*
X509741D01*
X501825Y781119D01*
Y786323D01*
X504641Y789139D01*
G01X514649Y1020266D02*
X518005Y1016910D01*
Y966911D01*
X503533Y952439D01*
Y863175D01*
X503383Y863025D01*
G01X514690Y996766D02*
Y973692D01*
X498507Y957509D01*
Y865392D01*
G01X519500Y1028377D02*
X519415Y1028292D01*
Y965874D01*
X504943Y951402D01*
Y869320D01*
X508900Y865363D01*
Y825277D01*
X509665Y824512D01*
G01X503144Y957934D02*
X516595Y971385D01*
Y1002861D01*
X514690Y1004766D01*
G01X546293Y72615D02*
X548532Y74854D01*
Y84536D01*
X542453Y90615D01*
X508637D01*
G01X512958Y99961D02*
X523200D01*
X531239Y108000D01*
X537240D01*
X539141Y109901D01*
X549923D01*
X552105Y112083D01*
G01X513008Y95236D02*
X515923Y98151D01*
X523951D01*
X531900Y106100D01*
X537900D01*
X539891Y108091D01*
X550991D01*
X554300Y111400D01*
Y113674D01*
X553027Y114947D01*
Y129654D01*
X601930Y178557D01*
Y288469D01*
X564910Y325489D01*
Y437490D01*
X561339Y441061D01*
Y640740D01*
X566700Y646101D01*
Y674801D01*
X571700Y679801D01*
Y732200D01*
X593439Y753939D01*
X598823Y766938D01*
Y907324D01*
X604715Y913216D01*
Y914640D01*
G01X515074Y258880D02*
X528812D01*
X533294Y254398D01*
X556959D01*
X558441Y252916D01*
Y228282D01*
X556541Y226382D01*
Y216982D01*
X564659Y208864D01*
G01X520146Y939241D02*
Y909446D01*
X514306Y903606D01*
Y845305D01*
X511367Y842366D01*
Y832820D01*
X512817Y831370D01*
Y797783D01*
X519887Y790713D01*
Y787876D01*
X528317Y779446D01*
Y758167D01*
X545300Y741184D01*
Y700971D01*
X543101Y698772D01*
G01X516902Y910251D02*
Y916607D01*
X511701Y921808D01*
Y941998D01*
X511171Y942528D01*
X509205D01*
X508675Y943058D01*
Y944528D01*
X509205Y945058D01*
X511171D01*
X511701Y945588D01*
Y952916D01*
X521796Y963011D01*
Y966771D01*
X528600Y973575D01*
Y1029700D01*
X546430Y1047530D01*
X598447D01*
X599806Y1048889D01*
Y1052902D01*
X599276Y1053432D01*
X593181D01*
X592509Y1054104D01*
Y1056472D01*
X593009Y1056972D01*
X599276D01*
X599806Y1057502D01*
Y1059982D01*
X599276Y1060512D01*
X594904D01*
X594374Y1061042D01*
Y1063522D01*
X594904Y1064052D01*
X599276D01*
X599806Y1064582D01*
Y1065898D01*
X600336Y1066428D01*
X603152D01*
X603682Y1065898D01*
Y1053457D01*
G01X514690Y1004766D02*
Y1012037D01*
X512187Y1014540D01*
Y1028110D01*
X514843Y1030766D01*
G01X560928Y228631D02*
X560171Y229388D01*
Y253746D01*
X558109Y255808D01*
X546992D01*
X544360Y258440D01*
X539990D01*
X537853Y256303D01*
G01X550087Y829836D02*
Y834322D01*
X539819Y844590D01*
Y868082D01*
X529789Y878112D01*
Y884786D01*
X525159Y889416D01*
Y913818D01*
G01X538468Y888033D02*
X540764D01*
X547558Y894827D01*
Y901885D01*
X540400Y909043D01*
Y988399D01*
X539300Y989499D01*
Y1024399D01*
X552991Y1038090D01*
X606823D01*
X607993Y1036920D01*
G01X606434Y1041904D02*
X604730Y1040200D01*
X551198D01*
X536400Y1025402D01*
Y988298D01*
X537998Y986700D01*
Y906999D01*
X540600Y904397D01*
Y896100D01*
X538700Y894200D01*
X536885D01*
X530968Y888283D01*
G01X610780Y1051037D02*
X602553Y1042810D01*
X550049D01*
X533320Y1026081D01*
Y964496D01*
X534986Y962830D01*
Y909688D01*
X534169Y908871D01*
X529421D01*
X528419Y907869D01*
Y906871D01*
X528949Y906341D01*
X535078D01*
X535608Y905811D01*
Y902398D01*
X533143Y899933D01*
Y897910D01*
G01X612955Y1062941D02*
X631429D01*
X632163Y1063675D01*
Y1066509D01*
X631201Y1067471D01*
X608589D01*
X606866Y1065748D01*
Y1051828D01*
X600458Y1045420D01*
X548621D01*
X530710Y1027509D01*
Y972167D01*
X525483Y966940D01*
Y962731D01*
X531076Y957138D01*
Y913190D01*
G01X584679Y336285D02*
Y308695D01*
X603740Y289634D01*
Y177806D01*
X554869Y128935D01*
Y115920D01*
X556400Y114389D01*
Y110501D01*
X551600Y105701D01*
Y87798D01*
X555572Y83826D01*
X562035D01*
X564255Y86046D01*
G01X578193Y336391D02*
Y337532D01*
X580554Y339893D01*
X584730D01*
X587529Y337094D01*
Y308972D01*
X605550Y290951D01*
Y177055D01*
X560200Y131705D01*
Y111400D01*
X554397Y105597D01*
Y87940D01*
X556606Y85731D01*
X560701D01*
G01X552105Y112083D02*
Y113243D01*
X551186Y114162D01*
Y130374D01*
X600120Y179308D01*
Y287180D01*
X563100Y324200D01*
Y436599D01*
X559529Y440170D01*
Y641491D01*
X564625Y646587D01*
Y676025D01*
X569849Y681249D01*
Y733550D01*
X592318Y756019D01*
X596733Y766677D01*
Y907933D01*
X601084Y912284D01*
Y913544D01*
G01X548311Y141247D02*
X560064D01*
X598710Y179893D01*
Y240942D01*
X595355Y244297D01*
X593351D01*
G01X560928Y228631D02*
X562196Y229899D01*
Y311803D01*
X557400Y316599D01*
Y433599D01*
X555299Y435700D01*
Y643246D01*
X559000Y646947D01*
Y677900D01*
X564659Y683559D01*
Y735359D01*
X586416Y757116D01*
X591496Y769379D01*
Y870093D01*
X588905Y872684D01*
Y923561D01*
X598201Y932857D01*
Y946313D01*
X602484Y950596D01*
Y965764D01*
G01X617634Y1049283D02*
Y1052804D01*
X618043Y1053213D01*
X623846D01*
X626051Y1055418D01*
Y1059667D01*
X624894Y1060824D01*
X615035D01*
X614338Y1060127D01*
Y1059031D01*
X613838Y1058531D01*
X610406D01*
X609906Y1058031D01*
Y1056589D01*
X610895Y1055600D01*
X612122D01*
X614338Y1053384D01*
Y1039298D01*
X606614Y1031574D01*
X589933D01*
X583771Y1025412D01*
X572860D01*
X568646Y1021198D01*
X563628D01*
X554290Y1011860D01*
Y1005486D01*
X552647Y1003843D01*
X549409D01*
X546808Y1001242D01*
Y957602D01*
X553590Y950820D01*
Y916881D01*
X564292Y906179D01*
Y898594D01*
X567112Y895774D01*
Y893374D01*
X553269Y879531D01*
Y875696D01*
X548962Y871389D01*
X546940D01*
G01X587880Y1034834D02*
X586235D01*
X578923Y1027522D01*
X562400D01*
X558678Y1023800D01*
Y1019493D01*
X550173Y1010988D01*
X545489D01*
X542058Y1007557D01*
Y1003443D01*
X544698Y1000803D01*
Y955963D01*
X551132Y949529D01*
Y901540D01*
X558261Y894411D01*
X564165D01*
G01X617894Y1043955D02*
X616994Y1043055D01*
Y1038969D01*
X606925Y1028900D01*
X591071D01*
X582220Y1020049D01*
X570482D01*
X569521Y1019088D01*
X565662D01*
X563378Y1016804D01*
Y1009426D01*
X561252Y1007300D01*
X559089D01*
X553522Y1001733D01*
X550333D01*
X548918Y1000318D01*
Y975982D01*
X552810Y972090D01*
X596157D01*
X599824Y968423D01*
Y965699D01*
X600665Y964858D01*
Y951047D01*
X596516Y946898D01*
Y933735D01*
X576481Y913700D01*
Y901706D01*
X580327Y897860D01*
Y892000D01*
G01X592900Y309871D02*
X607360Y295411D01*
Y176304D01*
X562546Y131490D01*
Y109773D01*
X556394Y103621D01*
G01X582048Y228646D02*
X597300Y213394D01*
Y180479D01*
X574191Y157370D01*
X560543D01*
G01X592272Y877262D02*
X593383Y876151D01*
Y768835D01*
X588396Y756795D01*
X566389Y734788D01*
Y682689D01*
X561165Y677465D01*
Y647117D01*
X556709Y642661D01*
Y437192D01*
X558900Y435001D01*
Y323850D01*
X564218Y318532D01*
Y246826D01*
X567803Y243241D01*
Y212008D01*
X564659Y208864D01*
G01X593351Y244297D02*
X598300Y249246D01*
Y286446D01*
X560700Y324046D01*
Y435800D01*
X558119Y438381D01*
Y642076D01*
X562895Y646852D01*
Y676894D01*
X568119Y682118D01*
Y734319D01*
X590325Y756525D01*
X595248Y768410D01*
Y880381D01*
X592110Y883519D01*
Y895611D01*
G01X576556Y728219D02*
Y679256D01*
X568800Y671500D01*
Y645640D01*
X563149Y639989D01*
Y442652D01*
X566720Y439081D01*
Y363231D01*
X591502Y338449D01*
Y315345D01*
X608770Y298077D01*
Y175718D01*
X588607Y155555D01*
Y143801D01*
X588568Y143762D01*
G01X573895Y965319D02*
X565401D01*
X555700Y955618D01*
Y919894D01*
X567063Y908531D01*
Y900394D01*
X573239Y894218D01*
Y870974D01*
X579406Y864807D01*
Y826222D01*
X578700Y825516D01*
Y822237D01*
X581106Y819831D01*
X582737D01*
G01X597556Y965829D02*
X596259D01*
X594834Y964404D01*
X579970D01*
X577077Y961511D01*
X569347D01*
X560437Y952601D01*
Y921028D01*
X570258Y911207D01*
Y900929D01*
X576705Y894482D01*
Y882872D01*
X581216Y878361D01*
Y823531D01*
X581158Y823473D01*
G01X608965Y966414D02*
X601321Y974058D01*
X567821D01*
X564996Y976883D01*
Y979707D01*
X560923Y983780D01*
Y988813D01*
G01X588568Y143762D02*
X582140Y137334D01*
Y117098D01*
X592677Y106561D01*
X594656D01*
G01X579954Y125107D02*
Y116723D01*
X590287Y106390D01*
Y95111D01*
G01X612923Y997860D02*
X611045Y995982D01*
Y952804D01*
X599863Y941622D01*
Y924936D01*
X606800Y917999D01*
Y912601D01*
X601612Y907413D01*
Y768624D01*
X594206Y750744D01*
X575979Y732517D01*
G01X648655Y76587D02*
Y84214D01*
X644159Y88710D01*
X607627D01*
X605687Y90650D01*
G01X648655Y72615D02*
X650894Y74854D01*
Y84536D01*
X644815Y90615D01*
X610999D01*
G01X615370Y95236D02*
X618285Y98151D01*
X626313D01*
X634262Y106100D01*
X640262D01*
X642253Y108091D01*
X653691D01*
X656700Y111100D01*
Y113956D01*
X654955Y115701D01*
Y129576D01*
X703720Y178341D01*
Y310871D01*
X679836Y334755D01*
Y344173D01*
X689300Y353637D01*
Y714100D01*
X695615Y720415D01*
Y790614D01*
X702914Y797913D01*
Y827320D01*
X703074Y827707D01*
Y831919D01*
X718994Y870352D01*
Y894453D01*
X719234Y894693D01*
Y895294D01*
X725194Y901254D01*
Y942073D01*
G01X615320Y99961D02*
X625562D01*
X633601Y108000D01*
X639602D01*
X641503Y109901D01*
X652285D01*
X654467Y112083D01*
G01X605437Y95236D02*
X610858D01*
X613628Y92466D01*
X618991D01*
X621925Y95400D01*
X627125D01*
X628225Y96500D01*
X642138D01*
X643113Y97475D01*
G01X617436Y258880D02*
X631174D01*
X635656Y254398D01*
X659321D01*
X660803Y252916D01*
Y228282D01*
X658903Y226382D01*
Y216982D01*
X667021Y208864D01*
G01X650673Y141247D02*
X662064D01*
X700500Y179683D01*
Y241514D01*
X697717Y244297D01*
X695713D01*
G01X663290Y228631D02*
X662533Y229388D01*
Y253746D01*
X660044Y256235D01*
X647765D01*
X645560Y258440D01*
X642352D01*
X640215Y256303D01*
G01X689486Y339583D02*
X705530Y323539D01*
Y177590D01*
X656986Y129046D01*
Y116459D01*
X658700Y114745D01*
Y110299D01*
X654500Y106099D01*
Y87260D01*
X658660Y83100D01*
X663671D01*
X666617Y86046D01*
G01X663063Y85731D02*
X658968D01*
X656759Y87940D01*
Y105459D01*
X661400Y110100D01*
Y130899D01*
X707340Y176839D01*
Y324799D01*
X690338Y341801D01*
X683357D01*
X682857Y341301D01*
Y339477D01*
G01X654467Y112083D02*
X653125Y113425D01*
Y130314D01*
X701910Y179092D01*
Y309538D01*
X677694Y333754D01*
Y344592D01*
X683448Y350346D01*
Y421692D01*
X687244Y425488D01*
Y785547D01*
X701104Y799407D01*
Y827680D01*
X701264Y828067D01*
Y832692D01*
X717169Y871088D01*
Y896069D01*
X722976Y901876D01*
Y926908D01*
X722789Y927095D01*
G01X718338Y305272D02*
X709150Y296084D01*
Y176088D01*
X663700Y130638D01*
Y108565D01*
X658756Y103621D01*
G01X684410Y228646D02*
X699090Y213966D01*
Y180269D01*
X676191Y157370D01*
X662905D01*
G01X719661Y904900D02*
X713804Y899043D01*
Y872616D01*
X697804Y833991D01*
Y800775D01*
X683784Y786755D01*
Y714734D01*
X678681Y709631D01*
Y536881D01*
X680326Y535236D01*
Y473571D01*
X684104Y469793D01*
Y455510D01*
X680628Y452034D01*
Y351517D01*
X670984Y341873D01*
Y263668D01*
X666540Y259224D01*
Y224492D01*
X664883Y222835D01*
Y215934D01*
X665965Y214852D01*
X667858D01*
X669486Y213224D01*
Y211329D01*
X667021Y208864D01*
G01X663290Y228631D02*
X664585Y229926D01*
Y260776D01*
X668945Y265136D01*
Y341829D01*
X679218Y352102D01*
Y452619D01*
X682694Y456095D01*
Y469207D01*
X677271Y474630D01*
Y710668D01*
X682027Y715424D01*
Y787445D01*
X696074Y801492D01*
Y834256D01*
X712394Y873653D01*
Y904249D01*
X719474Y911329D01*
Y928471D01*
X720271Y929268D01*
Y931730D01*
G01X697018Y106561D02*
X694639D01*
X684502Y116698D01*
Y137334D01*
X690930Y143762D01*
G01X682316Y125107D02*
Y116183D01*
X692649Y105850D01*
Y95111D01*
G01X722400Y942500D02*
Y929401D01*
X720884Y927885D01*
Y922729D01*
X721566Y922047D01*
Y902461D01*
X715774Y896669D01*
Y896275D01*
X715214Y895715D01*
Y871579D01*
X699534Y833723D01*
Y800058D01*
X685514Y786038D01*
Y426205D01*
X682038Y422729D01*
Y350931D01*
X676284Y345177D01*
Y332110D01*
X695713Y312681D01*
Y244297D01*
G01X690930Y143762D02*
X690969Y143801D01*
Y155911D01*
X710560Y175502D01*
Y293353D01*
X720243Y303036D01*
Y316890D01*
X691200Y345933D01*
Y713300D01*
X697425Y719525D01*
Y789224D01*
X704724Y796523D01*
Y826444D01*
X722600Y869600D01*
G01X728846Y948331D02*
Y943447D01*
X730896Y941397D01*
Y901997D01*
X723947Y895048D01*
X723917D01*
X722802Y893933D01*
Y893903D01*
X722454Y893555D01*
Y876542D01*
X726200Y872796D01*
Y868313D01*
X709924Y829021D01*
Y795934D01*
X705900Y791910D01*
Y783589D01*
X707700Y781789D01*
Y723500D01*
X694747Y710547D01*
Y348453D01*
X721500Y321700D01*
X743295D01*
X764970Y300025D01*
Y271829D01*
X767940Y268859D01*
Y226661D01*
X772527Y222074D01*
Y212008D01*
X769383Y208864D01*
G01X727116Y959326D02*
X726893Y959103D01*
Y942935D01*
X728900Y940928D01*
Y902400D01*
X721044Y894544D01*
Y893943D01*
X720804Y893703D01*
Y876197D01*
X724700Y872301D01*
Y869147D01*
X707191Y826875D01*
Y796091D01*
X699698Y788598D01*
Y718498D01*
X693017Y711817D01*
Y347426D01*
X720153Y320290D01*
X742710D01*
X763560Y299440D01*
Y270040D01*
X766425Y267175D01*
Y227308D01*
X763653Y224536D01*
G01X798075Y244297D02*
Y254658D01*
X766380Y286353D01*
Y300610D01*
X743880Y323110D01*
X723291D01*
X696600Y349801D01*
Y710401D01*
X709400Y723201D01*
Y782601D01*
X708300Y783701D01*
Y791430D01*
X712901Y796031D01*
Y821600D01*
G01X733798Y950186D02*
X735900Y948084D01*
Y900700D01*
X732821Y897621D01*
Y870478D01*
X721447Y843018D01*
Y792599D01*
X723200Y790846D01*
Y779190D01*
X715794Y771784D01*
Y724634D01*
X700768Y709608D01*
Y688784D01*
X709491Y680061D01*
Y654591D01*
X704100Y649200D01*
Y634739D01*
X700338Y630977D01*
Y531736D01*
X700500Y531574D01*
Y352861D01*
X727031Y326330D01*
X745215D01*
X769600Y301945D01*
Y287689D01*
X806296Y250993D01*
Y178928D01*
X758637Y131269D01*
X758636D01*
X758103Y130736D01*
Y114697D01*
X759600Y113200D01*
Y111600D01*
X759562D01*
X756053Y108091D01*
X744615D01*
X742624Y106100D01*
X736624D01*
X728675Y98151D01*
X720647D01*
X717732Y95236D01*
G01X756829Y112083D02*
Y113372D01*
X756207Y113994D01*
Y131401D01*
X804486Y179680D01*
Y250242D01*
X767790Y286938D01*
Y301195D01*
X744465Y324520D01*
X725280D01*
X698528Y351272D01*
Y632510D01*
X702100Y636082D01*
Y649803D01*
X707681Y655384D01*
Y679310D01*
X698754Y688237D01*
Y710154D01*
X711514Y722914D01*
Y780293D01*
X717270Y786049D01*
Y838073D01*
X731011Y871248D01*
Y899011D01*
X732306Y900306D01*
Y942682D01*
G01X751017Y76587D02*
Y84922D01*
X747229Y88710D01*
X709989D01*
X708049Y90650D01*
G01X751017Y72615D02*
X753256Y74854D01*
Y85244D01*
X747885Y90615D01*
X713361D01*
G01X717682Y99961D02*
X727924D01*
X735963Y108000D01*
X741964D01*
X743865Y109901D01*
X754647D01*
X756829Y112083D01*
G01X707799Y95236D02*
X713220D01*
X715990Y92466D01*
X722867D01*
X726701Y96300D01*
X744300D01*
X745475Y97475D01*
G01X705019Y1211711D02*
X706890Y1213582D01*
X732107D01*
X733013Y1212676D01*
Y1210676D01*
X733665Y1210024D01*
X740089D01*
X740492Y1210427D01*
Y1212973D01*
X741174Y1213655D01*
X742944D01*
X744689Y1215400D01*
X756200D01*
X757500Y1214100D01*
Y1189200D01*
X759176Y1187524D01*
X790376D01*
X793895Y1184005D01*
X799402D01*
X802612Y1187215D01*
X805519D01*
G01X708760Y1211711D02*
Y1211567D01*
X710485Y1209842D01*
X725037D01*
X725502Y1209377D01*
Y1206829D01*
X726331Y1206000D01*
X728606D01*
X729382Y1205224D01*
Y1202824D01*
X730065Y1202141D01*
X739174D01*
X740617Y1203584D01*
Y1205504D01*
X741113Y1206000D01*
X743053D01*
X744605Y1204448D01*
Y1180370D01*
X745275Y1179700D01*
X747106D01*
X749011Y1177795D01*
X755249D01*
X756817Y1176227D01*
X784345D01*
X786418Y1178300D01*
X803930D01*
X804558Y1177672D01*
X805821D01*
X809217Y1181068D01*
X816928D01*
X821098Y1185238D01*
X823516D01*
G01X719798Y258880D02*
X733536D01*
X738393Y254023D01*
X759983D01*
X761682Y252324D01*
Y226799D01*
X761265Y226382D01*
Y216982D01*
X769383Y208864D01*
G01X821582Y727140D02*
Y719706D01*
X821673Y719615D01*
Y537241D01*
X805884Y521452D01*
Y513652D01*
X794810Y502578D01*
Y469676D01*
X763777Y438643D01*
Y420216D01*
X757008Y413447D01*
X749647D01*
X740384Y404184D01*
Y389986D01*
X731511Y381113D01*
G01X815500Y824000D02*
X815540Y823960D01*
Y761210D01*
X815154Y760824D01*
X815227Y753859D01*
X816164Y752922D01*
Y734940D01*
X817397Y733707D01*
Y728236D01*
X816100Y726939D01*
Y537220D01*
X801459Y522579D01*
Y517337D01*
X796446Y512324D01*
X796271Y512094D01*
X796054Y511932D01*
X751922Y467800D01*
X733863D01*
X733430Y467367D01*
G01X723177Y728219D02*
Y774481D01*
X727228Y778532D01*
Y790101D01*
X723257Y794072D01*
Y842410D01*
X734975Y870699D01*
Y889071D01*
X736452Y890548D01*
G01X731201Y1211712D02*
X729661Y1210172D01*
Y1206921D01*
X730344Y1206238D01*
X739748D01*
X740617Y1207107D01*
Y1208666D01*
X741951Y1210000D01*
X744100D01*
X746200Y1207900D01*
Y1194000D01*
X747000Y1193200D01*
X748200D01*
X750000Y1191400D01*
Y1184799D01*
X751550Y1183249D01*
Y1180749D01*
X752372Y1179927D01*
X784428D01*
X784701Y1180200D01*
X801803D01*
X804703Y1183100D01*
X816093D01*
X818879Y1185886D01*
Y1187310D01*
G01X792382Y1191664D02*
X791177Y1192869D01*
X789213D01*
X787481Y1194601D01*
X771341D01*
X768602Y1197340D01*
Y1226300D01*
X768102Y1226800D01*
X735600D01*
X735100Y1226300D01*
Y1220180D01*
X732548Y1217628D01*
X729637D01*
X727461Y1215452D01*
G01X927193Y1361547D02*
X894877Y1393863D01*
Y1393901D01*
X868776Y1420002D01*
X850404D01*
X827812Y1442594D01*
X825118D01*
X823967Y1443745D01*
X798882D01*
X796805Y1445822D01*
X785268D01*
X778975Y1452115D01*
X776501D01*
X773068Y1455548D01*
X764324D01*
X758943Y1450167D01*
X750538D01*
X746634Y1454071D01*
Y1466797D01*
X734078Y1479353D01*
Y1585578D01*
X765417Y1616917D01*
X771383D01*
G01X899699Y1283872D02*
Y1298600D01*
X885437Y1312862D01*
Y1365287D01*
X860024Y1390700D01*
X799900D01*
X798100Y1392500D01*
Y1396942D01*
X785599Y1409443D01*
Y1411979D01*
X779475Y1418103D01*
X777898D01*
X755272Y1440729D01*
X753946Y1441615D01*
X744968Y1450593D01*
Y1466467D01*
X732668Y1478767D01*
Y1586768D01*
X741767Y1595867D01*
Y1618452D01*
X735054Y1625165D01*
X729600D01*
G01X763653Y224536D02*
Y252913D01*
X760746Y255820D01*
X749988D01*
X747368Y258440D01*
X744714D01*
X742577Y256303D01*
G01X818307Y724144D02*
X817510Y723347D01*
Y536634D01*
X803800Y522924D01*
Y514278D01*
X793400Y503878D01*
Y472086D01*
X761367Y440053D01*
Y420253D01*
X756547Y415433D01*
X744495D01*
X734661Y405599D01*
Y393633D01*
G01X738681Y1200491D02*
X737047Y1198857D01*
Y1173496D01*
X737916Y1172627D01*
X750845D01*
X751590Y1171882D01*
Y1169942D01*
X752846Y1168686D01*
X784626D01*
X789005Y1173065D01*
X792277D01*
G01X742421Y1204232D02*
Y1203231D01*
X740430Y1201240D01*
Y1177065D01*
X741299Y1176196D01*
X751075D01*
X751820Y1175451D01*
Y1173528D01*
X753062Y1172286D01*
X784331D01*
X785075Y1173030D01*
Y1174925D01*
X786550Y1176400D01*
X793578D01*
X794521Y1175457D01*
X798502D01*
X799020Y1175975D01*
G01X742421Y1211712D02*
X742613D01*
X742901Y1212000D01*
X749200D01*
X749700Y1211500D01*
Y1194200D01*
X751800Y1192100D01*
Y1188259D01*
X756601Y1183458D01*
X784470D01*
X785917Y1182011D01*
X786965D01*
X787524Y1182570D01*
Y1185141D01*
X788083Y1185700D01*
X788875D01*
X789434Y1185141D01*
Y1182570D01*
X789993Y1182011D01*
X800253D01*
X803447Y1185205D01*
X814170D01*
G01X738681Y1211712D02*
Y1212744D01*
X740555Y1214618D01*
Y1218600D01*
X741055Y1219100D01*
X764600D01*
X765100Y1218600D01*
Y1193239D01*
X767308Y1191031D01*
X787439D01*
X789321Y1189149D01*
X795538D01*
X796654Y1190265D01*
X799513D01*
X800391Y1189387D01*
X802067D01*
X803495Y1190815D01*
Y1192149D01*
X804458Y1193112D01*
G01X749439Y1458777D02*
Y1465988D01*
X735488Y1479939D01*
Y1584688D01*
X747777Y1596977D01*
X774581D01*
X778042Y1600438D01*
X784046D01*
G01X836704Y1448849D02*
X825480D01*
X821792Y1445161D01*
X800356D01*
X798127Y1447390D01*
X793765D01*
X791342Y1449813D01*
X786402D01*
X781296Y1454919D01*
Y1457325D01*
X777144Y1461477D01*
X755945D01*
X736898Y1480524D01*
Y1550661D01*
X759802Y1573565D01*
Y1590864D01*
G01X797318Y1471242D02*
X788897D01*
X781253Y1463598D01*
X755820D01*
X738500Y1480918D01*
Y1550267D01*
X763542Y1575309D01*
Y1590186D01*
G01X804919Y1489247D02*
X804907D01*
X780850Y1465190D01*
X756223D01*
X740162Y1481251D01*
Y1519962D01*
X742435Y1522235D01*
Y1550212D01*
X773615Y1581392D01*
X782858D01*
X789705Y1588239D01*
Y1604850D01*
X785573Y1608982D01*
X777059D01*
G01X740530Y1524113D02*
Y1550302D01*
X773781Y1583553D01*
X781124D01*
G01X790280Y287421D02*
Y269569D01*
X808106Y251743D01*
Y178178D01*
X759917Y129989D01*
Y115782D01*
X761500Y114199D01*
Y110901D01*
X756900Y106301D01*
Y87222D01*
X760322Y83800D01*
X766733D01*
X768979Y86046D01*
G01X786461Y293028D02*
X789351D01*
X793150Y289229D01*
Y269259D01*
X809916Y252493D01*
Y177426D01*
X764892Y132402D01*
X764891D01*
X764200Y131711D01*
Y110800D01*
X759121Y105721D01*
Y87940D01*
X761330Y85731D01*
X765425D01*
G01X761118Y103621D02*
X766172Y108675D01*
Y131122D01*
X811726Y176676D01*
Y308344D01*
X809466Y310604D01*
G01X798075Y244297D02*
X801457D01*
X803076Y242678D01*
Y180266D01*
X764057Y141247D01*
X753035D01*
G01X765267Y157370D02*
X778184D01*
X801666Y180852D01*
Y213752D01*
X786772Y228646D01*
G01X765713Y1437365D02*
Y1432848D01*
X778648Y1419913D01*
X780225D01*
X787409Y1412729D01*
Y1410194D01*
X805093Y1392510D01*
X860774D01*
X889297Y1363987D01*
Y1316945D01*
X887342Y1314990D01*
G01X1092769Y936975D02*
X1088954Y940790D01*
Y1050204D01*
X1075604Y1063554D01*
X1065968D01*
X1035626Y1093896D01*
X1019304D01*
X1012300Y1100900D01*
Y1174073D01*
X1003583Y1195118D01*
X994976Y1203725D01*
X967600Y1269822D01*
X920430Y1316992D01*
Y1361016D01*
X866074Y1415372D01*
X817960D01*
X808389Y1424943D01*
Y1427811D01*
X805175Y1431025D01*
Y1433219D01*
X805110Y1433284D01*
Y1433809D01*
X802219Y1436700D01*
X795980D01*
X794534Y1435254D01*
X792954D01*
X790681Y1437527D01*
X775959D01*
X769962Y1443524D01*
X755035D01*
G01X760398Y1440276D02*
X770440D01*
X771796Y1438920D01*
Y1433792D01*
X776126Y1429462D01*
X790467D01*
X792669Y1427260D01*
X794433D01*
X801100Y1424500D01*
X815658Y1409942D01*
X863824D01*
X908700Y1365066D01*
Y1316300D01*
G01X823890Y703415D02*
Y536491D01*
X807700Y520301D01*
Y511501D01*
X796620Y500421D01*
Y420520D01*
X783059Y406959D01*
Y340434D01*
X775209Y332584D01*
X772162D01*
G01X891107Y1314305D02*
Y1364738D01*
X861525Y1394320D01*
X805843D01*
X789219Y1410944D01*
Y1413881D01*
X781377Y1421723D01*
X779398D01*
X768910Y1432211D01*
Y1437741D01*
G01X988784Y1361974D02*
X987770D01*
X983546Y1357750D01*
X926256D01*
X866824Y1417182D01*
X818710D01*
X810199Y1425693D01*
Y1428871D01*
X807900Y1431170D01*
Y1434292D01*
X803682Y1438510D01*
X795088D01*
X794104Y1439494D01*
X783232D01*
X778509Y1444217D01*
X776277D01*
X774623Y1445871D01*
Y1447495D01*
X768812Y1453306D01*
G01X784678Y125107D02*
Y116223D01*
X795011Y105890D01*
Y95111D01*
G01X793292Y143762D02*
X786864Y137334D01*
Y116836D01*
X797139Y106561D01*
X799380D01*
G01X793292Y143762D02*
X793331Y143801D01*
Y156285D01*
X813136Y176090D01*
Y303780D01*
X825971Y316615D01*
Y345101D01*
G01X823670Y710542D02*
X826000Y708212D01*
Y535700D01*
X809713Y519413D01*
Y510414D01*
X798430Y499131D01*
Y418573D01*
X785758Y405901D01*
Y366637D01*
X795445Y356950D01*
G01X795296Y1416995D02*
X798800Y1413491D01*
Y1406483D01*
X807343Y1397940D01*
X863026D01*
X896842Y1364124D01*
Y1309537D01*
X906506Y1299873D01*
Y1299188D01*
G01X792848Y1414718D02*
X795012D01*
X796411Y1413319D01*
Y1406312D01*
X806593Y1396130D01*
X862276D01*
X895032Y1363374D01*
Y1307704D01*
X902908Y1299828D01*
G01X910788Y1299456D02*
X909483D01*
X898652Y1310287D01*
Y1364874D01*
X860824Y1402702D01*
X812655D01*
X797009Y1418348D01*
X795296Y1419058D01*
X786838D01*
X783469Y1422427D01*
Y1424655D01*
G01X786787Y1433800D02*
X788587Y1432000D01*
X793841D01*
X796455Y1434614D01*
X801100D01*
X801600Y1434114D01*
Y1431138D01*
X803810Y1428928D01*
Y1428927D01*
X804418Y1428319D01*
Y1426354D01*
X817210Y1413562D01*
X865324D01*
X918620Y1360266D01*
Y1316242D01*
X966062Y1268800D01*
X993542Y1202457D01*
X1002148Y1193851D01*
X1010329Y1174099D01*
Y1099240D01*
X1017644Y1091925D01*
X1035037D01*
X1065218Y1061744D01*
X1074853D01*
X1087144Y1049453D01*
Y979840D01*
X1078920Y971616D01*
Y856700D01*
G01X793459Y1429165D02*
X801011D01*
X801999Y1428177D01*
X802000D01*
X802608Y1427569D01*
Y1425604D01*
X816460Y1411752D01*
X864574D01*
X916810Y1359516D01*
Y1315492D01*
X964524Y1267778D01*
X992245Y1200856D01*
X1000851Y1192250D01*
X1008519Y1173737D01*
Y1098490D01*
X1016894Y1090115D01*
X1034203D01*
X1064384Y1059934D01*
X1074102D01*
X1085334Y1048702D01*
Y980590D01*
X1069685Y964941D01*
Y933391D01*
G01X911117Y1314130D02*
X908175D01*
X906700Y1315605D01*
Y1364506D01*
X863074Y1408132D01*
X814908D01*
X800089Y1422951D01*
X794182Y1425400D01*
X791765D01*
X789647Y1427518D01*
G01X902875Y1309301D02*
X900462Y1311714D01*
Y1365624D01*
X861574Y1404512D01*
X813406D01*
X798039Y1419881D01*
X794615Y1421300D01*
X789392D01*
X788648Y1422044D01*
G01X905740Y1309264D02*
X902272Y1312732D01*
Y1366374D01*
X862324Y1406322D01*
X814158D01*
X799064Y1421416D01*
X794277Y1423400D01*
X790540D01*
X787947Y1425993D01*
X785820D01*
G01X853379Y76587D02*
Y84922D01*
X849591Y88710D01*
X812351D01*
X810411Y90650D01*
G01X810161Y95236D02*
X815582D01*
X818352Y92466D01*
X825229D01*
X829063Y96300D01*
X846662D01*
X847837Y97475D01*
G01X812104Y1426483D02*
X819995Y1418592D01*
X867409D01*
X926841Y1359160D01*
X972919D01*
X978814Y1365055D01*
X997654D01*
X1001200Y1368601D01*
Y1370800D01*
X998600Y1373400D01*
G01X853379Y72615D02*
X855618Y74854D01*
Y85244D01*
X850247Y90615D01*
X815723D01*
G01X820094Y95236D02*
X823009Y98151D01*
X831037D01*
X838986Y106100D01*
X844986D01*
X846977Y108091D01*
X858415D01*
X861200Y110876D01*
Y114709D01*
X858270Y117639D01*
Y142250D01*
X878870Y162850D01*
Y247590D01*
X875000Y251460D01*
Y288199D01*
X878527Y291726D01*
Y294512D01*
X877413Y295626D01*
X874574D01*
X867832Y302368D01*
Y345077D01*
X869111Y346356D01*
Y355304D01*
X849800Y374615D01*
Y394797D01*
X841793Y414128D01*
Y420999D01*
X873557Y452763D01*
Y513142D01*
X837620Y549079D01*
Y633892D01*
X866228Y662500D01*
X874225D01*
X878881Y667156D01*
G01X820044Y99961D02*
X830286D01*
X838325Y108000D01*
X844326D01*
X846227Y109901D01*
X857009D01*
X859191Y112083D01*
G01X822160Y258880D02*
X835820D01*
X840302Y254398D01*
X864045D01*
X865527Y252916D01*
Y228282D01*
X863627Y226382D01*
Y216982D01*
X871745Y208864D01*
G01X858169Y495032D02*
X857200Y496001D01*
Y519850D01*
X831100Y545954D01*
Y667401D01*
X836287Y672588D01*
Y696406D01*
X834173Y698520D01*
Y711931D01*
X835987Y713745D01*
G01X824387Y726246D02*
Y719697D01*
X826200Y717884D01*
Y710008D01*
X827700Y708508D01*
Y694636D01*
X832400Y689936D01*
Y672799D01*
X828000Y668399D01*
Y545062D01*
X852859Y520203D01*
Y471509D01*
X850732Y469382D01*
G01X824804Y898395D02*
X826569D01*
X828702Y896262D01*
Y878225D01*
X830056Y876871D01*
Y871303D01*
X833559Y867800D01*
Y860060D01*
X827000Y853501D01*
Y849809D01*
X822485Y845294D01*
Y806707D01*
X827414Y801778D01*
Y790990D01*
X822484Y786060D01*
Y754645D01*
X824056Y753073D01*
Y751493D01*
X817574Y745011D01*
Y735525D01*
X818807Y734292D01*
Y732598D01*
X822505Y728900D01*
X824428D01*
X828544Y724784D01*
Y718044D01*
X827700Y717200D01*
Y712001D01*
X831867Y707834D01*
Y695197D01*
X834100Y692961D01*
Y672400D01*
X829600Y667900D01*
Y545458D01*
X854348Y520708D01*
Y472399D01*
X856787Y469960D01*
Y448294D01*
X835753Y427260D01*
Y412919D01*
X842240Y397255D01*
Y324854D01*
G01X845850Y710969D02*
X843879Y712940D01*
Y719009D01*
X834189Y728699D01*
Y732006D01*
X833074Y733121D01*
X831423D01*
X827169Y737375D01*
Y740126D01*
X828603Y741560D01*
X829930Y742110D01*
X831305D01*
X835800Y746605D01*
Y748106D01*
X836300Y748606D01*
X842303D01*
X853202Y759505D01*
Y786950D01*
X853282Y787030D01*
Y789887D01*
G01X866015Y224536D02*
X866668Y223883D01*
X867867D01*
X869889Y225905D01*
Y246233D01*
X868409Y247713D01*
Y254692D01*
X866325Y256776D01*
Y295974D01*
X857045Y305254D01*
Y349016D01*
X844105Y361956D01*
Y396440D01*
X837163Y413200D01*
Y424492D01*
X859100Y446429D01*
Y475047D01*
X863600Y479547D01*
Y515800D01*
X832700Y546700D01*
Y644837D01*
X848400Y660537D01*
Y676771D01*
X842469Y682702D01*
Y714524D01*
X833764Y723229D01*
Y726949D01*
X831402Y729311D01*
X831401D01*
X830379Y730333D01*
Y731960D01*
X824500Y737839D01*
Y739990D01*
X826885Y742375D01*
X831478Y744278D01*
X833400Y746200D01*
Y754400D01*
X848500Y769500D01*
Y773000D01*
X846319Y775181D01*
Y824561D01*
X864630Y842872D01*
Y852185D01*
X869049Y856604D01*
Y863934D01*
X866549Y866434D01*
Y881235D01*
X866550Y881236D01*
Y889349D01*
X867733Y890532D01*
Y927677D01*
X875190Y935134D01*
Y937726D01*
X873166Y939750D01*
Y942502D01*
X875520Y944856D01*
Y968535D01*
X874066Y969989D01*
Y977928D01*
G01X838152Y700215D02*
Y715149D01*
X831154Y722147D01*
Y725866D01*
X827769Y729251D01*
Y730878D01*
X821890Y736757D01*
Y741072D01*
X825427Y744609D01*
X827535Y745483D01*
X828389Y746337D01*
Y747571D01*
X829918Y749100D01*
Y754617D01*
X833270Y757969D01*
Y823178D01*
X827635Y828813D01*
Y846725D01*
X831583Y850673D01*
Y853454D01*
G01X857632Y789385D02*
X854612Y786365D01*
Y758920D01*
X839992Y744300D01*
X835490D01*
X831845Y740655D01*
X830103D01*
X829404Y740365D01*
X828579Y739540D01*
Y737960D01*
X832008Y734531D01*
X835099D01*
X848979Y720651D01*
Y711284D01*
X845784Y708089D01*
G01X895829Y800660D02*
X893600Y798431D01*
Y788501D01*
X895500Y786601D01*
Y783001D01*
X889102Y776603D01*
X872500D01*
X869198Y773301D01*
Y771997D01*
X861400Y764199D01*
Y749164D01*
X862700Y747864D01*
Y744700D01*
X860176Y742176D01*
X853300D01*
X852776Y742700D01*
X836399D01*
X832449Y738750D01*
X830484D01*
G01X824414Y939655D02*
Y935013D01*
X820500Y931099D01*
Y891479D01*
X821900Y890079D01*
Y875977D01*
X828284Y869593D01*
Y858284D01*
X824821Y854821D01*
Y850739D01*
X822608Y848526D01*
G01X836909Y916618D02*
X836119D01*
X834900Y915399D01*
Y899837D01*
X830512Y895449D01*
Y879043D01*
X835979Y873576D01*
X838133D01*
X839566Y872143D01*
Y865874D01*
X837000Y863308D01*
Y859160D01*
X842200Y853960D01*
Y825701D01*
X837000Y820501D01*
Y773256D01*
X840735Y769521D01*
X842661D01*
G01X823900Y882083D02*
Y890640D01*
X822353Y892187D01*
Y901015D01*
X832962Y911624D01*
Y917526D01*
X836191Y920755D01*
X836903Y922474D01*
Y923800D01*
X841018Y933733D01*
X844568Y937283D01*
X847526Y944427D01*
X850141Y947042D01*
X851925Y951350D01*
G01X830356Y1116251D02*
Y1113415D01*
X835571Y1108200D01*
X842288D01*
X855220Y1095268D01*
Y1049262D01*
X843301Y1020487D01*
Y1015336D01*
X845963Y1012674D01*
Y1008111D01*
X841247Y1003395D01*
Y954064D01*
X838339Y951156D01*
Y948207D01*
X834947Y944815D01*
X824833D01*
X821871Y941853D01*
Y936770D01*
X818515Y933414D01*
Y916056D01*
X817884Y915425D01*
G01X825336Y916774D02*
Y927451D01*
X830236Y932351D01*
Y936881D01*
X831549Y938194D01*
Y942006D01*
X832537Y942994D01*
X835702D01*
X840160Y947452D01*
Y950401D01*
X843068Y953309D01*
Y1002640D01*
X847773Y1007345D01*
Y1013424D01*
X845111Y1016086D01*
Y1020126D01*
X857030Y1048901D01*
Y1096019D01*
X842649Y1110400D01*
X836207D01*
X832612Y1113995D01*
Y1117092D01*
X831282Y1118422D01*
X828585D01*
X827856Y1117693D01*
Y1116251D01*
G01X829848Y914211D02*
X829296D01*
X828498Y915009D01*
Y926335D01*
X841039Y938876D01*
X845200Y948921D01*
Y1001437D01*
X850686Y1006923D01*
G01X853449Y1007048D02*
Y1005548D01*
X847010Y999109D01*
Y948470D01*
X842637Y937913D01*
X831057Y926333D01*
Y916745D01*
G01X866015Y224536D02*
Y226760D01*
X867257Y228002D01*
Y253746D01*
X864768Y256235D01*
X851935D01*
X849730Y258440D01*
X847076D01*
X844939Y256303D01*
G01X871745Y208864D02*
X873918Y211037D01*
Y218274D01*
X872880Y219312D01*
X870650D01*
X869443Y220519D01*
Y223368D01*
X872164Y226089D01*
Y247055D01*
X869998Y249221D01*
Y255501D01*
X867735Y257764D01*
Y297366D01*
X858455Y306646D01*
Y359372D01*
X845800Y372027D01*
Y396034D01*
X838573Y413481D01*
Y423272D01*
X865300Y449999D01*
Y516095D01*
X834400Y546995D01*
Y635228D01*
X866031Y666859D01*
X872862D01*
G01X871826Y186778D02*
X875419Y190371D01*
Y246311D01*
X871408Y250322D01*
Y256592D01*
X870039Y257961D01*
Y297431D01*
X859865Y307605D01*
Y361035D01*
X847800Y373100D01*
Y394893D01*
X839983Y413764D01*
Y422021D01*
X866800Y448838D01*
Y516700D01*
X835810Y547690D01*
Y634643D01*
X865767Y664600D01*
X873544D01*
X876265Y667321D01*
Y668189D01*
X879800Y671724D01*
Y697489D01*
X886967Y704656D01*
X893241D01*
G01X914202Y797460D02*
Y795003D01*
X890299Y771100D01*
X881799D01*
X873457Y762758D01*
Y756396D01*
X868610Y751549D01*
Y743811D01*
X858999Y734200D01*
X851034D01*
X846484Y738750D01*
G01X902641Y800748D02*
Y785740D01*
X890001Y773100D01*
X879399D01*
X872900Y766601D01*
X870700D01*
X866520Y762421D01*
Y756180D01*
X867200Y755500D01*
Y744900D01*
X858500Y736200D01*
X853166D01*
X848566Y740800D01*
X838762D01*
X836713Y738751D01*
G01X836909Y914018D02*
Y899113D01*
X833149Y895353D01*
Y888935D01*
X836601Y885483D01*
X838429D01*
X843289Y880623D01*
Y866928D01*
X841500Y865139D01*
Y857772D01*
X844181Y855091D01*
Y772907D01*
X845009Y772079D01*
X846000D01*
G01X837434Y851459D02*
X836212D01*
X832779Y848026D01*
Y837893D01*
X835553Y835119D01*
G01X859603Y863570D02*
X858831Y862798D01*
X856308D01*
X855015Y861505D01*
X846414D01*
X845820Y862099D01*
Y863413D01*
G01X843574Y859423D02*
X845521Y857476D01*
X854874D01*
X856857Y859459D01*
X859461D01*
G01X859463Y866125D02*
X858840Y865502D01*
X846291D01*
X845820Y865973D01*
Y867413D01*
G01X850800Y883500D02*
X848805Y885495D01*
X845264D01*
X839813Y890946D01*
Y901358D01*
X845220Y906765D01*
Y931512D01*
X849915Y942842D01*
X856259Y949186D01*
Y1008866D01*
X851558Y1013567D01*
Y1016801D01*
X849049Y1019310D01*
X848045D01*
G01X836704Y1448849D02*
X838619Y1446934D01*
X841990D01*
X842490Y1446434D01*
Y1429911D01*
X850989Y1421412D01*
X870188D01*
X931030Y1360570D01*
X971598D01*
X977934Y1366906D01*
X985021D01*
X991776Y1373661D01*
X994139D01*
X998600Y1369200D01*
G01X871341Y86046D02*
X868995Y83700D01*
X862784D01*
X859500Y86984D01*
Y105999D01*
X863100Y109599D01*
Y115461D01*
X860080Y118481D01*
Y141500D01*
X880680Y162100D01*
Y248527D01*
X876900Y252307D01*
Y287538D01*
X880337Y290975D01*
Y295263D01*
X877900Y297700D01*
X875592D01*
X873262Y300030D01*
G01X867787Y85731D02*
X863692D01*
X861483Y87940D01*
Y105183D01*
X865911Y109611D01*
Y118052D01*
X861890Y122073D01*
Y140750D01*
X882490Y161350D01*
Y250050D01*
X878830Y253710D01*
Y286907D01*
X882147Y290224D01*
Y296014D01*
X878651Y299510D01*
X876490D01*
X873356Y302644D01*
X872050D01*
G01X859191Y112083D02*
Y113769D01*
X856460Y116500D01*
Y143000D01*
X877060Y163600D01*
Y246839D01*
X873162Y250737D01*
Y257973D01*
X872300Y258835D01*
Y289399D01*
X876622Y293721D01*
G01X879112Y302369D02*
X883957Y297524D01*
Y289473D01*
X880800Y286316D01*
Y254300D01*
X884300Y250800D01*
Y160600D01*
X863700Y140000D01*
Y122824D01*
X867721Y118803D01*
Y107862D01*
X863480Y103621D01*
G01X853989Y630453D02*
X853347D01*
X851900Y631900D01*
Y637600D01*
X858000Y643700D01*
X862499D01*
X865799Y647000D01*
X997400D01*
X1002600Y641800D01*
Y633278D01*
X1006919Y628959D01*
Y457579D01*
X932617Y383277D01*
X907201D01*
X905080Y381156D01*
X894717D01*
X886472Y372911D01*
Y359712D01*
X888812Y357372D01*
G01X883552Y357276D02*
Y373934D01*
X891747Y382129D01*
Y383864D01*
X892970Y385087D01*
X931867D01*
X1004666Y457886D01*
Y586790D01*
X1004136Y587320D01*
X1002568D01*
X1002038Y587850D01*
Y589320D01*
X1002568Y589850D01*
X1004136D01*
X1004666Y590380D01*
Y591850D01*
X1004136Y592380D01*
X1002568D01*
X1002038Y592910D01*
Y594380D01*
X1002568Y594910D01*
X1004136D01*
X1004666Y595440D01*
Y617460D01*
X999600Y622526D01*
Y640801D01*
X995887Y644514D01*
X866624D01*
X863010Y640900D01*
X858993D01*
X853989Y635896D01*
Y632953D01*
G01X859441Y678015D02*
X858220Y679236D01*
Y694192D01*
X860548Y696520D01*
Y720108D01*
X857986Y722670D01*
G01X855646Y692710D02*
Y723819D01*
X871000Y739173D01*
Y745589D01*
X874142Y748731D01*
Y748914D01*
G01X883916Y808965D02*
X881200Y806249D01*
Y798499D01*
X862829Y780128D01*
Y775029D01*
X856500Y768700D01*
Y747216D01*
X859199Y744517D01*
G01X899916Y808965D02*
Y805433D01*
X897938Y803455D01*
Y799038D01*
X895400Y796500D01*
Y790704D01*
X897400Y788704D01*
Y782700D01*
X889500Y774800D01*
X877000D01*
X871300Y769100D01*
X868800D01*
X865110Y765410D01*
Y754589D01*
X865500Y754199D01*
Y745399D01*
X858734Y738633D01*
X854484D01*
G01X865973Y978187D02*
Y977927D01*
X871500Y972400D01*
Y970560D01*
X874110Y967950D01*
Y945673D01*
X865191Y936754D01*
Y934662D01*
X866323Y933530D01*
Y891483D01*
X865140Y890300D01*
Y881821D01*
X865139Y881820D01*
Y865849D01*
X867639Y863349D01*
Y857189D01*
X862880Y852430D01*
Y844086D01*
X858253Y839459D01*
X851184D01*
G01X863334Y1009393D02*
Y976166D01*
X872300Y967200D01*
Y948353D01*
X863381Y939434D01*
Y921960D01*
X862221Y920800D01*
Y912736D01*
X863110Y911847D01*
Y911846D01*
X864513Y910443D01*
Y892500D01*
X863330Y891317D01*
Y882571D01*
X863329Y882570D01*
Y865099D01*
X865829Y862599D01*
Y857939D01*
X861070Y853180D01*
Y846023D01*
X856601Y841554D01*
X850479D01*
X848384Y839459D01*
G01X848739Y847459D02*
Y847814D01*
X850293Y849368D01*
X854698D01*
X864019Y858689D01*
Y861849D01*
X861519Y864349D01*
Y883320D01*
X861520Y883321D01*
Y892517D01*
X862703Y893700D01*
Y909693D01*
X861300Y911096D01*
Y911097D01*
X860411Y911986D01*
Y922712D01*
X861571Y923872D01*
Y940746D01*
X870209Y949384D01*
G01X848384Y871459D02*
X850479Y873554D01*
X852954D01*
X856658Y877258D01*
X857709Y882581D01*
Y891157D01*
X857700Y891166D01*
Y891257D01*
X860893Y894450D01*
Y908943D01*
X858601Y911235D01*
Y934505D01*
G01X853030Y934690D02*
X854600Y933120D01*
Y914600D01*
X854400Y914400D01*
Y901500D01*
X853600Y900700D01*
Y895957D01*
X855899Y890407D01*
Y882782D01*
X855170Y879170D01*
X853364Y877364D01*
X850393D01*
X849901Y876872D01*
X849797D01*
X848384Y875459D01*
G01X848070Y1022190D02*
X851294D01*
X854400Y1019084D01*
Y1016954D01*
X859069Y1012285D01*
Y948022D01*
X852299Y941252D01*
X850500Y936911D01*
Y929449D01*
X851505Y928444D01*
Y903204D01*
X850700Y902399D01*
Y895612D01*
X853089Y889847D01*
Y883454D01*
X852179Y880454D01*
X851184Y879459D01*
G01X875473Y742056D02*
Y720127D01*
X887349Y708251D01*
X893150D01*
X895500Y705901D01*
Y672957D01*
X919557Y648900D01*
X999000D01*
X1008729Y639171D01*
Y456829D01*
X933367Y381467D01*
X907951D01*
X905381Y378897D01*
X895131D01*
X890982Y374748D01*
Y280707D01*
X890289Y280014D01*
Y271532D01*
X892484Y269337D01*
Y260860D01*
G01X895140Y265236D02*
Y269660D01*
X892099Y272701D01*
Y279264D01*
X892827Y279992D01*
Y373966D01*
X895539Y376678D01*
X905722D01*
X908701Y379657D01*
X934117D01*
X1010539Y456079D01*
Y641001D01*
X1000740Y650800D01*
X922100D01*
X897900Y675000D01*
Y706501D01*
X893501Y710900D01*
X888100D01*
X878670Y720330D01*
Y742841D01*
G01X978214Y821224D02*
Y821222D01*
X979964Y819472D01*
X981331D01*
X981757Y819046D01*
Y813956D01*
X980201Y812400D01*
X976537D01*
X963175Y825762D01*
Y829626D01*
X961101Y831700D01*
X952169D01*
X949668Y829199D01*
Y819767D01*
X942105Y812204D01*
X935204D01*
X926002Y803002D01*
Y797103D01*
X923684Y794785D01*
X916685D01*
X890791Y768891D01*
Y757300D01*
X889991Y756500D01*
X882000D01*
X881300Y757200D01*
X878300D01*
X876533Y755433D01*
Y751305D01*
X874142Y748914D01*
G01X872183Y993980D02*
X876900Y989263D01*
Y975099D01*
X875600Y973799D01*
Y970450D01*
X876930Y969120D01*
Y944270D01*
X874576Y941916D01*
Y940336D01*
X876600Y938312D01*
Y934549D01*
X869143Y927092D01*
Y889743D01*
X868000Y888600D01*
Y888488D01*
X867960Y888448D01*
Y880651D01*
X867959Y880650D01*
Y867019D01*
X870459Y864519D01*
Y856019D01*
X866040Y851600D01*
Y833354D01*
X875913Y823481D01*
Y823424D01*
X877028Y822309D01*
X877085D01*
X878632Y820762D01*
X884119D01*
X895916Y808965D01*
G01X875391Y993796D02*
X874877Y993282D01*
X878310Y989848D01*
Y974514D01*
X877010Y973214D01*
Y971035D01*
X878386Y969659D01*
Y934340D01*
X874533Y930487D01*
Y898822D01*
X871180Y895469D01*
Y889673D01*
X869370Y887863D01*
Y880066D01*
X869369Y880065D01*
Y867604D01*
X871869Y865104D01*
Y855434D01*
X867450Y851015D01*
Y844344D01*
X877555Y834239D01*
X879765D01*
X881370Y835844D01*
G01X888400Y994579D02*
X885545Y991724D01*
Y922655D01*
X886700Y921500D01*
Y903062D01*
X875900Y892262D01*
Y888308D01*
X873600Y886008D01*
Y869358D01*
X876099Y866859D01*
Y844201D01*
X877200Y843100D01*
X881682D01*
X882300Y843718D01*
X883100D01*
G01X892393D02*
X893968Y845293D01*
G01X892768Y840568D02*
X892200Y840000D01*
X876060D01*
X871300Y844760D01*
Y848981D01*
X874689Y852370D01*
Y866274D01*
X872190Y868773D01*
Y886593D01*
X874000Y888403D01*
Y892888D01*
X882723Y901611D01*
Y933432D01*
X882763Y933472D01*
G01X878976Y994020D02*
X879796Y993200D01*
Y922581D01*
X878700Y921485D01*
Y899584D01*
X872590Y893474D01*
Y889088D01*
X870780Y887278D01*
Y868188D01*
X873279Y865689D01*
Y854849D01*
X868860Y850430D01*
Y845204D01*
X878220Y835844D01*
G01Y851592D02*
X877730Y852082D01*
Y867788D01*
X875410Y870108D01*
Y885210D01*
X877900Y887700D01*
Y891645D01*
X891043Y904788D01*
Y904789D01*
X891519Y905265D01*
Y912281D01*
X890600Y913200D01*
Y927000D01*
X889400Y928200D01*
Y989070D01*
X894660Y994330D01*
G01X897825Y994413D02*
X894648Y991236D01*
Y904749D01*
X879795Y889896D01*
Y886995D01*
X878600Y885800D01*
Y881300D01*
X879765Y880135D01*
Y866673D01*
X879795Y866643D01*
Y859505D01*
X880800Y858500D01*
Y855311D01*
X884519Y851592D01*
G01X891383Y243203D02*
Y244969D01*
X891679Y245265D01*
Y248613D01*
X889999Y250293D01*
Y256904D01*
X888300Y258603D01*
Y262393D01*
X883091Y267602D01*
Y281676D01*
X886059Y284644D01*
G01X896034Y243307D02*
Y245073D01*
X896330Y245369D01*
Y246147D01*
X891512Y250965D01*
Y257853D01*
X890313Y259052D01*
Y268948D01*
X888479Y270782D01*
Y286939D01*
X885918Y289500D01*
G01X880736Y383125D02*
X887150Y389539D01*
X933584D01*
X959089Y415044D01*
Y432644D01*
X944200Y447533D01*
Y469500D01*
X939843Y473857D01*
X929090D01*
X924999Y477948D01*
G01X885931Y534093D02*
Y532205D01*
X946400Y471736D01*
Y447893D01*
X966694Y427599D01*
G01X895933Y609696D02*
X898908Y606721D01*
X909763D01*
X913998Y602486D01*
Y597103D01*
G01X978978Y817618D02*
X976681D01*
X974000Y820299D01*
Y825201D01*
X966613Y832588D01*
X963113D01*
X959001Y836700D01*
X957265D01*
X954851Y835700D01*
X952300D01*
X945000Y828400D01*
Y824824D01*
X934976Y814800D01*
X918279D01*
X917179Y815900D01*
X902509D01*
X897871Y811262D01*
Y806732D01*
X891916Y800777D01*
Y799605D01*
G01X884519Y854742D02*
X882438Y856823D01*
Y858456D01*
X884350Y860368D01*
X900501D01*
X903997Y863864D01*
Y895424D01*
X908920Y900347D01*
Y905630D01*
G01X909166Y994188D02*
X901894Y986916D01*
Y973662D01*
X898468Y970236D01*
Y898672D01*
X886150Y886354D01*
X884585D01*
G01X891343Y994378D02*
X887300Y990335D01*
Y925101D01*
X888628Y923773D01*
Y918042D01*
G01X903035Y141247D02*
X918040D01*
X952956Y176163D01*
Y225253D01*
X948741Y229468D01*
G01X899530Y530753D02*
X898220Y529443D01*
Y522879D01*
X948380Y472719D01*
Y449450D01*
X968462Y429368D01*
G01X908699Y709387D02*
X904882Y705570D01*
Y678446D01*
X913781Y669547D01*
X921653D01*
X938300Y652900D01*
X1001200D01*
X1012349Y641751D01*
Y455269D01*
X964197Y407117D01*
Y314899D01*
X958582Y309284D01*
X944339D01*
X939640Y304585D01*
X923732D01*
G01X963950Y734178D02*
X960140Y737988D01*
X936888D01*
X918575Y719675D01*
Y689883D01*
X912462Y683770D01*
G01X909265Y677795D02*
Y696805D01*
X916100Y703640D01*
Y720000D01*
X947950Y751850D01*
Y771749D01*
X927916Y791783D01*
Y800909D01*
G01X911280Y880680D02*
Y909301D01*
X909240Y911341D01*
X903960D01*
X902600Y912701D01*
Y935366D01*
X903720Y936486D01*
Y941675D01*
X901688Y943707D01*
Y965492D01*
X919739Y983543D01*
Y1108623D01*
X919795Y1108679D01*
Y1221677D01*
X919739Y1221733D01*
Y1300006D01*
X904890Y1314855D01*
Y1359242D01*
X904177Y1359955D01*
G01X916014Y879937D02*
X914900Y881051D01*
Y888130D01*
X913000Y890030D01*
Y911000D01*
X910700Y913300D01*
Y932900D01*
X905997Y937603D01*
Y946796D01*
X909811Y950610D01*
Y962400D01*
G01X921364Y951251D02*
X913581D01*
X908500Y946170D01*
Y939059D01*
X914723Y932836D01*
Y891555D01*
X917300Y888978D01*
Y881398D01*
X917598Y881100D01*
G01X909077Y1232724D02*
Y1230400D01*
X918385Y1221092D01*
Y1109264D01*
X914406Y1105285D01*
Y1003423D01*
X912690Y1001707D01*
Y994350D01*
G01X989513Y1097683D02*
X987620Y1095790D01*
X980240D01*
X978089Y1097941D01*
Y1205836D01*
X974454Y1209471D01*
Y1234340D01*
X961454Y1265727D01*
X913100Y1314081D01*
Y1335498D01*
X911135Y1337463D01*
Y1345560D01*
G01X915267Y157370D02*
X931687D01*
X951400Y177083D01*
Y199855D01*
X937438Y213817D01*
G01X923453Y569578D02*
X929166Y563865D01*
Y495735D01*
X952474Y472427D01*
Y449539D01*
X971826Y430187D01*
G01X923453Y569578D02*
X927900Y574025D01*
Y628498D01*
X922626Y633772D01*
G01X913998Y597103D02*
X916670D01*
X921217Y592556D01*
Y589216D01*
G01X933974Y719371D02*
X930293Y715690D01*
Y700294D01*
X923489Y693490D01*
Y672794D01*
X929690Y666593D01*
G01X965983Y763567D02*
Y731983D01*
X963900Y729900D01*
X956113D01*
X953700Y732313D01*
X944913D01*
X937170Y724570D01*
X931470D01*
X927000Y720100D01*
Y707604D01*
X921600Y702204D01*
Y671801D01*
X938927Y654474D01*
X1002825D01*
X1013759Y643540D01*
Y454684D01*
X965607Y406532D01*
Y166077D01*
X943292Y143762D01*
G01X928704Y680261D02*
X931800Y677165D01*
Y675625D01*
X932300Y675125D01*
X946072D01*
X954526Y666671D01*
G01X928612Y879937D02*
X931337D01*
X936200Y884800D01*
Y903457D01*
X937919Y905176D01*
X942294D01*
X949373Y912255D01*
Y923006D01*
X947212Y925167D01*
Y942187D01*
X943267Y946132D01*
Y955963D01*
X936505Y962725D01*
X935255D01*
G01X923289Y965780D02*
X932799Y956270D01*
Y942898D01*
X926723Y936822D01*
Y912421D01*
X924723Y910421D01*
Y894417D01*
X927027Y892113D01*
Y887700D01*
G01X928227Y951125D02*
X924054Y946952D01*
Y946622D01*
X922692Y945260D01*
Y913396D01*
X918901Y909605D01*
Y894759D01*
X920728Y892932D01*
Y887700D01*
G01X930300Y882018D02*
Y892814D01*
X933569Y896083D01*
Y903745D01*
X934946Y905122D01*
Y909228D01*
X938535Y912817D01*
Y954558D01*
X926796Y966297D01*
G01X959545Y918306D02*
X951587Y910348D01*
Y906387D01*
X937672Y892472D01*
Y876847D01*
X936312Y875487D01*
X930983D01*
X930240Y874744D01*
Y868799D01*
X928779Y867338D01*
X925462D01*
G01X921451Y903800D02*
Y894857D01*
X923878Y892430D01*
Y887700D01*
G01X914193Y945318D02*
Y936985D01*
X918533Y932645D01*
Y912117D01*
X916700Y910284D01*
Y894224D01*
X919163Y891761D01*
Y883086D01*
G01X928612Y886236D02*
Y892900D01*
X926372Y895140D01*
Y900412D01*
X930800Y904840D01*
G01X924956Y994321D02*
X926989Y996354D01*
X968053D01*
X978105Y1006406D01*
Y1028170D01*
X1007109Y1057174D01*
Y1173456D01*
X999655Y1191451D01*
X990850Y1200256D01*
X984958Y1214479D01*
X978169Y1221268D01*
G01X914033Y1345613D02*
Y1337304D01*
X915000Y1336337D01*
Y1314742D01*
X962989Y1266753D01*
X976264Y1234705D01*
Y1210222D01*
X979899Y1206587D01*
Y1115211D01*
X986645Y1108465D01*
G01X934678Y125107D02*
Y116450D01*
X945011Y106117D01*
Y95111D01*
G01X943292Y143762D02*
X936864Y137334D01*
Y116824D01*
X947127Y106561D01*
X949380D01*
G01X939992Y527726D02*
Y519664D01*
X950300Y509356D01*
Y504007D01*
X952100Y502207D01*
Y488801D01*
X958736Y482165D01*
G01X1003379Y76587D02*
Y84214D01*
X998883Y88710D01*
X962351D01*
X960411Y90650D01*
G01X997837Y97475D02*
X996284Y95922D01*
X981891D01*
X980497Y94942D01*
X977781D01*
X975305Y92466D01*
X968352D01*
X965582Y95236D01*
X960161D01*
G01X948741Y229468D02*
X954509Y235236D01*
Y289835D01*
X952790Y291554D01*
X949974D01*
G01X955850Y862902D02*
X958580Y865632D01*
Y880595D01*
X958765Y880780D01*
Y903097D01*
X961829Y906161D01*
Y921171D01*
X956500Y926500D01*
Y932899D01*
X954500Y934899D01*
Y977900D01*
X949671Y982729D01*
Y991564D01*
G01X1003379Y72615D02*
X1005618Y74854D01*
Y84535D01*
X999538Y90615D01*
X965723D01*
G01X1092554Y340318D02*
X1088558Y336322D01*
X1076858D01*
X1066074Y325538D01*
Y304414D01*
X1042376Y280716D01*
Y277970D01*
X1058778Y261568D01*
Y179476D01*
X1008050Y128748D01*
Y117573D01*
X1011307Y114316D01*
Y111373D01*
X1010112Y110178D01*
X997795D01*
X993419Y105802D01*
X988679D01*
X985205Y102328D01*
X982820Y99182D01*
X979363Y96752D01*
X971610D01*
X970094Y95236D01*
G01X1009191Y112083D02*
X997140D01*
X992669Y107612D01*
X987929D01*
X983684Y103367D01*
X981548Y100502D01*
X978790Y98562D01*
X971443D01*
X970044Y99961D01*
G01X1021745Y208864D02*
X1020043D01*
X1013627Y215280D01*
Y226382D01*
X1015527Y228282D01*
Y252916D01*
X1014335Y254108D01*
X988981D01*
X985170Y257919D01*
X973121D01*
X972160Y258880D01*
G01X975631Y343112D02*
X974512Y341993D01*
X971362D01*
X968348Y345007D01*
Y402369D01*
G01X971721Y407762D02*
Y404980D01*
X970487Y403746D01*
Y351756D01*
X975631Y346612D01*
G01X967562Y802982D02*
X968918D01*
X979213Y792687D01*
Y761306D01*
X992087Y748432D01*
Y668983D01*
X1015169Y645901D01*
Y453561D01*
X1009585Y447977D01*
Y437227D01*
X1060161Y386651D01*
X1062985D01*
X1095427Y354209D01*
Y309516D01*
X1091109Y305198D01*
X1079096D01*
X1065618Y291720D01*
Y163726D01*
X1045654Y143762D01*
G01X967842Y864801D02*
X967634Y864593D01*
Y845309D01*
X970040Y842903D01*
G01X967510Y868971D02*
Y868959D01*
X965413Y866862D01*
Y843230D01*
X969309Y839334D01*
G01X1060768Y1053457D02*
X1046057D01*
X1040130Y1047530D01*
X1000450D01*
X980215Y1027295D01*
Y1001074D01*
X980715Y1000574D01*
X983988D01*
X984518Y1000044D01*
Y997574D01*
X983988Y997044D01*
X979398D01*
X978868Y996514D01*
Y994044D01*
X979398Y993514D01*
X983988D01*
X984518Y992984D01*
Y990514D01*
X983988Y989984D01*
X979398D01*
X978868Y989454D01*
Y986984D01*
X979398Y986454D01*
X983988D01*
X984518Y985924D01*
Y983454D01*
X983988Y982924D01*
X978432D01*
X977902Y982394D01*
Y979924D01*
X978432Y979394D01*
X983988D01*
X984518Y978864D01*
Y976394D01*
X983988Y975864D01*
X979398D01*
X978868Y975334D01*
Y914918D01*
X973988Y910038D01*
G01X1090375Y899047D02*
X1096000Y904672D01*
Y939700D01*
X1090764Y944936D01*
Y1050955D01*
X1076355Y1065364D01*
X1066835D01*
X1036493Y1095706D01*
X1020294D01*
X1014110Y1101890D01*
Y1174805D01*
X1005282Y1196118D01*
X996413Y1204987D01*
X972219Y1263400D01*
Y1293571D01*
X986577Y1307929D01*
Y1356785D01*
X988784Y1358992D01*
Y1361974D01*
G01X1010499Y309062D02*
X1008089Y311472D01*
Y342495D01*
X1007608Y342976D01*
Y364690D01*
X995091Y377207D01*
Y405531D01*
X991392Y409230D01*
G01X982783Y909995D02*
X982859D01*
X985400Y907454D01*
Y896100D01*
X983500Y894200D01*
Y871571D01*
X979267Y861351D01*
Y845529D01*
X985370Y839426D01*
X990296D01*
X996215Y833507D01*
Y827498D01*
X993916Y825199D01*
Y814884D01*
X996300Y812500D01*
Y793725D01*
X1009208Y780817D01*
Y776004D01*
X1021016Y764196D01*
Y750193D01*
X1027478Y743731D01*
Y720331D01*
X1026916Y719769D01*
G01X1013319Y785929D02*
X1010725D01*
X1001739Y794915D01*
Y814181D01*
X1005300Y817742D01*
Y836823D01*
X995678Y846445D01*
Y851209D01*
X991388Y855499D01*
X984885D01*
X983269Y853883D01*
G01X988054Y888283D02*
X996310Y896539D01*
Y990014D01*
X993924Y992400D01*
Y1023084D01*
X1011040Y1040200D01*
X1056835D01*
X1057212Y1040356D01*
G01X990300Y897500D02*
X993700Y900900D01*
Y987523D01*
X991293Y989930D01*
Y1003700D01*
X984935Y1010058D01*
Y1025338D01*
X1002407Y1042810D01*
X1052610D01*
X1055662Y1045862D01*
X1062691D01*
X1067866Y1051037D01*
G01X989311Y920364D02*
Y935098D01*
X987711Y936698D01*
X985847D01*
X985317Y937228D01*
Y939698D01*
X985847Y940228D01*
X988116D01*
X988646Y940758D01*
Y943228D01*
X988116Y943758D01*
X985847D01*
X985317Y944288D01*
Y946758D01*
X985847Y947288D01*
X988116D01*
X988646Y947818D01*
Y950288D01*
X988116Y950818D01*
X985847D01*
X985317Y951348D01*
Y953818D01*
X985847Y954348D01*
X988116D01*
X988646Y954878D01*
Y957348D01*
X988116Y957878D01*
X985547D01*
X985017Y958408D01*
Y960878D01*
X985547Y961408D01*
X986900D01*
X987400Y961908D01*
Y1001999D01*
X982325Y1007074D01*
Y1026420D01*
X1001325Y1045420D01*
X1046520D01*
X1049572Y1048472D01*
X1061608D01*
X1064100Y1050964D01*
Y1054233D01*
X1064600Y1054733D01*
X1073129D01*
X1074232Y1055836D01*
G01X1007850Y1368835D02*
X988256Y1349241D01*
Y1323035D01*
X990501Y1320790D01*
Y1320756D01*
G01X1051796Y279965D02*
X1060588Y271173D01*
Y178726D01*
X1009860Y127998D01*
Y118323D01*
X1013117Y115066D01*
Y110623D01*
X1009673Y107179D01*
Y86811D01*
X1012721Y83763D01*
X1019058D01*
X1021341Y86046D01*
G01X1009191Y112083D02*
Y113683D01*
X1006240Y116634D01*
Y129498D01*
X1056968Y180226D01*
Y260818D01*
X1040566Y277220D01*
Y281466D01*
X1064264Y305164D01*
Y326288D01*
X1076232Y338256D01*
X1084056D01*
X1085615Y339815D01*
G01X1005397Y141247D02*
X1015994D01*
X1055318Y180571D01*
Y241420D01*
X1052441Y244297D01*
X1050437D01*
G01X1018014Y228631D02*
X1017257Y229388D01*
Y253746D01*
X1014768Y256235D01*
X1002194D01*
X999953Y258476D01*
X997112D01*
X994939Y256303D01*
G01X1002751Y757169D02*
X1001676Y756094D01*
Y678015D01*
G01X1076577Y1041332D02*
Y1039576D01*
X1066979Y1029978D01*
X1047664D01*
X1044622Y1026936D01*
Y1016191D01*
X1043622Y1015191D01*
X1042082D01*
X1041082Y1016191D01*
Y1025884D01*
X1040552Y1026414D01*
X1027596D01*
X1027059Y1026951D01*
X1007719D01*
X1005663Y1024895D01*
Y1022618D01*
X1002612Y1019567D01*
Y1017572D01*
X1005110Y1015074D01*
Y1012030D01*
X1003720Y1010640D01*
X1000771D01*
X998977Y1008846D01*
Y1004934D01*
X1002965Y1000946D01*
Y996034D01*
X1001744Y994813D01*
Y912932D01*
X1008574Y906102D01*
Y873122D01*
X1006841Y871389D01*
X1004713D01*
G01X998313Y888295D02*
X998420Y888402D01*
Y992164D01*
X996446Y994138D01*
Y1022621D01*
X1011376Y1037551D01*
X1064448D01*
X1065079Y1036920D01*
G01X1045364Y279895D02*
X1048140Y282671D01*
X1051894D01*
X1062398Y272167D01*
Y177976D01*
X1011670Y127248D01*
Y122424D01*
X1015912Y118182D01*
Y110858D01*
X1011483Y106429D01*
Y87940D01*
X1013692Y85731D01*
X1017787D01*
G01X1013480Y103621D02*
X1017722Y107863D01*
Y118932D01*
X1013480Y123174D01*
Y126498D01*
X1064208Y177226D01*
Y296090D01*
X1074933Y306815D01*
X1089988D01*
X1093478Y310305D01*
G01X1039134Y228646D02*
X1053908Y213872D01*
Y181156D01*
X1030122Y157370D01*
X1017629D01*
G01X1021713Y192665D02*
X1017686Y188638D01*
Y173280D01*
X1017071Y172665D01*
X1012999D01*
G01X1021745Y208864D02*
Y210068D01*
X1019450Y212363D01*
Y227043D01*
X1021205Y228798D01*
Y268628D01*
X1059987Y307410D01*
Y327073D01*
X1075457Y342543D01*
X1080152D01*
X1090983Y353374D01*
X1092561D01*
G01X1018014Y228631D02*
X1019255Y229872D01*
Y269125D01*
X1057827Y307697D01*
Y328139D01*
X1078189Y348501D01*
X1082787D01*
G01X1044390Y861210D02*
X1041363Y858183D01*
X1034369D01*
X1029400Y853214D01*
Y830300D01*
X1025900Y826800D01*
Y809347D01*
X1023760Y807207D01*
Y779960D01*
X1019214Y775414D01*
Y771046D01*
X1023760Y766500D01*
Y757409D01*
X1024684Y756485D01*
G01X1018419Y917575D02*
X1036264Y899730D01*
X1049670D01*
X1054390Y895010D01*
Y886144D01*
X1056805Y883729D01*
Y876704D01*
X1048101Y868000D01*
X1035900D01*
X1027500Y859600D01*
Y832599D01*
X1023900Y828999D01*
Y810700D01*
X1021908Y808708D01*
Y794161D01*
X1019324Y791577D01*
X1016147D01*
X1014064Y793660D01*
G01X1054900Y879321D02*
X1035228D01*
X1031832Y875925D01*
Y866584D01*
X1022921Y857673D01*
Y854971D01*
X1024264Y853628D01*
Y847340D01*
X1021353Y844429D01*
Y841120D01*
X1023867Y838606D01*
Y833644D01*
X1021353Y831130D01*
X1015265D01*
X1012703Y833692D01*
Y837659D01*
G01X1022346Y917669D02*
X1028546Y923869D01*
X1031898D01*
X1045516Y937487D01*
Y968415D01*
X1056022Y978921D01*
Y1005801D01*
X1061688Y1011467D01*
Y1015113D01*
X1076110Y1029535D01*
G01X1045654Y143762D02*
X1039226Y137334D01*
Y116914D01*
X1049579Y106561D01*
X1051742D01*
G01X1037040Y125107D02*
Y116540D01*
X1047373Y106207D01*
Y95111D01*
G01X1050437Y244297D02*
X1055138Y248998D01*
Y259762D01*
X1038067Y276833D01*
Y281637D01*
X1061717Y305287D01*
Y326414D01*
X1076073Y340770D01*
X1082297D01*
G01X1070009Y997860D02*
X1071914Y995955D01*
Y977414D01*
X1054246Y959746D01*
Y902995D01*
X1056200Y901041D01*
Y886894D01*
X1059063Y884031D01*
Y835580D01*
X1043100Y819617D01*
Y810400D01*
X1040000Y807300D01*
Y782496D01*
X1042232Y777107D01*
Y728232D01*
X1031447Y717447D01*
Y713324D01*
X1029885Y711762D01*
G01X1035619Y755809D02*
X1037328Y754100D01*
X1039400D01*
X1040800Y755500D01*
Y776751D01*
X1038400Y782546D01*
Y808299D01*
X1041400Y811299D01*
Y821144D01*
X1050358Y830102D01*
Y837793D01*
G01X1049087Y856033D02*
X1037349D01*
X1035200Y853884D01*
Y759620D01*
X1038344Y756476D01*
G01X1038678Y776750D02*
X1036800Y778628D01*
Y827099D01*
X1043250Y833549D01*
X1044650D01*
X1046045Y834944D01*
Y841217D01*
G01X1042414Y801443D02*
Y806939D01*
X1060873Y825398D01*
Y898928D01*
X1056056Y903745D01*
Y958995D01*
X1077134Y980073D01*
Y1006332D01*
X1073525Y1009941D01*
Y1012428D01*
G01X1038010Y902565D02*
X1050089Y914644D01*
Y967868D01*
X1063918Y981697D01*
Y1007126D01*
X1066116Y1009324D01*
Y1013416D01*
X1081714Y1029014D01*
Y1035348D01*
X1079178Y1037884D01*
G01X1029570Y917718D02*
X1047342Y935490D01*
Y967681D01*
X1060071Y980410D01*
Y1006262D01*
X1064240Y1010431D01*
Y1014339D01*
X1078755Y1028854D01*
Y1031518D01*
G01X1046068Y792742D02*
X1048722D01*
X1064493Y808513D01*
Y964871D01*
X1079031Y979409D01*
Y1008305D01*
X1076800Y1010536D01*
Y1012900D01*
G01X1046930Y796557D02*
X1062683Y812310D01*
Y925117D01*
X1060698Y927102D01*
Y931619D01*
G01X1046485Y1034538D02*
X1046908Y1034115D01*
X1066241D01*
X1067884Y1035758D01*
Y1037484D01*
X1074651Y1044251D01*
X1077795D01*
X1083524Y1038522D01*
Y981341D01*
X1066303Y964120D01*
Y932484D01*
X1066878Y931909D01*
G01X1105741Y76587D02*
Y84214D01*
X1101285Y88670D01*
X1064753D01*
X1062773Y90650D01*
G01X1105741Y72615D02*
X1107980Y74854D01*
Y84535D01*
X1101900Y90615D01*
X1068085D01*
G01X1072456Y95236D02*
X1073972Y96752D01*
X1081725D01*
X1085182Y99182D01*
X1087567Y102328D01*
X1091041Y105802D01*
X1095780D01*
X1099300Y109322D01*
X1111566D01*
X1113508Y111264D01*
Y114554D01*
X1110412Y117650D01*
Y128748D01*
X1160900Y179236D01*
Y300014D01*
X1171174Y310288D01*
X1181549D01*
X1181706Y310131D01*
G01X1072406Y99961D02*
X1073805Y98562D01*
X1081152D01*
X1083910Y100502D01*
X1086046Y103367D01*
X1090291Y107612D01*
X1095030D01*
X1099501Y112083D01*
X1111553D01*
G01X1062523Y95236D02*
X1067944D01*
X1070714Y92466D01*
X1077667D01*
X1080143Y94942D01*
X1082859D01*
X1084253Y95922D01*
X1098646D01*
X1100199Y97475D01*
G01X1124107Y208864D02*
X1115989Y216982D01*
Y226382D01*
X1117889Y228282D01*
Y250281D01*
X1116169Y252001D01*
X1094257D01*
X1087378Y258880D01*
X1074522D01*
G01X1120376Y228631D02*
X1119619Y229388D01*
Y251663D01*
X1117196Y254086D01*
X1099518D01*
X1097301Y256303D01*
G01X1179901Y306366D02*
X1177789Y308478D01*
X1171924D01*
X1162710Y299264D01*
Y178486D01*
X1112222Y127998D01*
Y118400D01*
X1115318Y115304D01*
Y110514D01*
X1112035Y107231D01*
Y86811D01*
X1115055Y83791D01*
X1121448D01*
X1123703Y86046D01*
G01X1120149Y85731D02*
X1116054D01*
X1113845Y87940D01*
Y106481D01*
X1118303Y110939D01*
Y118123D01*
X1114032Y122394D01*
Y127248D01*
X1164520Y177736D01*
Y298514D01*
X1170954Y304948D01*
X1173559D01*
G01X1178045Y312193D02*
X1170519D01*
X1159090Y300764D01*
Y179986D01*
X1108602Y129498D01*
Y116900D01*
X1111553Y113949D01*
Y112083D01*
G01X1187996Y331992D02*
X1184960Y328956D01*
Y307788D01*
X1166330Y289158D01*
Y176986D01*
X1115842Y126498D01*
Y123144D01*
X1120113Y118873D01*
Y107892D01*
X1115842Y103621D01*
G01X1107759Y141247D02*
X1118356D01*
X1157680Y180571D01*
Y241420D01*
X1154803Y244297D01*
X1152799D01*
G01X1141496Y228646D02*
X1156190Y213952D01*
Y181076D01*
X1132484Y157370D01*
X1119991D01*
G01X1114708Y190185D02*
X1112556Y188033D01*
Y174176D01*
X1109903Y171523D01*
G01X1120376Y228631D02*
X1123030Y231285D01*
Y253975D01*
X1126657Y257602D01*
X1147496D01*
X1153636Y263742D01*
Y301295D01*
X1171508Y319167D01*
X1174929D01*
G01X1122705Y588515D02*
X1145300Y565920D01*
Y442937D01*
X1155137Y433100D01*
X1171799D01*
X1178083Y439384D01*
Y442856D01*
G01X1179184Y446595D02*
X1177596D01*
X1171600Y440599D01*
X1150579D01*
X1147330Y443848D01*
Y568155D01*
X1124470Y591015D01*
X1122705D01*
G01X1129471Y732571D02*
X1125109Y728209D01*
X1121401Y719257D01*
Y705069D01*
X1119171Y699685D01*
X1116296Y696810D01*
Y691851D01*
G01X1139402Y125107D02*
Y116692D01*
X1149735Y106359D01*
Y95111D01*
G01X1124107Y208864D02*
X1127102Y211859D01*
Y219125D01*
X1128315Y220338D01*
Y253363D01*
X1130902Y255950D01*
X1148230D01*
X1155046Y262766D01*
Y300710D01*
X1170596Y316260D01*
X1175084D01*
X1178916Y320092D01*
Y329720D01*
X1214965Y365769D01*
Y373549D01*
X1218347Y376931D01*
Y416173D01*
X1220131Y417957D01*
Y478284D01*
X1260037Y518190D01*
Y528832D01*
X1294798Y563593D01*
X1301997D01*
X1305317Y566913D01*
Y624580D01*
X1301127Y628770D01*
Y744685D01*
X1299124Y746688D01*
Y780452D01*
X1284343Y795233D01*
Y810600D01*
X1294164Y820421D01*
X1305231D01*
X1310602Y825792D01*
X1315976D01*
X1323205Y833021D01*
G01X1148016Y143762D02*
X1141588Y137334D01*
Y117066D01*
X1152093Y106561D01*
X1154104D01*
G01X1326355Y836170D02*
Y825895D01*
X1313685Y813225D01*
X1308739D01*
X1306828Y815136D01*
X1296802D01*
X1292587Y810921D01*
Y797335D01*
X1308811Y781111D01*
Y566417D01*
X1303167Y560773D01*
X1295968D01*
X1262857Y527662D01*
Y517020D01*
X1239945Y494108D01*
Y465928D01*
X1238408Y464391D01*
X1234493D01*
X1223591Y453489D01*
Y414615D01*
X1221167Y412191D01*
Y371818D01*
X1219745Y370396D01*
Y368554D01*
X1197871Y346680D01*
Y318077D01*
X1167740Y287946D01*
Y173484D01*
X1148055Y153799D01*
Y143801D01*
X1148016Y143762D01*
G01X1181379Y316049D02*
X1179499Y314169D01*
X1170500D01*
X1156456Y300125D01*
Y261794D01*
X1152799Y258137D01*
Y244297D01*
G01X1208103Y72615D02*
X1210342Y74854D01*
Y84535D01*
X1204262Y90615D01*
X1170447D01*
G01X1208103Y76587D02*
Y84214D01*
X1203607Y88710D01*
X1167075D01*
X1165135Y90650D01*
G01X1164885Y95236D02*
X1170306D01*
X1173076Y92466D01*
X1180029D01*
X1182505Y94942D01*
X1185221D01*
X1186615Y95922D01*
X1201008D01*
X1202561Y97475D01*
G01X1262605Y1187215D02*
X1260516D01*
X1257306Y1184005D01*
X1248869D01*
X1241662Y1191212D01*
X1228188D01*
X1227400Y1192000D01*
Y1195000D01*
X1225800Y1196600D01*
Y1214252D01*
X1224552Y1215500D01*
X1203500D01*
X1201678Y1217322D01*
X1190826D01*
X1190028Y1216524D01*
Y1214417D01*
X1189193Y1213582D01*
X1163976D01*
X1162105Y1211711D01*
G01X1280602Y1185238D02*
X1278184D01*
X1274014Y1181068D01*
X1266303D01*
X1262907Y1177672D01*
X1261644D01*
X1261293Y1178023D01*
X1244650D01*
X1242686Y1179987D01*
X1210112D01*
X1208867Y1181232D01*
Y1191100D01*
X1207000Y1192967D01*
Y1204000D01*
X1206500Y1204500D01*
X1204001D01*
X1202424Y1206077D01*
X1198476D01*
X1197617Y1206936D01*
Y1208693D01*
X1196468Y1209842D01*
X1167571D01*
X1165846Y1211567D01*
Y1211711D01*
G01X1213915Y112083D02*
X1203083D01*
X1198612Y107612D01*
X1192653D01*
X1188408Y103367D01*
X1186272Y100502D01*
X1183514Y98562D01*
X1176167D01*
X1174768Y99961D01*
G01X1266616Y322456D02*
X1267583Y321489D01*
X1267578Y321484D01*
Y308436D01*
X1264422Y305280D01*
X1260853D01*
X1260068Y304495D01*
Y286090D01*
X1263342Y282816D01*
Y179009D01*
X1212774Y128441D01*
Y117732D01*
X1215989Y114517D01*
Y111258D01*
X1214253Y109522D01*
X1203082D01*
X1199362Y105802D01*
X1193403D01*
X1189929Y102328D01*
X1187544Y99182D01*
X1184087Y96752D01*
X1176334D01*
X1174818Y95236D01*
G01X1177035Y257919D02*
X1191381D01*
X1194977Y254323D01*
X1218844D01*
X1220251Y252916D01*
Y228282D01*
X1218351Y226382D01*
Y216982D01*
X1226469Y208864D01*
G01X1275965Y1187232D02*
Y1185886D01*
X1273179Y1183100D01*
X1262201D01*
X1259028Y1179927D01*
X1245922D01*
X1242184Y1183665D01*
X1217100D01*
X1216600Y1184165D01*
Y1194000D01*
X1214468Y1196132D01*
Y1206432D01*
X1212928Y1207972D01*
X1207028D01*
X1206900Y1208100D01*
X1203301D01*
X1201401Y1210000D01*
X1198493D01*
X1197576Y1210917D01*
Y1212654D01*
X1196648Y1213582D01*
X1191725D01*
X1189855Y1211712D01*
X1188287D01*
G01X1222738Y228631D02*
X1221981Y229388D01*
Y253746D01*
X1219492Y256235D01*
X1206969D01*
X1204718Y258486D01*
X1201846D01*
X1199663Y256303D01*
G01X1249363Y1166065D02*
Y1166820D01*
X1243743Y1172440D01*
X1202860D01*
X1201300Y1174000D01*
Y1198110D01*
X1200800Y1198610D01*
X1197648D01*
X1195767Y1200491D01*
G01X1256218Y1175987D02*
X1255688Y1175457D01*
X1251607D01*
X1250884Y1176180D01*
X1206021D01*
X1205117Y1177084D01*
Y1196084D01*
X1202800Y1198401D01*
Y1200939D01*
X1199507Y1204232D01*
G01X1271256Y1185205D02*
X1261389D01*
X1258195Y1182011D01*
X1247186D01*
X1241744Y1187453D01*
X1220682D01*
X1220182Y1187953D01*
Y1194583D01*
X1221700Y1196101D01*
Y1210800D01*
X1220788Y1211712D01*
X1199507D01*
G01X1226065Y86046D02*
X1223781Y83762D01*
X1217446D01*
X1214397Y86811D01*
Y107106D01*
X1217799Y110508D01*
Y115267D01*
X1214584Y118482D01*
Y127691D01*
X1265152Y178259D01*
Y284460D01*
X1261923Y287689D01*
Y300243D01*
X1262665Y300985D01*
Y302730D01*
G01X1222511Y85731D02*
X1218416D01*
X1216207Y87940D01*
Y106356D01*
X1220745Y110894D01*
Y118071D01*
X1216394Y122422D01*
Y126941D01*
X1266962Y177509D01*
Y302167D01*
G01X1213915Y112083D02*
Y114031D01*
X1210964Y116982D01*
Y129191D01*
X1261532Y179759D01*
Y282066D01*
X1258258Y285340D01*
Y305245D01*
X1262016Y309003D01*
X1263328D01*
G01X1218204Y103621D02*
X1222555Y107972D01*
Y118821D01*
X1218204Y123172D01*
Y126191D01*
X1268772Y176759D01*
Y260460D01*
X1274528Y266216D01*
Y320092D01*
X1266626Y327994D01*
X1257506D01*
X1254000Y331500D01*
Y340000D01*
X1254500Y340500D01*
X1256000D01*
G01X1210121Y141247D02*
X1221025D01*
X1260122Y180344D01*
Y241340D01*
X1257165Y244297D01*
X1255161D01*
G01X1217070Y190185D02*
X1214918Y188033D01*
Y174176D01*
X1212265Y171523D01*
G01X1323205Y829871D02*
Y827627D01*
X1311623Y816045D01*
X1309909D01*
X1307047Y818907D01*
X1295229D01*
X1286115Y809793D01*
Y795796D01*
X1301288Y780623D01*
Y747511D01*
X1303931Y744868D01*
Y628743D01*
X1307401Y625273D01*
Y567002D01*
X1302582Y562183D01*
X1295383D01*
X1261447Y528247D01*
Y517605D01*
X1221861Y478019D01*
Y416256D01*
X1219757Y414152D01*
Y374725D01*
X1217177Y372145D01*
Y369925D01*
G01X1243858Y228646D02*
X1258712Y213792D01*
Y182103D01*
X1233979Y157370D01*
X1222353D01*
G01X1261659Y318258D02*
X1254723Y311322D01*
Y289584D01*
X1226083Y260944D01*
Y225188D01*
X1228700Y222571D01*
Y211095D01*
X1226469Y208864D01*
G01X1222738Y228631D02*
X1223917Y229810D01*
Y260828D01*
X1245888Y282799D01*
Y451669D01*
X1262489Y468270D01*
Y493440D01*
X1276137Y507088D01*
Y522157D01*
X1296346Y542366D01*
X1326357D01*
X1344032Y560041D01*
Y583395D01*
X1345190Y584553D01*
Y593034D01*
X1341793Y596431D01*
Y623069D01*
X1340069Y624793D01*
Y629290D01*
X1342687Y631908D01*
Y634357D01*
X1340930Y636114D01*
Y637670D01*
X1341793Y638533D01*
Y666681D01*
X1345067Y669955D01*
X1346321D01*
X1348593Y672227D01*
Y680011D01*
X1346109Y682495D01*
Y686842D01*
X1324453Y708498D01*
Y777526D01*
X1326925Y779998D01*
Y797512D01*
X1329000Y799587D01*
Y804000D01*
G01X1317000Y788000D02*
Y786188D01*
X1315251Y784439D01*
Y692567D01*
X1321347Y686471D01*
Y556160D01*
X1317359Y552172D01*
X1296477D01*
X1269297Y524992D01*
Y509923D01*
X1255649Y496275D01*
Y471105D01*
X1239048Y454504D01*
Y333676D01*
X1229922Y324550D01*
G01X1321000Y788000D02*
Y784656D01*
X1319067Y782723D01*
Y739459D01*
X1321123Y737403D01*
Y692387D01*
X1325007Y688503D01*
Y552164D01*
X1319209Y546366D01*
X1295791D01*
X1272917Y523492D01*
Y508423D01*
X1259269Y494775D01*
Y469605D01*
X1242668Y453004D01*
Y324706D01*
X1234904Y316942D01*
G01X1321000Y804000D02*
Y799854D01*
X1318987Y797841D01*
Y785279D01*
X1317061Y783353D01*
Y693600D01*
X1323157Y687504D01*
Y553638D01*
X1319881Y550362D01*
X1297227D01*
X1271107Y524242D01*
Y509173D01*
X1257459Y495525D01*
Y470355D01*
X1240858Y453754D01*
Y332759D01*
X1232165Y324066D01*
Y320876D01*
X1232197Y320844D01*
Y316964D01*
G01X1313000Y788000D02*
X1311631Y786631D01*
Y565247D01*
X1304337Y557953D01*
X1297138D01*
X1265677Y526492D01*
Y511423D01*
X1252029Y497775D01*
Y472605D01*
X1240995Y461571D01*
X1235663D01*
X1227044Y452952D01*
Y370680D01*
X1225755Y369391D01*
G01X1317000Y804000D02*
Y802054D01*
X1314905Y799959D01*
Y787018D01*
X1313441Y785554D01*
Y681138D01*
X1315953Y678626D01*
Y676586D01*
X1313641Y674274D01*
Y564697D01*
X1305087Y556143D01*
X1297888D01*
X1267487Y525742D01*
Y510673D01*
X1253839Y497025D01*
Y471855D01*
X1241745Y459761D01*
X1236413D01*
X1229162Y452510D01*
Y369395D01*
X1229122Y369355D01*
G01X1313000Y804000D02*
X1311467Y802467D01*
Y798192D01*
X1310221Y796946D01*
Y565832D01*
X1303752Y559363D01*
X1296553D01*
X1264267Y527077D01*
Y512008D01*
X1250619Y498360D01*
Y473190D01*
X1240410Y462981D01*
X1235078D01*
X1225336Y453239D01*
Y371986D01*
X1222601Y369251D01*
G01X1241764Y125107D02*
Y116542D01*
X1252097Y106209D01*
Y95111D01*
G01X1250378Y143762D02*
X1243950Y137334D01*
Y116916D01*
X1254305Y106561D01*
X1256466D01*
G01X1284419Y359377D02*
X1276393Y351351D01*
Y263717D01*
X1270182Y257506D01*
Y173564D01*
X1250417Y153799D01*
Y143801D01*
X1250378Y143762D01*
G01X1238293Y317296D02*
X1244478Y323481D01*
Y452254D01*
X1261079Y468855D01*
Y494025D01*
X1274727Y507673D01*
Y522742D01*
X1296541Y544556D01*
X1319959D01*
X1332926Y557523D01*
Y580554D01*
X1337052Y584680D01*
Y606742D01*
X1336081Y607713D01*
Y619971D01*
X1337518Y621408D01*
Y649864D01*
X1340149Y652495D01*
Y654669D01*
X1337303Y657515D01*
Y693652D01*
X1322933Y708022D01*
Y739409D01*
X1322290Y740052D01*
Y781539D01*
X1325000Y784249D01*
Y788000D01*
G01X1329000D02*
Y783233D01*
X1328335Y782568D01*
Y775703D01*
X1326140Y773508D01*
Y742790D01*
X1328905Y740025D01*
Y706042D01*
X1347519Y687428D01*
Y683422D01*
X1350003Y680938D01*
Y564017D01*
X1326088Y540102D01*
X1296246D01*
X1277547Y521403D01*
Y506503D01*
X1263899Y492855D01*
Y467685D01*
X1247298Y451084D01*
Y334701D01*
X1255504Y326495D01*
X1265335D01*
X1271571Y320259D01*
Y281185D01*
G01X1250055Y1749208D02*
X1543488D01*
X1547458Y1745238D01*
Y1743178D01*
X1543488Y1739208D01*
X1250055D01*
G01X1318859Y45448D02*
X1315712Y42301D01*
X1312493D01*
X1310465Y44329D01*
Y84214D01*
X1306024Y88655D01*
X1269492D01*
X1267497Y90650D01*
G01X1267247Y95236D02*
X1272668D01*
X1275438Y92466D01*
X1282601D01*
X1285077Y94942D01*
X1287583D01*
X1288977Y95922D01*
X1303370D01*
X1304923Y97475D01*
G01X1255161Y244297D02*
X1256848Y245984D01*
Y309565D01*
X1264088Y316805D01*
Y320382D01*
G01X1299304Y487382D02*
X1296144D01*
X1282902Y474140D01*
X1279029D01*
X1259223Y454334D01*
G01X1272809Y90615D02*
X1306624D01*
X1312704Y84535D01*
Y47631D01*
X1314887Y45448D01*
G01X1277130Y99961D02*
X1278529Y98562D01*
X1285876D01*
X1288634Y100502D01*
X1290770Y103367D01*
X1295015Y107612D01*
X1300576D01*
X1302698Y109734D01*
Y109735D01*
X1305046Y112083D01*
X1316277D01*
G01X1277180Y95236D02*
X1278696Y96752D01*
X1286449D01*
X1289906Y99182D01*
X1292291Y102328D01*
X1295765Y105802D01*
X1301326D01*
X1305702Y110178D01*
X1317085D01*
X1318212Y111305D01*
Y114789D01*
X1315029Y117972D01*
Y141513D01*
X1336680Y163164D01*
Y268459D01*
X1342866Y274645D01*
Y277913D01*
X1344007Y279054D01*
G01X1279246Y258880D02*
X1292786D01*
X1297321Y254345D01*
X1321184D01*
X1322613Y252916D01*
Y228282D01*
X1320713Y226382D01*
Y216982D01*
X1328831Y208864D01*
G01X1284900Y678800D02*
X1284260Y679440D01*
Y706960D01*
X1285500Y708200D01*
Y731707D01*
X1273392Y743815D01*
Y786337D01*
X1272099Y787630D01*
Y844357D01*
X1282919Y855177D01*
Y855769D01*
X1284693Y857543D01*
X1286868D01*
X1290761Y861436D01*
X1294809D01*
X1296717Y863344D01*
X1312058D01*
X1313253Y864539D01*
X1329098D01*
X1331019Y862618D01*
Y861921D01*
G01X1289811Y677612D02*
Y682914D01*
X1287400Y685325D01*
Y733727D01*
X1276047Y745080D01*
Y786242D01*
X1273909Y788380D01*
Y842703D01*
X1284720Y853514D01*
X1286868D01*
X1292454Y859100D01*
X1295435D01*
X1297733Y861398D01*
X1312193D01*
X1313897Y863102D01*
X1327072D01*
X1327869Y862305D01*
Y861921D01*
G01X1289317Y706932D02*
Y762748D01*
X1281768Y770297D01*
Y786023D01*
X1275719Y792072D01*
Y841719D01*
X1280212Y846212D01*
X1284469D01*
X1285500Y847243D01*
Y851500D01*
G01X1319389Y859837D02*
X1312740D01*
X1311668Y858765D01*
X1306484D01*
X1304544Y856825D01*
X1293025D01*
X1288575Y852375D01*
Y834377D01*
X1285356Y831158D01*
X1278966D01*
X1277529Y829721D01*
Y792822D01*
X1283578Y786773D01*
Y771047D01*
X1292135Y762490D01*
Y597241D01*
X1293241Y596135D01*
Y576211D01*
X1300817Y568635D01*
G01X1312890Y856653D02*
X1309275D01*
X1301893Y849271D01*
X1298737D01*
X1294467Y853541D01*
X1292696D01*
X1290385Y851230D01*
Y828726D01*
X1279339Y817680D01*
Y793572D01*
X1285388Y787523D01*
Y771797D01*
X1293945Y763240D01*
Y600917D01*
X1303587Y591275D01*
Y567911D01*
X1301194Y565518D01*
G01X1298963Y659609D02*
X1297314Y661258D01*
Y779702D01*
X1282501Y794515D01*
Y811701D01*
X1293031Y822231D01*
X1303710D01*
X1308083Y826604D01*
Y832683D01*
X1309588Y834188D01*
X1310595Y834605D01*
X1313000D01*
G01X1319042Y869303D02*
X1315026D01*
X1314554Y868831D01*
X1309078D01*
X1307399Y870510D01*
X1297754D01*
X1294207Y866963D01*
X1292360D01*
X1286860Y861463D01*
X1284529D01*
X1282999Y859933D01*
Y858026D01*
X1279460Y854487D01*
G01X1319121Y872379D02*
X1315898D01*
X1315468Y872809D01*
X1297793D01*
X1293984Y869000D01*
X1290618D01*
X1287056Y865438D01*
X1284673D01*
X1284300Y865065D01*
X1281663Y861690D01*
X1279460Y859487D01*
G01X1319202Y875530D02*
X1316030D01*
X1314719Y874219D01*
X1299281D01*
X1295758Y877742D01*
X1292368D01*
X1286396Y883714D01*
X1280233D01*
X1279460Y884487D01*
G01X1319229Y878679D02*
X1315179D01*
X1312129Y875629D01*
X1300661D01*
X1294482Y881808D01*
X1292037D01*
X1284358Y889487D01*
X1279460D01*
G01X1281400Y940256D02*
Y939230D01*
X1285417Y935213D01*
Y929008D01*
X1281299Y924890D01*
X1276894D01*
X1273098Y921094D01*
X1272391Y919387D01*
Y913135D01*
X1290533Y894993D01*
X1296866D01*
G01X1327920Y893436D02*
Y894474D01*
X1321808Y900586D01*
Y906930D01*
X1314615Y914123D01*
X1274400D01*
G01X1325100Y228631D02*
X1324343Y229388D01*
Y253746D01*
X1321854Y256235D01*
X1309075D01*
X1306869Y258441D01*
X1304163D01*
X1302025Y256303D01*
G01X1324770Y835500D02*
Y834730D01*
X1324945Y834555D01*
Y826480D01*
X1313100Y814635D01*
X1309324D01*
X1306782Y817177D01*
X1296026D01*
X1287691Y808842D01*
Y797167D01*
X1306915Y777943D01*
Y661088D01*
X1305836Y660009D01*
G01X1316906Y839320D02*
X1310278D01*
X1309756Y839536D01*
X1306808D01*
X1304703Y837431D01*
Y832488D01*
X1301915Y829700D01*
X1300117D01*
X1297667Y832150D01*
G01X1293500Y827500D02*
X1294530Y826470D01*
X1300680D01*
X1306113Y831903D01*
Y836846D01*
X1307253Y837986D01*
X1309547D01*
X1310143Y837739D01*
X1313000D01*
G01X1319282Y850381D02*
X1309145D01*
X1303951Y845187D01*
X1295187D01*
X1293500Y843500D01*
G01Y851500D02*
X1297981Y847019D01*
X1302766D01*
X1309176Y853429D01*
X1319228D01*
G01X1293500Y835500D02*
X1295400D01*
X1300669Y840769D01*
X1303809D01*
X1307141Y844101D01*
X1319200D01*
G01X1319119Y847152D02*
X1315502D01*
X1314727Y846377D01*
X1307256D01*
X1303696Y842817D01*
X1300004D01*
X1296687Y839500D01*
G01X1294000Y863500D02*
X1295588Y865088D01*
X1311787D01*
X1312635Y865936D01*
X1330925D01*
X1332654Y867665D01*
G01X1291129Y892267D02*
X1292527Y890869D01*
X1293607D01*
X1304213Y880263D01*
X1320055D01*
G01X1297558Y970216D02*
Y968442D01*
X1298410Y967590D01*
Y951642D01*
X1310824Y939228D01*
X1316003D01*
X1320627Y934604D01*
Y929199D01*
X1322809Y927017D01*
Y916877D01*
X1326446Y913240D01*
Y899179D01*
X1331069Y894556D01*
Y893462D01*
G01X1384265Y320871D02*
X1383398Y320004D01*
X1370720D01*
X1348060Y297344D01*
Y274184D01*
X1340300Y266424D01*
Y161664D01*
X1318649Y140013D01*
Y122418D01*
X1323018Y118049D01*
Y110991D01*
X1318569Y106542D01*
Y56616D01*
X1328003Y47182D01*
Y32403D01*
G01X1384265Y325371D02*
X1380708Y321814D01*
X1369970D01*
X1345952Y297796D01*
Y275171D01*
X1338490Y267709D01*
Y162414D01*
X1316839Y140763D01*
Y118722D01*
X1320022Y115539D01*
Y110555D01*
X1316759Y107292D01*
Y55866D01*
X1325977Y46648D01*
Y29674D01*
X1328318Y27333D01*
G01X1316277Y112083D02*
Y114164D01*
X1313219Y117222D01*
Y142263D01*
X1334870Y163914D01*
Y269209D01*
X1340869Y275208D01*
Y278352D01*
X1340104Y279117D01*
G01X1319432Y190185D02*
X1317280Y188033D01*
Y174176D01*
X1314627Y171523D01*
G01X1327939Y835500D02*
Y834700D01*
X1327765Y834526D01*
Y823504D01*
X1317040Y812779D01*
Y810230D01*
X1315046Y808236D01*
Y803192D01*
X1313000Y801146D01*
Y796000D01*
G01X1331089Y835500D02*
Y834412D01*
X1331700Y833801D01*
Y823058D01*
X1321054Y812412D01*
Y810692D01*
X1318933Y808571D01*
Y800933D01*
X1317000Y799000D01*
G01X1305250Y889250D02*
X1307938Y886562D01*
X1320055D01*
G01X1324775Y893449D02*
Y894004D01*
X1322841Y895938D01*
X1308942D01*
X1307869Y897011D01*
Y900084D01*
X1305356Y902597D01*
G01X1311325Y928918D02*
Y923183D01*
X1324000Y910508D01*
Y901000D01*
G01X1431080Y1301702D02*
Y1306412D01*
X1429654Y1307838D01*
X1320517D01*
X1320514Y1307837D01*
X1309975Y1297298D01*
Y1285263D01*
X1308107Y1283395D01*
G01X1303900Y1288000D02*
Y1295800D01*
X1317520Y1309420D01*
X1324309Y1312232D01*
X1368632D01*
X1407825Y1351425D01*
Y1426975D01*
G01X1387847Y366710D02*
Y363814D01*
X1389127Y362534D01*
Y322370D01*
X1384951Y318194D01*
X1371470D01*
X1350122Y296846D01*
Y272481D01*
X1342110Y264469D01*
Y160914D01*
X1320459Y139263D01*
Y123168D01*
X1324828Y118799D01*
Y107883D01*
X1320566Y103621D01*
G01X1325100Y228631D02*
X1327692Y231223D01*
Y255640D01*
X1333037Y260985D01*
Y270499D01*
X1337046Y274508D01*
Y279810D01*
X1344142Y286906D01*
Y298546D01*
X1372232Y326636D01*
Y361298D01*
G01X1333000Y788000D02*
X1334796Y786204D01*
Y766659D01*
X1334537Y766400D01*
Y743215D01*
X1331747Y740425D01*
Y717109D01*
X1343184Y705672D01*
Y698579D01*
X1359941Y681822D01*
Y499405D01*
X1375548Y483798D01*
Y453120D01*
X1395669Y432999D01*
Y410735D01*
X1384930Y399996D01*
Y382119D01*
X1399884Y367165D01*
G01X1337000Y804000D02*
Y799991D01*
X1330939Y793930D01*
Y785433D01*
X1333386Y782986D01*
Y773790D01*
X1327550Y767954D01*
Y743375D01*
X1330337Y740588D01*
Y710889D01*
X1340499Y700727D01*
Y698633D01*
X1348929Y690203D01*
Y684829D01*
X1352404Y681354D01*
Y557123D01*
X1358531Y550996D01*
Y498820D01*
X1374138Y483213D01*
Y452454D01*
X1386814Y439778D01*
Y421104D01*
X1388410Y419508D01*
X1391211D01*
X1392717Y418002D01*
Y410994D01*
X1391623Y409900D01*
G01X1340518Y835500D02*
Y820210D01*
X1333046Y812738D01*
Y807092D01*
X1331075Y805121D01*
Y798075D01*
X1329000Y796000D01*
G01X1321000D02*
X1323042Y798042D01*
Y805550D01*
X1325003Y807511D01*
Y813585D01*
X1333600Y822182D01*
Y833801D01*
X1334219Y834420D01*
Y835500D01*
G01X1325000Y799000D02*
X1327017Y801017D01*
Y805632D01*
X1328991Y807606D01*
Y812778D01*
X1338000Y821787D01*
Y833500D01*
X1337387Y834113D01*
Y835500D01*
G01X1343668D02*
Y834000D01*
X1343500Y833832D01*
Y818559D01*
X1337007Y812066D01*
Y806998D01*
X1334993Y804984D01*
Y800993D01*
X1333000Y799000D01*
G01X1430839Y965546D02*
X1414736Y949443D01*
X1338730D01*
X1325815Y936528D01*
Y932023D01*
X1325905Y931933D01*
Y929532D01*
X1324595Y928222D01*
Y922912D01*
X1328868Y918639D01*
Y900202D01*
X1334219Y894851D01*
Y893516D01*
G01X1337428Y893597D02*
Y896821D01*
X1336332Y897917D01*
X1334690D01*
X1333758Y898849D01*
Y922318D01*
X1332407Y923669D01*
Y927393D01*
X1327225Y932575D01*
Y935106D01*
X1328061Y935942D01*
X1338287D01*
X1345948Y943603D01*
G01X1348419Y265222D02*
X1357743Y255898D01*
X1384914D01*
X1396515Y244297D01*
X1405162D01*
G01X1400231Y390256D02*
X1401692Y391717D01*
Y428971D01*
X1376958Y453705D01*
Y484383D01*
X1361351Y499990D01*
Y690972D01*
X1337012Y715311D01*
Y735256D01*
X1339203Y737447D01*
Y782917D01*
X1337000Y785120D01*
Y788000D01*
G01X1341000D02*
X1342823Y786177D01*
Y733859D01*
X1345343Y731339D01*
Y722095D01*
X1344206Y720958D01*
Y713369D01*
X1364971Y692604D01*
Y501490D01*
X1380578Y485883D01*
Y455205D01*
X1405848Y429935D01*
Y363367D01*
X1404690Y362209D01*
G01X1345000Y788000D02*
Y785400D01*
X1349400Y781000D01*
Y710972D01*
X1366381Y693991D01*
Y502075D01*
X1381988Y486468D01*
Y455819D01*
X1409773Y428034D01*
Y406444D01*
X1414369Y401848D01*
Y398056D01*
G01X1349000Y804000D02*
Y800488D01*
X1347000Y798488D01*
Y785600D01*
X1350900Y781700D01*
Y711577D01*
X1367791Y694686D01*
Y502660D01*
X1383398Y487053D01*
Y456404D01*
X1411498Y428304D01*
Y409084D01*
X1416329Y404253D01*
Y391144D01*
X1413489Y388304D01*
Y374533D01*
X1432741Y355281D01*
Y349081D01*
X1434697Y347125D01*
G01X1345000Y804000D02*
Y802048D01*
X1343178Y800226D01*
Y798410D01*
X1339076Y794308D01*
Y785901D01*
X1341013Y783964D01*
Y726453D01*
X1342567Y724899D01*
Y723261D01*
X1339881Y720575D01*
Y715023D01*
X1363161Y691743D01*
Y500740D01*
X1378768Y485133D01*
Y454455D01*
X1403950Y429273D01*
Y391159D01*
X1402968Y390177D01*
G01X1345950Y850340D02*
X1346590D01*
X1348430Y848500D01*
Y830863D01*
X1347827Y830260D01*
Y815561D01*
X1345037Y812771D01*
Y809643D01*
X1342969Y807575D01*
Y803133D01*
X1341000Y801164D01*
Y799000D01*
G01X1345252Y842470D02*
X1347060Y840662D01*
Y832020D01*
X1345730Y830690D01*
Y818311D01*
X1338995Y811576D01*
Y797995D01*
X1337000Y796000D01*
G01X1345000D02*
Y799280D01*
X1346917Y801197D01*
Y808317D01*
X1349013Y810413D01*
Y812813D01*
X1351300Y815100D01*
Y821366D01*
X1353134Y823200D01*
Y829466D01*
X1349800Y832800D01*
Y846330D01*
X1350660Y847190D01*
X1351070D01*
G01X1353000Y804000D02*
Y799400D01*
X1350900Y797300D01*
Y786600D01*
X1353000Y784500D01*
Y711472D01*
X1369201Y695271D01*
Y503245D01*
X1384808Y487638D01*
Y456989D01*
X1413642Y428155D01*
Y419612D01*
X1415610Y417644D01*
G01X1348917Y796000D02*
Y797825D01*
X1351053Y799961D01*
Y807853D01*
X1352987Y809787D01*
Y819787D01*
X1354800Y821600D01*
Y830610D01*
X1353115Y832295D01*
Y834830D01*
G01X1354185Y906498D02*
X1354184D01*
X1353501Y905815D01*
Y898516D01*
X1349834Y894849D01*
Y886148D01*
X1347101Y883415D01*
Y879344D01*
X1346445Y878688D01*
X1346139D01*
G01X1353948Y943603D02*
Y937779D01*
X1348518Y932349D01*
Y919361D01*
X1346340Y917183D01*
Y901930D01*
X1346924Y901346D01*
Y888234D01*
X1345252Y886562D01*
G01X1357948Y938842D02*
X1352546Y933440D01*
Y917041D01*
X1348177Y912672D01*
Y886801D01*
X1346370Y884994D01*
X1345709D01*
G01X1441088Y976409D02*
X1436999Y972320D01*
Y966026D01*
X1416553Y945580D01*
X1353184D01*
X1340595Y932991D01*
Y924140D01*
X1341905Y922830D01*
Y898076D01*
X1340532Y896703D01*
Y893355D01*
G01X1440700Y981763D02*
X1437480D01*
X1435189Y979472D01*
Y966776D01*
X1415834Y947421D01*
X1352465D01*
X1336595Y931551D01*
Y924148D01*
X1338015Y922728D01*
Y898995D01*
X1338953Y898057D01*
Y892862D01*
G01X1349848Y936755D02*
Y936655D01*
X1344437Y931244D01*
Y899486D01*
X1343673Y898722D01*
Y893355D01*
G01X1405162Y244297D02*
X1407110D01*
X1410067Y241340D01*
Y183645D01*
X1386729Y160307D01*
Y157257D01*
X1370719Y141247D01*
X1360122D01*
G01X1357000Y804000D02*
Y781000D01*
X1354810Y778810D01*
Y712222D01*
X1371011Y696021D01*
Y503995D01*
X1386618Y488388D01*
Y457739D01*
X1415674Y428683D01*
Y421278D01*
G01X1404249Y735858D02*
Y780644D01*
X1403815Y781691D01*
X1389406Y796100D01*
X1369794D01*
X1363000Y802894D01*
Y811620D01*
G01X1359000D02*
Y802176D01*
X1367896Y793280D01*
X1388236D01*
X1400934Y780582D01*
Y716407D01*
X1372821Y688294D01*
Y504745D01*
X1388428Y489138D01*
Y458489D01*
X1419010Y427907D01*
Y372836D01*
X1439719Y352127D01*
Y350387D01*
G01X1361000Y804000D02*
Y802609D01*
X1368919Y794690D01*
X1388821D01*
X1402344Y781167D01*
Y715822D01*
X1374231Y687709D01*
Y505330D01*
X1389838Y489723D01*
Y459074D01*
X1421005Y427907D01*
Y407616D01*
G01X1359425Y829000D02*
X1357082Y826657D01*
Y809582D01*
X1355000Y807500D01*
Y798300D01*
X1352817Y796117D01*
Y796000D01*
G01X1356264Y834860D02*
Y834324D01*
X1355920Y833980D01*
Y832250D01*
X1357370Y830800D01*
X1360100D01*
X1361100Y829800D01*
Y818882D01*
X1365049Y814933D01*
Y810405D01*
X1369534Y805920D01*
X1378184D01*
X1378364Y806100D01*
X1382400D01*
X1383500Y805000D01*
Y803500D01*
X1385260Y801740D01*
X1392954D01*
X1404894Y789800D01*
X1408941D01*
X1414405Y784336D01*
Y713809D01*
X1420128Y708086D01*
Y704072D01*
X1419148Y703092D01*
X1417350D01*
X1411977Y697719D01*
Y693814D01*
X1405683Y687520D01*
Y685262D01*
X1375641Y655220D01*
Y622832D01*
X1375762Y622711D01*
Y505794D01*
X1391248Y490308D01*
Y459659D01*
X1423903Y427004D01*
Y386520D01*
X1438768Y371655D01*
G01X1367298Y829871D02*
X1383400Y813769D01*
Y810800D01*
X1386300Y807900D01*
X1398400D01*
X1401300Y805000D01*
X1411600D01*
X1412305Y804295D01*
Y790991D01*
X1421738Y781558D01*
Y727738D01*
X1418000Y724000D01*
G01X1360999Y836170D02*
X1362400Y834769D01*
Y828500D01*
X1384879Y806021D01*
X1395045D01*
X1396593Y804473D01*
Y800307D01*
X1405400Y791500D01*
X1409236D01*
X1419928Y780808D01*
Y746928D01*
X1418000Y745000D01*
G01X1371664Y831436D02*
X1381559Y821541D01*
X1385173D01*
X1394997Y811717D01*
X1398530D01*
G01X1402417Y811692D02*
X1402392Y811717D01*
X1401230D01*
X1398414Y814533D01*
X1394798D01*
X1385886Y823445D01*
X1382355D01*
X1375300Y830500D01*
Y833600D01*
X1374314Y834586D01*
G01X1375162Y835458D02*
X1376700Y833920D01*
Y831700D01*
X1383051Y825349D01*
X1385977D01*
X1395383Y815943D01*
X1401420D01*
X1405646Y811717D01*
X1406483D01*
G01X1378312Y838608D02*
X1381520Y835400D01*
X1383300D01*
X1396310Y822390D01*
X1402929D01*
X1405402Y819917D01*
G01X1383779Y872399D02*
X1387380Y876000D01*
X1392128D01*
X1394262Y878134D01*
X1399866D01*
X1402000Y876000D01*
G01X1384256Y881848D02*
X1390758Y888350D01*
X1394002D01*
X1397652Y892000D01*
X1402000D01*
G01X1359430Y893910D02*
Y900154D01*
X1368548Y909272D01*
Y931303D01*
X1373948Y936703D01*
Y940103D01*
G01X1387753Y912629D02*
X1382046D01*
X1367689Y898272D01*
X1363791D01*
X1362390Y896871D01*
Y894970D01*
X1362564Y894796D01*
Y893880D01*
G01X1394891Y914783D02*
X1390223Y910115D01*
X1382337D01*
X1368671Y896449D01*
X1367839D01*
X1365713Y894323D01*
Y893491D01*
G01X1368863Y894770D02*
X1372276Y898183D01*
X1376403D01*
X1379601Y901381D01*
Y904703D01*
X1380842Y905944D01*
X1383243D01*
X1385569Y908270D01*
X1402187D01*
G01X1372354Y157370D02*
X1380912D01*
X1408657Y185115D01*
Y213848D01*
X1393859Y228646D01*
G01X1375171Y424741D02*
X1372945Y422515D01*
Y418793D01*
X1380746Y410992D01*
Y376746D01*
X1389826Y367666D01*
Y364256D01*
X1390976Y363106D01*
Y321051D01*
X1420023Y292004D01*
Y173404D01*
X1400418Y153799D01*
Y143801D01*
X1400379Y143762D01*
G01X1375108Y420838D02*
X1383291Y412655D01*
Y377132D01*
X1398162Y362261D01*
Y317483D01*
X1421694Y293951D01*
Y263181D01*
X1425995Y258880D01*
X1429247D01*
G01X1442633Y371502D02*
Y384088D01*
X1428029Y398692D01*
Y426886D01*
X1394068Y460847D01*
Y491478D01*
X1380822Y504724D01*
Y551451D01*
X1381840Y552469D01*
X1384399D01*
X1386016Y554086D01*
Y629084D01*
X1388716Y631784D01*
Y639578D01*
X1401305Y652167D01*
Y659095D01*
X1405069Y662859D01*
X1411751D01*
X1431343Y682451D01*
Y696562D01*
X1436669Y701888D01*
X1438381D01*
X1439720Y703227D01*
Y706995D01*
X1451442Y718717D01*
Y753061D01*
X1458053Y759672D01*
Y799829D01*
X1451608Y806274D01*
X1446088D01*
X1435807Y816555D01*
X1433663D01*
X1416298Y833920D01*
X1404480D01*
X1397168Y841232D01*
X1393732D01*
X1383046Y851918D01*
G01X1440523Y382747D02*
X1425919Y397351D01*
Y426983D01*
X1392658Y460244D01*
Y490893D01*
X1377172Y506379D01*
Y552514D01*
X1380890Y556232D01*
Y621225D01*
X1377051Y625064D01*
Y640179D01*
X1379940Y643068D01*
X1390211D01*
X1392717Y645574D01*
Y650517D01*
X1396130Y653930D01*
X1397820D01*
X1399100Y655210D01*
Y659185D01*
X1422966Y683051D01*
Y697507D01*
X1432226Y706767D01*
X1437045D01*
X1450032Y719754D01*
Y761733D01*
X1456643Y768344D01*
Y795657D01*
X1450679Y801621D01*
X1446897D01*
X1436965Y811553D01*
X1434385D01*
X1430100Y815838D01*
Y818123D01*
X1418273Y829950D01*
X1411850D01*
X1409550Y832250D01*
X1403550D01*
X1396370Y839430D01*
X1393534D01*
X1383075Y849889D01*
X1381925D01*
X1379896Y851918D01*
G01X1373000Y804000D02*
X1378080Y798920D01*
X1391784D01*
X1404204Y786500D01*
X1408251D01*
X1409115Y785636D01*
Y773520D01*
G01X1369000Y804000D02*
X1375490Y797510D01*
X1389991D01*
X1405210Y782291D01*
X1405659Y781207D01*
Y752676D01*
X1407482Y750853D01*
G01X1418000Y705000D02*
X1412675Y710325D01*
Y784071D01*
X1408746Y788000D01*
X1404699D01*
X1392369Y800330D01*
X1384670D01*
X1381000Y804000D01*
G01X1377560Y837740D02*
X1378410Y836890D01*
Y834888D01*
X1378230Y834708D01*
Y832270D01*
X1382450Y828050D01*
X1385836D01*
X1396133Y817753D01*
X1406047D01*
X1416950Y806850D01*
Y802950D01*
X1421900Y798000D01*
Y788600D01*
X1423548Y786952D01*
Y701548D01*
X1418000Y696000D01*
G01X1414597Y792375D02*
Y804803D01*
X1412200Y807200D01*
X1402000D01*
X1399408Y809792D01*
X1390526D01*
X1370447Y829871D01*
G01X1383046Y845619D02*
X1392295Y836370D01*
X1395370D01*
X1403940Y827800D01*
X1406500D01*
X1412600Y821700D01*
X1417500D01*
X1423200Y816000D01*
Y810900D01*
X1426500Y807600D01*
X1428900D01*
X1432200Y804300D01*
Y800049D01*
X1449194Y783055D01*
Y763370D01*
X1448622Y762798D01*
Y732497D01*
X1446860Y730735D01*
G01X1446717Y735536D02*
X1442622Y739631D01*
Y784176D01*
X1421000Y805798D01*
Y814700D01*
X1418000Y817700D01*
X1412500D01*
X1411000Y819200D01*
Y820400D01*
X1405790Y825610D01*
X1399230D01*
X1383935Y840905D01*
G01X1379896Y848769D02*
X1382200D01*
X1393079Y837890D01*
X1395910D01*
X1403600Y830200D01*
X1407500D01*
X1411700Y826000D01*
X1416100D01*
X1424900Y817200D01*
Y813435D01*
X1425740Y812595D01*
X1428552D01*
X1439018Y802129D01*
Y795599D01*
X1454504Y780113D01*
Y777575D01*
G01X1438930Y716363D02*
X1440179Y717612D01*
Y774211D01*
X1424395Y789995D01*
Y798805D01*
X1418900Y804300D01*
Y807600D01*
X1411400Y815100D01*
Y816240D01*
X1408700Y818940D01*
Y820100D01*
X1405000Y823800D01*
X1398100D01*
X1384742Y837158D01*
X1382058D01*
X1379896Y839320D01*
G01X1401300Y820485D02*
X1396220D01*
X1383684Y833021D01*
X1379896D01*
G01Y855068D02*
X1383581D01*
X1395969Y842680D01*
X1402220D01*
X1406900Y838000D01*
X1416500D01*
X1421920Y832580D01*
X1427820D01*
X1429000Y831400D01*
Y827250D01*
X1442512Y813738D01*
Y812278D01*
X1446508Y808282D01*
X1451595D01*
X1459463Y800414D01*
Y759087D01*
X1452852Y752476D01*
Y714513D01*
X1441155Y702816D01*
Y683935D01*
X1419682Y662462D01*
X1414196D01*
X1409826Y658092D01*
X1404232D01*
X1403035Y656895D01*
Y651451D01*
X1390126Y638542D01*
Y631199D01*
X1387426Y628499D01*
Y514374D01*
X1393944Y507856D01*
G01X1379896Y861367D02*
X1381626Y863097D01*
X1393603D01*
X1397867Y858833D01*
X1403667D01*
X1404500Y858000D01*
X1420800D01*
X1434318Y844482D01*
X1444599D01*
X1449150Y839931D01*
X1454608D01*
X1466312Y828227D01*
Y819691D01*
X1466513Y819490D01*
Y756162D01*
X1462981Y752630D01*
Y713073D01*
X1458206Y708298D01*
Y675638D01*
X1437035Y654467D01*
X1415451D01*
X1395127Y634143D01*
Y566547D01*
X1398984Y562690D01*
Y546631D01*
X1397079Y544726D01*
G01X1381560Y856690D02*
X1381930Y856320D01*
X1384794D01*
X1387026Y854088D01*
X1390550D01*
X1393810Y850828D01*
X1402776D01*
X1406387Y847217D01*
Y846513D01*
X1410900Y842000D01*
X1416300D01*
X1421750Y836550D01*
X1429850D01*
X1430500Y835900D01*
Y831635D01*
X1433540Y828595D01*
X1434675D01*
X1437965Y825305D01*
Y824427D01*
X1460873Y801519D01*
Y758502D01*
X1454262Y751891D01*
Y713476D01*
X1443129Y702343D01*
Y683914D01*
X1418567Y659352D01*
X1415556D01*
X1391701Y635497D01*
Y630779D01*
X1388836Y627914D01*
Y516198D01*
X1394044Y510990D01*
G01X1446323Y673183D02*
Y700659D01*
X1457082Y711418D01*
Y750721D01*
X1463693Y757332D01*
Y807811D01*
X1439124Y832380D01*
Y834602D01*
X1437091Y836635D01*
X1436300D01*
X1428435Y844500D01*
X1423100D01*
X1417600Y850000D01*
X1407772D01*
X1404062Y853710D01*
X1398192D01*
X1392100Y859802D01*
X1384080D01*
G01X1376747Y861367D02*
X1379887Y864507D01*
X1395256D01*
X1395576Y864827D01*
X1398035D01*
X1400862Y862000D01*
X1421535D01*
X1433400Y850135D01*
X1446399D01*
X1467722Y828812D01*
Y820276D01*
X1467923Y820075D01*
Y755577D01*
X1464391Y752045D01*
Y712488D01*
X1462016Y710113D01*
Y677051D01*
X1436171Y651206D01*
X1414185D01*
X1396537Y633558D01*
Y567132D01*
X1400394Y563275D01*
Y545143D01*
X1397988Y542737D01*
X1394240D01*
X1393628Y542125D01*
Y515252D01*
X1395949Y512931D01*
Y502943D01*
X1406910Y491982D01*
G01X1383046Y858218D02*
X1385382D01*
X1387772Y855828D01*
X1391534D01*
X1395062Y852300D01*
X1403460D01*
X1407560Y848200D01*
X1409200D01*
X1411440Y845960D01*
X1417440D01*
X1422960Y840440D01*
X1429760D01*
X1432200Y838000D01*
Y834265D01*
X1434060Y832405D01*
X1437104D01*
X1462283Y807226D01*
Y757917D01*
X1455672Y751306D01*
Y712439D01*
X1444859Y701626D01*
Y679088D01*
X1422911Y657140D01*
X1415339D01*
X1393717Y635518D01*
Y558105D01*
X1395605Y556217D01*
G01X1451428Y673252D02*
Y684216D01*
X1455633Y688421D01*
Y707953D01*
X1458492Y710812D01*
Y750136D01*
X1465103Y756747D01*
Y811796D01*
X1436417Y840482D01*
X1435718D01*
X1422170Y854030D01*
X1406370D01*
X1404368Y856032D01*
X1398082D01*
X1392747Y861367D01*
X1383046D01*
G01X1405500Y880000D02*
X1388746D01*
X1384295Y875549D01*
G01X1376747Y867665D02*
X1378352Y866060D01*
X1394691D01*
X1394868Y866237D01*
X1404663D01*
X1404920Y865980D01*
X1419922D01*
X1434000Y851902D01*
X1446627D01*
X1469132Y829397D01*
Y820861D01*
X1469333Y820660D01*
Y754992D01*
X1465801Y751460D01*
Y711903D01*
X1464463Y710565D01*
Y676703D01*
X1461474Y673714D01*
Y655807D01*
G01X1402000Y884000D02*
X1389260D01*
X1383939Y878679D01*
G01X1464536Y433114D02*
X1471398Y439976D01*
Y705248D01*
X1471870Y705720D01*
Y708880D01*
X1471030Y709720D01*
Y716810D01*
X1476690Y722470D01*
Y744357D01*
X1481580Y749247D01*
Y755718D01*
X1472153Y765145D01*
Y821830D01*
X1471952Y822031D01*
Y830567D01*
X1441900Y860619D01*
X1430894D01*
X1417563Y873950D01*
X1405650D01*
X1403622Y871922D01*
X1393830D01*
X1391139Y869231D01*
X1383710D01*
G01X1459873Y391705D02*
Y398321D01*
X1462520Y400968D01*
Y434874D01*
X1469988Y442342D01*
Y661514D01*
X1466466Y665036D01*
Y710573D01*
X1467211Y711318D01*
Y745068D01*
X1468867Y746724D01*
X1472213D01*
X1473354Y747865D01*
Y750710D01*
X1470743Y753321D01*
Y821245D01*
X1470542Y821446D01*
Y829982D01*
X1441315Y859209D01*
X1430309D01*
X1419518Y870000D01*
X1411900D01*
X1411388Y870512D01*
X1395115D01*
X1392268Y867665D01*
X1379896D01*
G01X1383046Y870814D02*
X1390271D01*
X1392789Y873332D01*
X1402332D01*
X1406960Y877960D01*
X1415569D01*
X1431500Y862029D01*
X1442485D01*
X1473362Y831152D01*
Y822616D01*
X1473563Y822415D01*
Y765730D01*
X1482990Y756303D01*
Y704160D01*
X1472808Y693978D01*
Y437762D01*
X1464250Y429204D01*
Y399803D01*
X1463145Y398698D01*
Y391579D01*
G01X1405500Y896000D02*
X1399092D01*
X1393473Y890381D01*
X1389551D01*
X1384148Y884978D01*
G01X1400379Y143762D02*
X1393951Y137334D01*
Y116796D01*
X1404186Y106561D01*
X1406467D01*
G01X1391765Y125107D02*
Y116422D01*
X1402098Y106089D01*
Y95111D01*
G01X1522881Y901034D02*
X1520986Y899139D01*
Y889096D01*
X1490319Y858429D01*
X1464718D01*
X1458067Y865080D01*
Y880578D01*
X1453478Y885167D01*
X1443949D01*
X1433274Y895842D01*
Y917005D01*
X1430794Y919485D01*
X1409661D01*
X1406687Y916511D01*
Y910054D01*
X1402669Y906036D01*
X1393609D01*
X1387504Y899931D01*
G01X1390541Y900086D02*
X1394694Y904239D01*
X1403009D01*
X1408173Y909403D01*
Y915828D01*
X1410157Y917812D01*
X1430392D01*
X1431725Y916479D01*
Y895396D01*
X1443364Y883757D01*
X1452797D01*
X1456657Y879897D01*
Y864495D01*
X1464133Y857019D01*
X1491011D01*
X1522954Y888962D01*
Y897951D01*
G01X1460466Y76587D02*
Y84214D01*
X1455970Y88710D01*
X1419438D01*
X1417498Y90650D01*
G01X1460466Y72615D02*
X1462705Y74854D01*
Y84535D01*
X1456625Y90615D01*
X1422810D01*
G01X1427131Y99961D02*
X1428530Y98562D01*
X1435976D01*
X1445026Y107612D01*
X1450491D01*
X1454962Y112083D01*
X1466278D01*
G01X1469538Y416795D02*
X1470576Y415757D01*
Y393200D01*
X1505983Y357793D01*
Y310469D01*
X1494592Y299078D01*
Y270937D01*
X1515785Y249744D01*
Y179396D01*
X1465110Y128721D01*
Y117949D01*
X1468193Y114866D01*
Y111160D01*
X1466490Y109457D01*
X1454896D01*
X1451241Y105802D01*
X1445776D01*
X1436726Y96752D01*
X1428697D01*
X1427181Y95236D01*
G01X1417248D02*
X1422669D01*
X1425439Y92466D01*
X1432590D01*
X1435066Y94942D01*
X1437646D01*
X1438626Y95922D01*
X1453371D01*
X1454924Y97475D01*
G01X1478832Y208864D02*
X1470714Y216982D01*
Y226382D01*
X1472230Y227898D01*
Y251301D01*
X1470708Y252823D01*
X1448692D01*
X1442635Y258880D01*
X1429247D01*
G01X1486360Y345200D02*
X1480156Y351404D01*
Y359904D01*
X1451227Y388833D01*
Y405235D01*
X1456913Y410921D01*
Y436382D01*
X1464958Y444427D01*
Y590233D01*
X1456052Y599139D01*
X1438576D01*
X1436175Y601540D01*
X1434847D01*
X1430944Y605443D01*
G01X1429059Y908579D02*
Y896067D01*
X1442779Y882347D01*
X1452212D01*
X1455200Y879359D01*
Y863534D01*
X1463245Y855489D01*
X1492396D01*
X1529808Y892901D01*
Y912794D01*
X1548616Y931602D01*
G01X1426085Y910281D02*
Y897046D01*
X1442194Y880937D01*
X1451627D01*
X1453775Y878789D01*
Y862759D01*
X1462600Y853934D01*
X1502213D01*
X1531363Y883084D01*
Y910570D01*
X1548629Y927836D01*
G01X1417284Y911009D02*
X1420229Y908064D01*
Y900907D01*
X1441609Y879527D01*
X1451042D01*
X1452363Y878206D01*
Y862126D01*
X1462001Y852488D01*
X1502812D01*
X1532809Y882485D01*
Y910021D01*
X1538477Y915689D01*
X1548504D01*
G01X1531546Y1062769D02*
X1549079D01*
X1549697Y1063387D01*
Y1066470D01*
X1549004Y1067163D01*
X1522283D01*
X1520740Y1065620D01*
Y1051442D01*
X1514714Y1045416D01*
X1461930D01*
X1446004Y1029490D01*
Y973980D01*
X1444035Y972011D01*
Y951125D01*
X1429907Y936998D01*
G01X1517855Y1053457D02*
X1518630Y1054232D01*
Y1064491D01*
X1517470Y1065651D01*
X1515619D01*
X1515119Y1065151D01*
Y1063580D01*
X1514589Y1063050D01*
X1509324D01*
X1508794Y1062520D01*
Y1060040D01*
X1509324Y1059510D01*
X1514589D01*
X1515119Y1058980D01*
Y1056500D01*
X1514589Y1055970D01*
X1506608D01*
X1506108Y1055470D01*
Y1053058D01*
X1506736Y1052430D01*
X1514589D01*
X1515119Y1051900D01*
Y1048889D01*
X1513756Y1047526D01*
X1502817D01*
X1502287Y1048056D01*
Y1050164D01*
X1501757Y1050694D01*
X1499277D01*
X1498747Y1050164D01*
Y1048056D01*
X1498217Y1047526D01*
X1461056D01*
X1443894Y1030364D01*
Y974854D01*
X1441925Y972885D01*
Y956290D01*
X1440360Y954725D01*
X1438461D01*
X1426692Y942956D01*
X1426690D01*
X1425071Y941337D01*
Y941335D01*
X1424897Y941161D01*
Y936777D01*
G01X1475101Y228631D02*
X1477418Y230948D01*
Y302545D01*
X1464216Y315747D01*
Y371331D01*
X1449274Y386273D01*
Y416511D01*
X1435424Y430361D01*
G01X1434944Y605443D02*
X1439438Y600949D01*
X1457382D01*
X1466768Y591563D01*
Y443677D01*
X1458769Y435678D01*
Y410217D01*
X1453037Y404485D01*
Y389583D01*
X1482797Y359823D01*
Y353263D01*
X1486360Y349700D01*
G01X1458214Y406231D02*
X1460579Y408596D01*
Y434928D01*
X1468578Y442927D01*
Y594040D01*
X1459859Y602759D01*
X1440520D01*
X1438944Y604335D01*
Y605637D01*
G01X1521939Y1040818D02*
X1521317Y1040196D01*
X1464094D01*
X1451224Y1027326D01*
Y956302D01*
X1456893Y950633D01*
Y900521D01*
X1454631Y898259D01*
Y896504D01*
X1453332Y895205D01*
X1442736D01*
X1441223Y893692D01*
Y891957D01*
G01X1524953Y1051037D02*
X1523886D01*
X1523386Y1051537D01*
Y1056215D01*
X1524136Y1056965D01*
X1527514D01*
X1528042Y1056437D01*
Y1049096D01*
X1526093Y1047147D01*
X1522585D01*
X1521975Y1046537D01*
Y1044607D01*
X1521475Y1044107D01*
X1518023D01*
X1516722Y1042806D01*
X1463012D01*
X1448614Y1028408D01*
Y970492D01*
X1448084Y969962D01*
X1447298D01*
X1446768Y969432D01*
Y966952D01*
X1447298Y966422D01*
X1448084D01*
X1448614Y965892D01*
Y963412D01*
X1448084Y962882D01*
X1447298D01*
X1446768Y962352D01*
Y959872D01*
X1447298Y959342D01*
X1448084D01*
X1448614Y958812D01*
Y955220D01*
X1454270Y949564D01*
Y907393D01*
X1447261Y900384D01*
Y898571D01*
G01X1468309Y408861D02*
Y392838D01*
X1504173Y356974D01*
Y311803D01*
X1492316Y299946D01*
Y270069D01*
X1513975Y248410D01*
Y180146D01*
X1463300Y129471D01*
Y117199D01*
X1466278Y114221D01*
Y112083D01*
G01X1462484Y141247D02*
X1473081D01*
X1512565Y180731D01*
Y241260D01*
X1509528Y244297D01*
X1507524D01*
G01X1464628Y171523D02*
X1467281Y174176D01*
Y189367D01*
X1464158Y192490D01*
G01X1475101Y228631D02*
X1473960Y229772D01*
Y252131D01*
X1471471Y254620D01*
X1453709D01*
X1452026Y256303D01*
G01X1461113Y871389D02*
X1463928D01*
X1466053Y873514D01*
Y917539D01*
X1465225Y918367D01*
Y929013D01*
X1466184Y929972D01*
X1472412D01*
X1472942Y930502D01*
Y932982D01*
X1472412Y933512D01*
X1467285D01*
X1466755Y934042D01*
Y936522D01*
X1467285Y937052D01*
X1472412D01*
X1472942Y937582D01*
Y940062D01*
X1472412Y940592D01*
X1467285D01*
X1466755Y941122D01*
Y943602D01*
X1467285Y944132D01*
X1472412D01*
X1472942Y944662D01*
Y947142D01*
X1472412Y947672D01*
X1467285D01*
X1466755Y948202D01*
Y950682D01*
X1467285Y951212D01*
X1472412D01*
X1472942Y951742D01*
Y954222D01*
X1472412Y954752D01*
X1467285D01*
X1466755Y955282D01*
Y957762D01*
X1467285Y958292D01*
X1472412D01*
X1472942Y958822D01*
Y961302D01*
X1472412Y961832D01*
X1467285D01*
X1461872Y967245D01*
Y976669D01*
X1460109Y978432D01*
Y984883D01*
X1462679Y987453D01*
Y998515D01*
X1469180Y1005016D01*
Y1014682D01*
X1478562Y1024064D01*
Y1024454D01*
X1481171Y1027063D01*
X1483799D01*
X1484853Y1026009D01*
X1498541D01*
X1500469Y1027937D01*
X1519391D01*
X1529084Y1037630D01*
Y1043349D01*
X1531947Y1046212D01*
G01X1522099Y1035521D02*
X1520700Y1036920D01*
X1512764D01*
X1512264Y1036420D01*
Y1033622D01*
X1511734Y1033092D01*
X1509254D01*
X1508724Y1033622D01*
Y1036773D01*
X1508154Y1037343D01*
X1481294D01*
X1480770Y1037867D01*
X1464749D01*
X1453334Y1026452D01*
Y957176D01*
X1459003Y951507D01*
Y903652D01*
X1462449Y900206D01*
Y896825D01*
X1458518Y892894D01*
X1456392D01*
X1452641Y889143D01*
Y888033D01*
G01X1503572Y1034538D02*
X1491770D01*
X1490113Y1032881D01*
X1464013D01*
X1462421Y1031289D01*
Y1021268D01*
X1455841Y1014688D01*
Y1002848D01*
X1458919Y999770D01*
Y994640D01*
X1455841Y991562D01*
Y977788D01*
X1457352Y976277D01*
G01X1503884Y295549D02*
Y266849D01*
X1517595Y253138D01*
Y178646D01*
X1466920Y127971D01*
Y118699D01*
X1470003Y115616D01*
Y110410D01*
X1466760Y107167D01*
Y86811D01*
X1469745Y83826D01*
X1476208D01*
X1478428Y86046D01*
G01X1497446Y295877D02*
Y297177D01*
X1499166Y298897D01*
X1504765D01*
X1506007Y297655D01*
Y267510D01*
X1519405Y254112D01*
Y177896D01*
X1468837Y127328D01*
Y122214D01*
X1473002Y118049D01*
Y110849D01*
X1468570Y106417D01*
Y87940D01*
X1470779Y85731D01*
X1474874D01*
G01X1470567Y103621D02*
X1474812Y107866D01*
Y118799D01*
X1470647Y122964D01*
Y126578D01*
X1521215Y177146D01*
Y255807D01*
X1507824Y269198D01*
Y359161D01*
X1494286Y372699D01*
G01X1474716Y157370D02*
X1487209D01*
X1511075Y181236D01*
Y213792D01*
X1496221Y228646D01*
G01X1475236Y412482D02*
X1476340Y411378D01*
Y395786D01*
X1509234Y362892D01*
Y270497D01*
X1522625Y257106D01*
Y173644D01*
X1502780Y153799D01*
Y143801D01*
X1502741Y143762D01*
G01X1507524Y244297D02*
Y252414D01*
X1490614Y269324D01*
Y302781D01*
X1492862Y305029D01*
Y365454D01*
X1466231Y392085D01*
Y423671D01*
G01X1466653Y428582D02*
X1478575Y416660D01*
Y395546D01*
X1511514Y362607D01*
Y270470D01*
X1523104Y258880D01*
X1531609D01*
G01X1471375Y433115D02*
Y426213D01*
X1480443Y417145D01*
Y395673D01*
X1513382Y362734D01*
Y272192D01*
X1523942Y261632D01*
X1553312D01*
X1555696Y259248D01*
X1559270D01*
X1563206Y255312D01*
X1574109D01*
X1579149Y250272D01*
Y230317D01*
X1577463Y228631D01*
G01X1527096Y997860D02*
X1533848Y991108D01*
Y957357D01*
X1539544Y943605D01*
X1550562Y932587D01*
Y914957D01*
X1549132Y913527D01*
X1538310D01*
X1534257Y909474D01*
Y881917D01*
X1503154Y850814D01*
X1489858D01*
X1474772Y835728D01*
Y823201D01*
X1474973Y823000D01*
Y766315D01*
X1484400Y756888D01*
Y699480D01*
X1480570Y695650D01*
X1478079D01*
X1474713Y692284D01*
Y685247D01*
G01X1480343Y914776D02*
X1478621Y913054D01*
Y866486D01*
X1473489Y861354D01*
G01X1494954Y895264D02*
X1493439Y896779D01*
Y906979D01*
X1476784Y923634D01*
Y964046D01*
X1482798Y970060D01*
Y974826D01*
X1485183Y977211D01*
Y1003943D01*
X1488183Y1006943D01*
Y1010943D01*
X1490682Y1013442D01*
X1499981D01*
X1506180Y1019641D01*
X1517379D01*
X1522078Y1024340D01*
Y1027273D01*
X1532067Y1037262D01*
Y1041832D01*
G01X1502741Y143762D02*
X1496313Y137334D01*
Y116916D01*
X1506668Y106561D01*
X1508829D01*
G01X1494127Y125107D02*
Y116542D01*
X1504460Y106209D01*
Y95111D01*
G01X1562828Y72615D02*
X1565067Y74854D01*
Y84535D01*
X1558987Y90615D01*
X1525172D01*
G01X1562828Y76587D02*
Y84214D01*
X1558332Y88710D01*
X1521800D01*
X1519860Y90650D01*
G01X1529493Y99961D02*
X1530892Y98562D01*
X1538352D01*
X1542440Y102650D01*
X1544830Y106230D01*
X1547402Y107612D01*
X1552117D01*
X1556588Y112083D01*
X1568640D01*
G01X1594466Y350984D02*
X1597944Y347506D01*
Y336124D01*
X1592994Y331174D01*
Y275377D01*
X1618307Y250064D01*
Y179056D01*
X1567472Y128221D01*
Y117799D01*
X1570715Y114556D01*
Y111370D01*
X1567934Y108589D01*
X1555654D01*
X1552867Y105802D01*
X1547859D01*
X1546130Y104873D01*
X1543932Y101582D01*
X1539102Y96752D01*
X1531059D01*
X1529543Y95236D01*
G01X1519610D02*
X1525031D01*
X1527801Y92466D01*
X1534770D01*
X1537246Y94942D01*
X1539852D01*
X1540832Y95922D01*
X1555733D01*
X1557286Y97475D01*
G01X1531609Y258880D02*
X1545229D01*
X1552286Y251823D01*
X1571652D01*
X1573076Y250399D01*
Y216982D01*
X1581194Y208864D01*
G01X1551175Y347283D02*
X1547810Y343918D01*
Y312634D01*
X1544736Y309560D01*
Y305156D01*
G01X1577463Y228631D02*
X1575464Y230630D01*
Y250857D01*
X1572701Y253620D01*
X1557071D01*
X1554388Y256303D01*
G01X1553862Y344867D02*
X1552445D01*
X1549620Y342042D01*
Y311409D01*
X1549139Y310928D01*
Y306950D01*
X1550931Y305158D01*
G01X1596691Y287397D02*
Y274472D01*
X1620117Y251046D01*
Y178306D01*
X1569309Y127498D01*
Y118522D01*
X1572525Y115306D01*
Y110620D01*
X1569202Y107297D01*
Y86731D01*
X1572107Y83826D01*
X1578570D01*
X1580790Y86046D01*
G01X1596197Y293477D02*
X1598281D01*
X1599396Y292362D01*
Y274327D01*
X1621927Y251796D01*
Y177556D01*
X1571119Y126748D01*
Y122675D01*
X1575440Y118354D01*
Y110975D01*
X1571012Y106547D01*
Y87860D01*
X1573141Y85731D01*
X1577236D01*
G01X1568640Y112083D02*
Y114071D01*
X1565662Y117049D01*
Y129019D01*
X1616497Y179854D01*
Y249314D01*
X1591184Y274627D01*
Y370564D01*
X1596253Y375633D01*
G01X1605966Y343794D02*
Y340438D01*
X1602272Y336744D01*
Y274705D01*
X1623737Y253240D01*
Y176806D01*
X1572929Y125998D01*
Y123425D01*
X1577250Y119104D01*
Y107942D01*
X1572929Y103621D01*
G01X1564846Y141247D02*
X1575556D01*
X1614767Y180458D01*
Y241420D01*
X1611890Y244297D01*
X1609886D01*
G01X1577078Y157370D02*
X1589684D01*
X1613333Y181019D01*
Y213896D01*
X1598583Y228646D01*
G01X1566990Y171523D02*
X1569643Y174176D01*
Y189367D01*
X1566520Y192490D01*
G01X1609886Y244297D02*
Y252414D01*
X1588943Y273357D01*
Y372169D01*
X1596534Y379760D01*
G01X1596489Y125107D02*
Y116602D01*
X1606822Y106269D01*
Y95111D01*
G01X1605103Y143762D02*
X1598675Y137334D01*
Y116976D01*
X1609090Y106561D01*
X1611191D01*
G01X1602138Y351047D02*
X1608440Y344745D01*
Y340216D01*
X1604127Y335903D01*
Y274845D01*
X1625147Y253825D01*
Y175622D01*
X1605142Y155617D01*
Y143801D01*
X1605103Y143762D01*
G01X1665190Y76587D02*
Y84214D01*
X1660694Y88710D01*
X1624162D01*
X1622222Y90650D01*
G01X1621972Y95236D02*
X1627393D01*
X1630163Y92466D01*
X1637426D01*
X1639902Y94942D01*
X1642462D01*
X1643442Y95922D01*
X1658095D01*
X1659648Y97475D01*
G01X1626147Y351033D02*
Y263456D01*
X1630723Y258880D01*
X1633971D01*
G01X1619192Y1211711D02*
X1621063Y1213582D01*
X1646280D01*
X1647115Y1214417D01*
Y1216524D01*
X1647913Y1217322D01*
X1663500D01*
X1665222Y1215600D01*
X1681301D01*
X1683000Y1213901D01*
Y1196100D01*
X1683500Y1195600D01*
X1698301D01*
X1707601Y1186300D01*
X1715870D01*
X1716785Y1187215D01*
X1719692D01*
G01X1622933Y1211711D02*
Y1211567D01*
X1624658Y1209842D01*
X1653555D01*
X1654704Y1208693D01*
Y1206936D01*
X1655640Y1206000D01*
X1661800D01*
X1662300Y1205500D01*
Y1203483D01*
X1663800Y1201983D01*
Y1192100D01*
X1665900Y1190000D01*
Y1181400D01*
X1667313Y1179987D01*
X1699773D01*
X1701577Y1178183D01*
X1718220D01*
X1718731Y1177672D01*
X1719994D01*
X1723390Y1181068D01*
X1731101D01*
X1735271Y1185238D01*
X1737689D01*
G01X1665190Y72615D02*
X1667429Y74854D01*
Y84535D01*
X1661349Y90615D01*
X1627534D01*
G01X1631905Y95236D02*
X1633421Y96752D01*
X1641450D01*
X1650500Y105802D01*
X1655229D01*
X1657937Y108510D01*
X1670172D01*
X1672909Y111247D01*
Y114714D01*
X1669914Y117709D01*
Y128801D01*
X1720669Y179556D01*
Y267255D01*
X1648285Y339639D01*
X1636688D01*
X1634219Y342108D01*
Y372204D01*
X1641615Y379600D01*
G01X1631855Y99961D02*
X1633254Y98562D01*
X1640700D01*
X1649750Y107612D01*
X1654479D01*
X1657187Y110320D01*
X1669239D01*
X1671002Y112083D01*
G01X1683556Y208864D02*
X1675438Y216982D01*
Y226382D01*
X1677338Y228282D01*
Y250890D01*
X1675887Y252341D01*
X1653418D01*
X1646879Y258880D01*
X1633971D01*
G01X1712248Y244297D02*
Y271121D01*
X1647819Y335550D01*
X1640030D01*
G01X1679825Y228631D02*
X1682638Y231444D01*
Y297894D01*
X1646894Y333638D01*
X1633543D01*
X1628079Y339102D01*
Y369275D01*
X1638340Y379536D01*
G01X1671002Y112083D02*
Y114061D01*
X1668104Y116959D01*
Y129551D01*
X1718859Y180306D01*
Y266505D01*
X1647594Y337770D01*
X1632646D01*
X1630691Y339725D01*
Y347432D01*
G01X1636561Y343072D02*
X1647412D01*
X1690636Y299848D01*
X1696960D01*
X1726099Y270709D01*
Y177306D01*
X1675344Y126551D01*
Y123058D01*
X1679555Y118847D01*
Y107885D01*
X1675291Y103621D01*
G01X1686408Y332584D02*
X1684034Y334958D01*
X1660773D01*
X1657504Y338227D01*
Y352252D01*
X1640197Y369559D01*
Y374690D01*
G01X1679825Y228631D02*
X1679068Y229388D01*
Y253746D01*
X1678241Y254573D01*
X1658480D01*
X1656750Y256303D01*
G01X1707465Y143762D02*
Y155958D01*
X1727509Y176002D01*
Y271294D01*
X1697545Y301258D01*
X1691563D01*
X1654771Y338050D01*
Y352088D01*
G01X1706450Y1173065D02*
X1705366D01*
X1704741Y1172440D01*
X1659723D01*
X1658500Y1173663D01*
Y1198110D01*
X1658000Y1198610D01*
X1654735D01*
X1652854Y1200491D01*
G01X1713239Y1176038D02*
X1708113D01*
X1707844Y1176307D01*
X1701257D01*
X1701130Y1176180D01*
X1664220D01*
X1662204Y1178196D01*
Y1201220D01*
X1661099Y1202325D01*
X1658501D01*
X1656594Y1204232D01*
G01Y1211712D02*
X1658464Y1213582D01*
X1663500D01*
X1665282Y1211800D01*
X1677899D01*
X1678900Y1210799D01*
Y1196562D01*
X1677269Y1194931D01*
Y1187953D01*
X1677769Y1187453D01*
X1698831D01*
X1701984Y1184300D01*
X1716715D01*
X1717620Y1185205D01*
X1728343D01*
G01X1733052Y1187310D02*
Y1185886D01*
X1730266Y1183100D01*
X1718876D01*
X1717976Y1182200D01*
X1700736D01*
X1699271Y1183665D01*
X1674819D01*
X1673621Y1184863D01*
Y1194379D01*
X1671800Y1196200D01*
Y1206526D01*
X1670426Y1207900D01*
X1663700D01*
X1661600Y1210000D01*
X1655580D01*
X1654663Y1210917D01*
Y1212654D01*
X1653735Y1213582D01*
X1648812D01*
X1646942Y1211712D01*
X1645374D01*
G01X1703609Y287320D02*
X1722479Y268450D01*
Y178806D01*
X1671724Y128051D01*
Y118459D01*
X1674719Y115464D01*
Y110497D01*
X1671484Y107262D01*
Y86811D01*
X1674469Y83826D01*
X1680932D01*
X1683152Y86046D01*
G01X1679598Y85731D02*
X1675503D01*
X1673294Y87940D01*
Y106512D01*
X1677745Y110963D01*
Y118097D01*
X1673534Y122308D01*
Y127301D01*
X1724289Y178056D01*
Y269959D01*
X1702107Y292141D01*
X1700223D01*
G01X1712248Y244297D02*
X1714252D01*
X1717051Y241498D01*
Y180493D01*
X1677805Y141247D01*
X1667208D01*
G01X1669352Y171523D02*
X1672005Y174176D01*
Y189367D01*
X1668882Y192490D01*
G01X1666860Y353661D02*
X1672833Y347688D01*
X1679146D01*
X1686309Y340525D01*
X1688979D01*
X1725219Y304285D01*
X1783565D01*
X1790015Y297835D01*
Y212961D01*
X1785918Y208864D01*
G01X1782187Y228631D02*
X1788576Y235020D01*
Y297279D01*
X1782980Y302875D01*
X1723861D01*
X1688168Y338568D01*
X1685498D01*
X1679346Y344720D01*
X1672213D01*
X1663650Y353283D01*
G01X1673723Y353881D02*
X1674998Y352606D01*
X1679897D01*
X1687970Y344533D01*
X1690640D01*
X1727668Y307505D01*
X1796189D01*
X1798050Y305644D01*
Y295660D01*
X1795445Y293055D01*
Y151518D01*
X1772276Y128349D01*
Y117887D01*
X1775692Y114471D01*
Y110657D01*
X1774180Y109145D01*
X1761870D01*
X1758607Y105882D01*
X1752935D01*
X1749597Y102544D01*
X1748377Y100993D01*
X1746377Y99324D01*
X1743668Y96615D01*
X1735646D01*
X1734267Y95236D01*
G01X1773364Y112083D02*
Y113807D01*
X1770466Y116705D01*
Y129099D01*
X1793635Y152268D01*
Y293805D01*
X1796240Y296410D01*
Y304894D01*
X1795439Y305695D01*
X1726761D01*
X1689844Y342612D01*
X1687174D01*
X1679903Y349883D01*
X1673974D01*
X1670323Y353534D01*
G01X1679440Y157370D02*
X1691933D01*
X1715641Y181078D01*
Y213950D01*
X1700945Y228646D01*
G01X1691182Y357016D02*
X1703537Y344661D01*
Y334789D01*
X1728561Y309765D01*
X1799661D01*
X1808708Y300718D01*
Y288334D01*
X1800875Y280501D01*
Y149268D01*
X1777706Y126099D01*
Y123029D01*
X1781900Y118835D01*
Y107868D01*
X1777653Y103621D01*
G01X1824706Y1100185D02*
X1823681Y1099160D01*
Y1097017D01*
X1831605Y1089093D01*
Y999272D01*
X1829133Y996800D01*
X1794999D01*
X1788337Y990138D01*
X1777460D01*
X1772440Y985118D01*
Y974128D01*
X1738249Y939937D01*
Y920686D01*
X1737450Y919887D01*
Y534764D01*
X1717302Y514616D01*
X1713981Y506609D01*
Y471899D01*
X1704100Y462018D01*
Y442954D01*
X1688962Y427816D01*
Y394863D01*
X1713581Y370244D01*
Y345383D01*
X1712226Y344028D01*
G01X1715590Y331719D02*
X1710110Y337199D01*
Y370690D01*
X1687000Y393800D01*
Y428700D01*
X1702100Y443800D01*
Y462600D01*
X1712100Y472600D01*
Y506798D01*
X1716273Y516873D01*
X1735640Y536240D01*
Y940240D01*
X1769400Y974000D01*
Y1004200D01*
X1764800Y1008800D01*
Y1037300D01*
X1772400Y1044900D01*
Y1079600D01*
X1765900Y1086100D01*
Y1091700D01*
X1748500Y1109100D01*
Y1202900D01*
X1747500Y1203900D01*
Y1224900D01*
X1769500Y1246900D01*
Y1588889D01*
X1767670Y1590719D01*
X1761072D01*
G01X1766313Y1580198D02*
X1767690Y1578821D01*
Y1247650D01*
X1745600Y1225560D01*
Y1201990D01*
X1746690Y1200900D01*
Y1108350D01*
X1764090Y1090950D01*
Y1085350D01*
X1770590Y1078850D01*
Y1045650D01*
X1762990Y1038050D01*
Y1008050D01*
X1767590Y1003450D01*
Y974750D01*
X1733830Y940990D01*
Y536990D01*
X1714698Y517858D01*
X1710290Y507216D01*
Y473350D01*
X1700290Y463350D01*
Y444550D01*
X1685190Y429450D01*
Y393050D01*
X1708300Y369940D01*
Y332822D01*
X1714943Y326179D01*
X1716755D01*
G01X1828272Y1095968D02*
X1833415Y1090825D01*
Y998522D01*
X1829883Y994990D01*
X1795749D01*
X1789087Y988328D01*
X1778428D01*
X1775300Y985200D01*
Y974428D01*
X1740059Y939187D01*
Y919936D01*
X1739260Y919137D01*
Y534014D01*
X1718838Y513592D01*
X1715791Y506240D01*
Y471149D01*
X1705910Y461268D01*
Y442204D01*
X1690772Y427066D01*
Y395613D01*
X1715791Y370594D01*
Y341108D01*
X1715930Y340969D01*
G01X1707465Y143762D02*
X1701037Y137334D01*
Y117076D01*
X1711552Y106561D01*
X1713553D01*
G01X1698851Y125107D02*
Y116702D01*
X1709184Y106369D01*
Y95111D01*
G01X1737786Y377173D02*
X1738946D01*
X1740223Y375896D01*
Y374316D01*
X1739194Y373287D01*
X1718218D01*
X1694392Y397113D01*
Y425566D01*
X1709530Y440704D01*
Y459768D01*
X1719411Y469649D01*
Y505416D01*
X1721981Y511614D01*
X1749739Y539372D01*
X1754334D01*
X1756089Y541127D01*
Y542952D01*
G01X1744180Y383966D02*
X1746720Y381426D01*
Y377615D01*
X1737424Y368319D01*
X1720626D01*
X1692582Y396363D01*
Y426316D01*
X1707720Y441454D01*
Y460518D01*
X1717601Y470399D01*
Y505779D01*
X1720446Y512639D01*
X1749747Y541940D01*
X1750879D01*
G01X1758957Y543036D02*
Y541435D01*
X1755084Y537562D01*
X1750489D01*
X1723594Y510664D01*
X1721221Y504947D01*
Y468899D01*
X1711340Y459018D01*
Y439954D01*
X1696202Y424816D01*
Y397863D01*
X1718968Y375097D01*
X1727675D01*
X1729751Y377173D01*
G01X1767552Y76587D02*
Y84214D01*
X1763056Y88710D01*
X1726524D01*
X1724584Y90650D01*
G01X1724334Y95236D02*
X1729755D01*
X1732525Y92466D01*
X1739633D01*
X1741972Y94805D01*
X1745445D01*
X1746562Y95922D01*
X1760457D01*
X1762010Y97475D01*
G01X1756391Y487382D02*
X1743598Y474589D01*
X1736785D01*
X1736113Y473917D01*
X1729576D01*
X1719516Y463857D01*
Y457540D01*
X1716310Y454334D01*
G01X1767552Y72615D02*
X1769791Y74854D01*
Y84535D01*
X1763711Y90615D01*
X1729896D01*
G01X1773364Y112083D02*
X1772291Y111010D01*
X1761175D01*
X1757857Y107692D01*
X1752185D01*
X1749442Y104949D01*
X1748105Y103613D01*
X1747094Y102328D01*
X1745429Y100936D01*
X1742918Y98425D01*
X1735753D01*
X1734217Y99961D01*
G01X1736333Y258880D02*
X1749721D01*
X1754601Y254000D01*
X1778616D01*
X1779700Y252916D01*
Y228282D01*
X1777800Y226382D01*
Y216982D01*
X1785918Y208864D01*
G01X1771714Y171523D02*
X1774367Y174176D01*
Y189367D01*
X1771244Y192490D01*
G01X1782187Y228631D02*
X1781430Y229388D01*
Y253746D01*
X1778941Y256235D01*
X1767066D01*
X1764701Y258600D01*
X1761409D01*
X1759112Y256303D01*
G01X1786466Y85923D02*
X1785358D01*
X1783261Y83826D01*
X1777210D01*
X1773806Y87230D01*
Y106211D01*
X1777502Y109907D01*
Y115221D01*
X1774086Y118637D01*
Y127599D01*
X1797255Y150768D01*
Y284334D01*
X1804758Y291837D01*
Y294429D01*
G01X1781960Y85731D02*
X1777865D01*
X1775616Y87980D01*
Y105461D01*
X1780090Y109935D01*
Y118085D01*
X1775896Y122279D01*
Y126849D01*
X1799065Y150018D01*
Y282633D01*
X1806898Y290466D01*
Y299250D01*
X1805196Y300952D01*
G01X1793524Y303343D02*
X1791825Y301644D01*
Y198711D01*
X1785779Y192665D01*
G54D13*
X62205Y765197D03*
X74016Y333464D03*
X102224Y70866D03*
X409488Y1604724D03*
X433130Y70866D03*
X463387Y286221D03*
X463386Y765197D03*
X661674Y23622D03*
X785039Y1547638D03*
X890217Y23622D03*
X1118760D03*
X1347303Y70866D03*
X1377559Y286220D03*
X1431457Y1604724D03*
X1575846Y23622D03*
X1766929Y333464D03*
X1778740Y765197D03*
X1795010Y23622D03*
G54D22*
X420661Y1119422D03*
X423141Y1113822D03*
Y1119422D03*
X418181Y1113822D03*
Y1119422D03*
X420661Y1113822D03*
X455269Y1119422D03*
X450309Y1113822D03*
Y1119422D03*
X452789Y1113822D03*
Y1119422D03*
X455269Y1113822D03*
X488728Y1119422D03*
X483768Y1113822D03*
X486248D03*
Y1119422D03*
X483768D03*
X488728Y1113822D03*
X518376D03*
Y1119422D03*
X520856Y1113822D03*
Y1119422D03*
X515896Y1113822D03*
Y1119422D03*
X526699Y706388D03*
X1332355Y1113822D03*
Y1119422D03*
X1334835Y1113822D03*
Y1119422D03*
X1337315Y1113822D03*
Y1119422D03*
X1366963D03*
Y1113822D03*
X1364483Y1119422D03*
Y1113822D03*
X1369443Y1119422D03*
Y1113822D03*
X1397942Y1119422D03*
X1400422D03*
Y1113822D03*
X1397942D03*
X1402902Y1119422D03*
Y1113822D03*
X1432550Y1119422D03*
Y1113822D03*
X1430070Y1119422D03*
Y1113822D03*
X1435030Y1119422D03*
Y1113822D03*
G54D32*
G01X883100Y843718D02*
X892393D01*
G01X928612Y864189D02*
X927044Y865757D01*
X924359D01*
X923884Y866232D01*
Y874389D01*
X923055Y875218D01*
X911823D01*
X911280Y875761D01*
Y880680D01*
G01X917598Y881100D02*
Y878352D01*
X919163Y876787D01*
G01X927027Y887700D02*
Y882437D01*
X926101Y881511D01*
X923887D01*
X922313Y879937D01*
G01X920728Y887700D02*
Y881502D01*
X919163Y879937D01*
G01X925462D02*
X926577Y880399D01*
X927696Y881518D01*
X929800D01*
X930300Y882018D01*
G01X923878Y887700D02*
Y884651D01*
X922313Y883086D01*
G01X1331019Y861921D02*
Y859853D01*
X1332654Y858218D01*
G01X1327869Y861921D02*
Y859853D01*
X1329504Y858218D01*
G01X1323205D02*
X1321586Y859837D01*
X1319389D01*
G01X1320055Y858218D02*
X1318490Y856653D01*
X1312890D01*
G01X1313000Y834605D02*
X1320905D01*
X1321600Y835300D01*
Y837715D01*
X1323204Y839319D01*
G01X1329504Y870814D02*
X1327993Y869303D01*
X1319042D01*
G01X1332654Y870814D02*
X1331089Y872379D01*
X1319121D01*
G01X1326355Y873964D02*
X1324789Y875530D01*
X1319202D01*
G01X1326355Y877114D02*
X1324790Y878679D01*
X1319229D01*
G01X1351550Y886562D02*
X1351066Y885394D01*
X1348513Y882841D01*
Y877428D01*
X1346626Y875541D01*
X1335160D01*
X1334229Y876472D01*
Y884315D01*
X1333564Y884980D01*
X1331860D01*
X1331069Y885771D01*
Y887211D01*
X1330153Y888127D01*
X1328875D01*
X1327920Y889082D01*
Y893436D01*
G01X1326355Y842470D02*
X1324770Y840885D01*
Y835500D01*
G01X1313000Y837739D02*
X1318474D01*
X1320055Y839320D01*
G01X1329504Y851918D02*
X1327967Y850381D01*
X1319282D01*
G01X1319228Y853429D02*
X1321694D01*
X1323205Y851918D01*
G01X1319200Y844101D02*
X1327045D01*
X1327957Y845013D01*
Y846638D01*
X1328576Y847257D01*
X1331142D01*
X1332654Y848769D01*
G01X1329504D02*
X1328021Y848154D01*
X1327019Y847152D01*
X1319119D01*
G01X1331069Y893462D02*
Y891277D01*
X1329504Y889712D01*
G01Y845619D02*
Y845004D01*
X1327939Y843439D01*
Y835500D01*
G01X1332654Y845619D02*
X1331089Y844054D01*
Y835500D01*
G01X1351550Y883413D02*
X1349897Y881760D01*
Y874455D01*
X1347830Y872388D01*
X1334771D01*
X1334231Y872928D01*
Y874689D01*
X1333385Y875535D01*
X1331932D01*
X1331086Y876381D01*
Y884273D01*
X1330380Y884979D01*
X1325094D01*
X1324775Y885298D01*
Y893449D01*
G01X1338953Y845619D02*
X1340518Y844054D01*
Y835500D01*
G01X1334219D02*
Y840905D01*
X1332654Y842470D01*
G01X1337387Y835500D02*
Y847185D01*
X1335803Y848769D01*
G01X1342103D02*
X1343668Y847204D01*
Y835500D01*
G01X1334219Y893516D02*
Y888127D01*
X1332654Y886562D01*
G01X1338953Y880263D02*
X1339769D01*
X1340523Y881017D01*
Y887383D01*
X1339769Y888137D01*
X1338268D01*
X1337428Y888977D01*
Y893597D01*
G01X1338953Y848769D02*
X1340524Y850340D01*
X1345950D01*
G01X1351070Y847190D02*
X1353128D01*
X1354699Y845619D01*
G01X1353115Y834830D02*
Y843265D01*
X1353870Y844020D01*
X1356299D01*
X1357849Y842470D01*
G01X1346139Y878688D02*
X1338165D01*
X1337375Y879478D01*
Y881841D01*
X1335803Y883413D01*
G01X1345709Y884994D02*
X1343684D01*
X1342103Y883413D01*
G01X1340532Y893355D02*
Y891293D01*
X1338952Y889713D01*
G01X1343673Y893355D02*
Y888132D01*
X1342103Y886562D01*
G01X1354699Y842470D02*
X1356264Y840905D01*
Y834860D01*
G01X1364148Y833021D02*
X1365733Y831436D01*
X1371664D01*
G01X1374314Y834586D02*
X1368882D01*
X1367298Y836170D01*
G01Y839320D02*
X1368878Y837740D01*
X1374360D01*
X1375162Y836938D01*
Y835458D01*
G01X1364148Y848769D02*
X1365687Y847230D01*
X1377430D01*
X1378312Y846348D01*
Y838608D01*
G01X1367298Y870814D02*
X1368883Y872399D01*
X1383779D01*
G01X1367298Y880263D02*
X1368883Y881848D01*
X1384256D01*
G01X1357849Y883413D02*
X1359430Y884994D01*
Y893910D01*
G01X1362564Y893880D02*
Y888127D01*
X1360999Y886562D01*
G01X1365713Y893491D02*
Y884978D01*
X1364148Y883413D01*
G01X1367298Y886562D02*
X1368863Y888127D01*
Y894770D01*
G01X1370447Y839320D02*
X1372037Y840910D01*
X1374170D01*
X1375170Y839910D01*
Y838560D01*
X1375990Y837740D01*
X1377560D01*
G01X1383935Y840905D02*
X1381995D01*
X1381500Y841400D01*
Y844015D01*
X1379896Y845619D01*
G01X1376747Y858218D02*
X1378275Y856690D01*
X1381560D01*
G01X1384080Y859802D02*
X1375162D01*
X1373597Y861367D01*
G01X1384295Y875549D02*
X1375182D01*
X1373598Y873965D01*
G01X1383939Y878679D02*
X1378312D01*
X1376747Y877114D01*
G01X1383710Y869231D02*
X1375163D01*
X1373597Y867665D01*
G01X1384148Y884978D02*
X1375162D01*
X1373597Y883413D01*
G54D23*
X843012Y1592787D03*
Y1602787D03*
Y1612787D03*
Y1622787D03*
X853012Y1592787D03*
Y1602787D03*
Y1612787D03*
Y1622787D03*
X878012Y1592787D03*
Y1602787D03*
Y1612787D03*
Y1622787D03*
X888012Y1592787D03*
Y1602787D03*
Y1612787D03*
Y1622787D03*
X913012Y1592787D03*
Y1602787D03*
Y1612787D03*
Y1622787D03*
X923012Y1592787D03*
Y1602787D03*
Y1612787D03*
Y1622787D03*
X948012Y1592787D03*
Y1602787D03*
Y1612787D03*
Y1622787D03*
X958012Y1592787D03*
Y1602787D03*
Y1612787D03*
Y1622787D03*
X983012Y1592787D03*
X993012D03*
X983012Y1602787D03*
Y1612787D03*
X993012Y1602787D03*
Y1612787D03*
X983012Y1622787D03*
X993012D03*
X1018012Y1592787D03*
X1028012D03*
X1018012Y1602787D03*
Y1612787D03*
X1028012Y1602787D03*
Y1612787D03*
X1018012Y1622787D03*
X1028012D03*
G54D14*
X56248Y1806941D03*
Y1796941D03*
X308348D03*
Y1806941D03*
X917073Y1786014D03*
Y1776014D03*
X1169123D03*
Y1786014D03*
G54D33*
G01X480711Y999941D02*
X476512D01*
X465754Y1010699D01*
Y1019662D01*
X435173Y1050243D01*
X429289D01*
X421307Y1058225D01*
Y1091649D01*
X414800Y1098156D01*
Y1102604D01*
X416988Y1104792D01*
G01X477857Y1004375D02*
X472253Y1009979D01*
Y1023602D01*
X466000Y1029855D01*
Y1034795D01*
X467810Y1036605D01*
Y1041821D01*
X444846Y1064785D01*
Y1092559D01*
X449116Y1096829D01*
Y1104792D01*
G01X467345Y996480D02*
X467545Y996280D01*
X482789D01*
X485839Y999330D01*
Y1027035D01*
X490025Y1031221D01*
Y1040372D01*
X478628Y1051769D01*
X474992D01*
X465520Y1061241D01*
Y1096012D01*
X471322Y1101814D01*
X479597D01*
X482575Y1104792D01*
G01X475018Y992568D02*
X485127D01*
X490966Y998407D01*
Y1010674D01*
X494962Y1014670D01*
Y1026953D01*
X518524Y1050515D01*
Y1093808D01*
X514703Y1097629D01*
Y1104792D01*
G01X937200Y841000D02*
Y843200D01*
X934400Y846000D01*
X932100D01*
X930900Y844800D01*
X925955D01*
X925462Y845293D01*
G01X942194Y891216D02*
Y889700D01*
X939296Y886802D01*
Y874963D01*
X938729Y874396D01*
G01X1394885Y999941D02*
X1390686D01*
X1379928Y1010699D01*
Y1019662D01*
X1349347Y1050243D01*
X1343463D01*
X1335481Y1058225D01*
Y1091649D01*
X1328974Y1098156D01*
Y1102604D01*
X1331162Y1104792D01*
G01X1392031Y1004375D02*
X1386427Y1009979D01*
Y1023602D01*
X1380174Y1029855D01*
Y1034795D01*
X1381984Y1036605D01*
Y1041821D01*
X1359020Y1064785D01*
Y1092559D01*
X1363290Y1096829D01*
Y1104792D01*
G01X1381519Y996280D02*
X1396963D01*
X1400013Y999330D01*
Y1027035D01*
X1404199Y1031221D01*
Y1040372D01*
X1392802Y1051769D01*
X1389166D01*
X1379694Y1061241D01*
Y1096012D01*
X1385496Y1101814D01*
X1393771D01*
X1396749Y1104792D01*
G01X1389192Y992568D02*
X1399301D01*
X1405140Y998407D01*
Y1010674D01*
X1409136Y1014670D01*
Y1026953D01*
X1432698Y1050515D01*
Y1093808D01*
X1428877Y1097629D01*
Y1104792D01*
G54D15*
X109882Y1504685D03*
Y1509804D03*
Y1607048D03*
Y1612166D03*
X127205Y1504685D03*
Y1509804D03*
X118543Y1509016D03*
Y1514134D03*
X127205Y1607048D03*
Y1612166D03*
X118543Y1611378D03*
Y1616496D03*
X144528Y1504685D03*
Y1509804D03*
X135866Y1509016D03*
Y1514134D03*
X144528Y1607048D03*
Y1612166D03*
X135866Y1611378D03*
Y1616496D03*
X161850Y1504685D03*
Y1509804D03*
X153189Y1509016D03*
Y1514134D03*
X161850Y1607048D03*
Y1612166D03*
X153189Y1611378D03*
Y1616496D03*
X170512Y1509016D03*
Y1514134D03*
Y1611378D03*
Y1616496D03*
X283110Y1458622D03*
X291771Y1462953D03*
X283110Y1463741D03*
X291771Y1468071D03*
X283110Y1576339D03*
X291771Y1580670D03*
X283110Y1581457D03*
X291771Y1585788D03*
X300433Y1458622D03*
X309094Y1462953D03*
X300433Y1463741D03*
X309094Y1468071D03*
X300433Y1576339D03*
X309094Y1580670D03*
X300433Y1581457D03*
X309094Y1585788D03*
X317756Y1458622D03*
X326417Y1462953D03*
X317756Y1463741D03*
X326417Y1468071D03*
X317756Y1576339D03*
X326417Y1580670D03*
X317756Y1581457D03*
X326417Y1585788D03*
X335078Y1458622D03*
X343740Y1462953D03*
X335078Y1463741D03*
X343740Y1468071D03*
X335078Y1576339D03*
X343740Y1580670D03*
X335078Y1581457D03*
X343740Y1585788D03*
X352401Y1504685D03*
Y1509804D03*
X361063Y1509016D03*
Y1514134D03*
X456339Y1473977D03*
Y1479095D03*
Y1560985D03*
Y1566103D03*
X473662Y1473977D03*
Y1479095D03*
X465000Y1478308D03*
Y1483426D03*
X473662Y1560985D03*
Y1566103D03*
X465000Y1565315D03*
Y1570434D03*
X490985Y1473977D03*
Y1479095D03*
X482323Y1478308D03*
Y1483426D03*
X490985Y1560985D03*
Y1566103D03*
X482323Y1565315D03*
Y1570434D03*
X499646Y1478308D03*
Y1483426D03*
Y1565315D03*
Y1570434D03*
X508307Y1473977D03*
X516969Y1478308D03*
X508307Y1479095D03*
X516969Y1483426D03*
X508307Y1560985D03*
X516969Y1565315D03*
X508307Y1566103D03*
X516969Y1570434D03*
X629567Y1489331D03*
Y1494449D03*
Y1591693D03*
Y1596811D03*
X646890Y1489331D03*
Y1494449D03*
X638228Y1493662D03*
Y1498780D03*
X646890Y1591693D03*
X638228Y1596024D03*
X646890Y1596811D03*
X638228Y1601142D03*
X664213Y1489331D03*
Y1494449D03*
X655551Y1493662D03*
Y1498780D03*
X664213Y1591693D03*
X655551Y1596024D03*
X664213Y1596811D03*
X655551Y1601142D03*
X681535Y1489331D03*
Y1494449D03*
X672874Y1493662D03*
Y1498780D03*
X681535Y1591693D03*
X672874Y1596024D03*
X681535Y1596811D03*
X672874Y1601142D03*
X690197Y1493662D03*
Y1498780D03*
Y1596024D03*
Y1601142D03*
X1131850Y1504685D03*
X1140511Y1509016D03*
X1131850Y1509804D03*
X1140511Y1514134D03*
X1131850Y1607048D03*
X1140511Y1611378D03*
X1131850Y1612166D03*
X1140511Y1616496D03*
X1149173Y1504685D03*
Y1509804D03*
Y1607048D03*
Y1612166D03*
X1166496Y1504685D03*
Y1509804D03*
X1157834Y1509016D03*
Y1514134D03*
X1166496Y1607048D03*
Y1612166D03*
X1157834Y1611378D03*
Y1616496D03*
X1183818Y1504685D03*
Y1509804D03*
X1175157Y1509016D03*
Y1514134D03*
X1183818Y1607048D03*
Y1612166D03*
X1175157Y1611378D03*
Y1616496D03*
X1192480Y1509016D03*
Y1514134D03*
Y1611378D03*
Y1616496D03*
X1305079Y1458622D03*
X1313740Y1462953D03*
X1305079Y1463741D03*
X1313740Y1468071D03*
X1305079Y1576339D03*
X1313740Y1580670D03*
X1305079Y1581457D03*
X1313740Y1585788D03*
X1322402Y1458622D03*
X1331063Y1462953D03*
X1322402Y1463741D03*
X1331063Y1468071D03*
X1322402Y1576339D03*
X1331063Y1580670D03*
X1322402Y1581457D03*
X1331063Y1585788D03*
X1339725Y1458622D03*
X1348386Y1462953D03*
X1339725Y1463741D03*
X1348386Y1468071D03*
X1339725Y1576339D03*
X1348386Y1580670D03*
X1339725Y1581457D03*
X1348386Y1585788D03*
X1357047Y1458622D03*
X1365709Y1462953D03*
X1357047Y1463741D03*
X1365709Y1468071D03*
X1357047Y1576339D03*
X1365709Y1580670D03*
X1357047Y1581457D03*
X1365709Y1585788D03*
X1478307Y1473977D03*
Y1479095D03*
Y1560985D03*
Y1566103D03*
X1495630Y1473977D03*
Y1479095D03*
X1486968Y1478308D03*
Y1483426D03*
X1495630Y1560985D03*
Y1566103D03*
X1486968Y1565315D03*
Y1570434D03*
X1512953Y1473977D03*
Y1479095D03*
X1504291Y1478308D03*
Y1483426D03*
X1512953Y1560985D03*
Y1566103D03*
X1504291Y1565315D03*
Y1570434D03*
X1530275Y1473977D03*
Y1479095D03*
X1521614Y1478308D03*
Y1483426D03*
X1530275Y1560985D03*
Y1566103D03*
X1521614Y1565315D03*
Y1570434D03*
X1538937Y1478308D03*
Y1483426D03*
Y1565315D03*
Y1570434D03*
X1651535Y1489331D03*
X1660196Y1493662D03*
X1651535Y1494449D03*
X1660196Y1498780D03*
X1651535Y1591693D03*
X1660196Y1596024D03*
X1651535Y1596811D03*
X1660196Y1601142D03*
X1668858Y1489331D03*
Y1494449D03*
Y1591693D03*
Y1596811D03*
X1686181Y1489331D03*
Y1494449D03*
X1677519Y1493662D03*
Y1498780D03*
X1686181Y1591693D03*
X1677519Y1596024D03*
X1686181Y1596811D03*
X1677519Y1601142D03*
X1703503Y1489331D03*
Y1494449D03*
X1694842Y1493662D03*
Y1498780D03*
X1703503Y1591693D03*
X1694842Y1596024D03*
X1703503Y1596811D03*
X1694842Y1601142D03*
X1712165Y1493662D03*
Y1498780D03*
Y1596024D03*
Y1601142D03*
G54D24*
X895384Y228740D03*
Y276772D03*
X923336Y226772D03*
Y278740D03*
G54D34*
G01X142988Y1184976D02*
X143100D01*
X143280Y1185156D01*
X153915D01*
X154804Y1186045D01*
Y1186951D01*
X155254Y1187401D01*
X156299D01*
G01X142988Y1186086D02*
X143100D01*
X143280Y1185906D01*
X153604D01*
X154054Y1186356D01*
Y1186951D01*
X153604Y1187401D01*
X152559D01*
G01X140000Y1189826D02*
X140112D01*
X140292Y1189646D01*
X146123D01*
X146573Y1190096D01*
Y1190691D01*
X146123Y1191141D01*
X145078D01*
G01X140000Y1188716D02*
X140112D01*
X140292Y1188896D01*
X146434D01*
X147323Y1189785D01*
Y1190691D01*
X147773Y1191141D01*
X148818D01*
G01X140000Y1192456D02*
X140112D01*
X140292Y1192636D01*
X153915D01*
X154804Y1193525D01*
Y1194431D01*
X155254Y1194881D01*
X156299D01*
G01X140000Y1193566D02*
X140112D01*
X140292Y1193386D01*
X153604D01*
X154054Y1193836D01*
Y1194431D01*
X153604Y1194881D01*
X152559D01*
G01X140000Y1196196D02*
X140112D01*
X140292Y1196376D01*
X146434D01*
X147323Y1197265D01*
Y1198171D01*
X147773Y1198621D01*
X148818D01*
G01X140000Y1197306D02*
X140112D01*
X140292Y1197126D01*
X146123D01*
X146573Y1197576D01*
Y1198171D01*
X146123Y1198621D01*
X145078D01*
G01X140000Y1199937D02*
X140112D01*
X140292Y1200117D01*
X153915D01*
X154804Y1201006D01*
Y1201912D01*
X155254Y1202362D01*
X156299D01*
G01X140000Y1201047D02*
X140112D01*
X140292Y1200867D01*
X153604D01*
X154054Y1201317D01*
Y1201912D01*
X153604Y1202362D01*
X152559D01*
G01X140000Y1203677D02*
X140112D01*
X140292Y1203857D01*
X146434D01*
X147323Y1204746D01*
Y1205652D01*
X147773Y1206102D01*
X148818D01*
G01X140000Y1211157D02*
X140112D01*
X140292Y1211337D01*
X146434D01*
X147323Y1212226D01*
Y1213132D01*
X147773Y1213582D01*
X148818D01*
G01X140000Y1212267D02*
X140112D01*
X140292Y1212087D01*
X146123D01*
X146573Y1212537D01*
Y1213132D01*
X146123Y1213582D01*
X145078D01*
G01X140000Y1204787D02*
X140112D01*
X140292Y1204607D01*
X146123D01*
X146573Y1205057D01*
Y1205652D01*
X146123Y1206102D01*
X145078D01*
G01X140000Y1207417D02*
X140112D01*
X140292Y1207597D01*
X153915D01*
X154804Y1208486D01*
Y1209392D01*
X155254Y1209842D01*
X156299D01*
G01X140000Y1208527D02*
X140112D01*
X140292Y1208347D01*
X153604D01*
X154054Y1208797D01*
Y1209392D01*
X153604Y1209842D01*
X152559D01*
G01X233527Y1069788D02*
Y1069900D01*
X233347Y1070080D01*
Y1076283D01*
X233754Y1076690D01*
X234391D01*
X234841Y1076240D01*
Y1075195D01*
G01X232417Y1069788D02*
Y1069900D01*
X232597Y1070080D01*
Y1076594D01*
X233443Y1077440D01*
X234391D01*
X234841Y1077890D01*
Y1078935D01*
G01X236157Y1069976D02*
Y1070088D01*
X236337Y1070268D01*
Y1084075D01*
X237183Y1084921D01*
X238131D01*
X238581Y1085371D01*
Y1086416D01*
G01Y1082676D02*
Y1083721D01*
X238131Y1084171D01*
X237494D01*
X237087Y1083764D01*
Y1070268D01*
X237267Y1070088D01*
Y1069976D01*
G01X156299Y1217322D02*
X155254D01*
X154804Y1216872D01*
Y1215966D01*
X153915Y1215077D01*
X139780D01*
X139600Y1214897D01*
X139488D01*
G01X152559Y1217322D02*
X153604D01*
X154054Y1216872D01*
Y1216277D01*
X153604Y1215827D01*
X139780D01*
X139600Y1216007D01*
X139488D01*
G01X239897Y1069976D02*
Y1070088D01*
X240077Y1070268D01*
Y1076595D01*
X240923Y1077441D01*
X241871D01*
X242321Y1077891D01*
Y1078936D01*
G01X241007Y1069976D02*
Y1070088D01*
X240827Y1070268D01*
Y1076284D01*
X241234Y1076691D01*
X241871D01*
X242321Y1076241D01*
Y1075196D01*
G01X244747Y1069976D02*
Y1070088D01*
X244567Y1070268D01*
Y1083765D01*
X244974Y1084172D01*
X245611D01*
X246061Y1083722D01*
Y1082677D01*
G01X243637Y1069976D02*
Y1070088D01*
X243817Y1070268D01*
Y1084076D01*
X244663Y1084922D01*
X245611D01*
X246061Y1085372D01*
Y1086417D01*
G01X247378Y1069976D02*
Y1070088D01*
X247558Y1070268D01*
Y1076595D01*
X248404Y1077441D01*
X249352D01*
X249802Y1077891D01*
Y1078936D01*
G01X248488Y1069976D02*
Y1070088D01*
X248308Y1070268D01*
Y1076284D01*
X248715Y1076691D01*
X249352D01*
X249802Y1076241D01*
Y1075196D01*
G01X252228Y1069976D02*
Y1070088D01*
X252048Y1070268D01*
Y1083764D01*
X252455Y1084171D01*
X253092D01*
X253542Y1083721D01*
Y1082676D01*
G01X251118Y1069976D02*
Y1070088D01*
X251298Y1070268D01*
Y1084075D01*
X252144Y1084921D01*
X253092D01*
X253542Y1085371D01*
Y1086416D01*
G01X145078Y1221062D02*
X146123D01*
X146573Y1221512D01*
Y1222107D01*
X146122Y1222557D01*
X142482D01*
X140678Y1224361D01*
X140426Y1224360D01*
X140347Y1224439D01*
G01X141132Y1225224D02*
X141211Y1225145D01*
Y1224889D01*
X142793Y1223307D01*
X146434D01*
X147323Y1222418D01*
Y1221512D01*
X147773Y1221062D01*
X148818D01*
G01X147503Y1256412D02*
Y1256300D01*
X147323Y1256120D01*
Y1247693D01*
X147773Y1247243D01*
X148818D01*
G01X146393Y1256412D02*
Y1256300D01*
X146573Y1256120D01*
Y1247693D01*
X146123Y1247243D01*
X145078D01*
G01X254858Y1069976D02*
Y1070088D01*
X255038Y1070268D01*
Y1076595D01*
X255884Y1077441D01*
X256832D01*
X257282Y1077891D01*
Y1078936D01*
G01X255968Y1069976D02*
Y1070088D01*
X255788Y1070268D01*
Y1076284D01*
X256195Y1076691D01*
X256832D01*
X257282Y1076241D01*
Y1075196D01*
G01X258598Y1069976D02*
Y1070088D01*
X258778Y1070268D01*
Y1084076D01*
X259624Y1084922D01*
X260572D01*
X261022Y1085372D01*
Y1086417D01*
G01X259708Y1069976D02*
Y1070088D01*
X259528Y1070268D01*
Y1083765D01*
X259935Y1084172D01*
X260572D01*
X261022Y1083722D01*
Y1082677D01*
G01X262338Y1069976D02*
Y1070088D01*
X262518Y1070268D01*
Y1076595D01*
X263364Y1077441D01*
X264312D01*
X264762Y1077891D01*
Y1078936D01*
G01X263448Y1069976D02*
Y1070088D01*
X263268Y1070268D01*
Y1076284D01*
X263675Y1076691D01*
X264312D01*
X264762Y1076241D01*
Y1075196D01*
G01X266078Y1069976D02*
Y1070088D01*
X266258Y1070268D01*
Y1084075D01*
X267104Y1084921D01*
X268052D01*
X268502Y1085371D01*
Y1086416D01*
G01X150134Y1259824D02*
Y1259712D01*
X150314Y1259532D01*
Y1253368D01*
X151203Y1252479D01*
X152109D01*
X152559Y1252029D01*
Y1250984D01*
G01X151244Y1259824D02*
Y1259712D01*
X151064Y1259532D01*
Y1253679D01*
X151514Y1253229D01*
X152109D01*
X152559Y1253679D01*
Y1254724D01*
G01X153874Y1259824D02*
Y1259712D01*
X154054Y1259532D01*
Y1245887D01*
X154943Y1244998D01*
X155849D01*
X156299Y1244548D01*
Y1243503D01*
G01X154984Y1259824D02*
Y1259712D01*
X154804Y1259532D01*
Y1246198D01*
X155254Y1245748D01*
X155849D01*
X156299Y1246198D01*
Y1247243D01*
G01X267188Y1069976D02*
Y1070088D01*
X267008Y1070268D01*
Y1083764D01*
X267415Y1084171D01*
X268052D01*
X268502Y1083721D01*
Y1082676D01*
G01X274668Y1069976D02*
Y1070088D01*
X274488Y1070268D01*
Y1083765D01*
X274895Y1084172D01*
X275532D01*
X275982Y1083722D01*
Y1082677D01*
G01X273558Y1069976D02*
Y1070088D01*
X273738Y1070268D01*
Y1084076D01*
X274584Y1084922D01*
X275532D01*
X275982Y1085372D01*
Y1086417D01*
G01X269819Y1069976D02*
Y1070088D01*
X269999Y1070268D01*
Y1076595D01*
X270845Y1077441D01*
X271793D01*
X272243Y1077891D01*
Y1078936D01*
G01X270929Y1069976D02*
Y1070088D01*
X270749Y1070268D01*
Y1076284D01*
X271156Y1076691D01*
X271793D01*
X272243Y1076241D01*
Y1075196D01*
G01X282149Y1069976D02*
Y1070088D01*
X281969Y1070268D01*
Y1083764D01*
X282376Y1084171D01*
X283013D01*
X283463Y1083721D01*
Y1082676D01*
G01X278409Y1069976D02*
Y1070088D01*
X278229Y1070268D01*
Y1076284D01*
X278636Y1076691D01*
X279273D01*
X279723Y1076241D01*
Y1075196D01*
G01X277299Y1069976D02*
Y1070088D01*
X277479Y1070268D01*
Y1076595D01*
X278325Y1077441D01*
X279273D01*
X279723Y1077891D01*
Y1078936D01*
G01X281039Y1069976D02*
Y1070088D01*
X281219Y1070268D01*
Y1084075D01*
X282065Y1084921D01*
X283013D01*
X283463Y1085371D01*
Y1086416D01*
G01X158724Y1259824D02*
Y1259712D01*
X158544Y1259532D01*
Y1253679D01*
X158994Y1253229D01*
X159589D01*
X160039Y1253679D01*
Y1254724D01*
G01X161354Y1259824D02*
Y1259712D01*
X161534Y1259532D01*
Y1245887D01*
X162423Y1244998D01*
X163329D01*
X163779Y1244548D01*
Y1243503D01*
G01X157614Y1259824D02*
Y1259712D01*
X157794Y1259532D01*
Y1253368D01*
X158683Y1252479D01*
X159589D01*
X160039Y1252029D01*
Y1250984D01*
G01X162464Y1259824D02*
Y1259712D01*
X162284Y1259532D01*
Y1246198D01*
X162734Y1245748D01*
X163329D01*
X163779Y1246198D01*
Y1247243D01*
G01X165094Y1259824D02*
Y1259712D01*
X165274Y1259532D01*
Y1253368D01*
X166163Y1252479D01*
X167069D01*
X167519Y1252029D01*
Y1250984D01*
G01X288519Y1069976D02*
Y1070088D01*
X288699Y1070268D01*
Y1084076D01*
X289545Y1084922D01*
X290493D01*
X290943Y1085372D01*
Y1086417D01*
G01X284779Y1069000D02*
Y1069112D01*
X284959Y1069292D01*
Y1076595D01*
X285805Y1077441D01*
X286753D01*
X287203Y1077891D01*
Y1078936D01*
G01X289629Y1069976D02*
Y1070088D01*
X289449Y1070268D01*
Y1083765D01*
X289856Y1084172D01*
X290493D01*
X290943Y1083722D01*
Y1082677D01*
G01X285889Y1069000D02*
Y1069112D01*
X285709Y1069292D01*
Y1076284D01*
X286116Y1076691D01*
X286753D01*
X287203Y1076241D01*
Y1075196D01*
G01X166204Y1259824D02*
Y1259712D01*
X166024Y1259532D01*
Y1253679D01*
X166474Y1253229D01*
X167069D01*
X167519Y1253679D01*
Y1254724D01*
G01X177425Y1259824D02*
Y1259712D01*
X177245Y1259532D01*
Y1246198D01*
X177695Y1245748D01*
X178290D01*
X178740Y1246198D01*
Y1247243D01*
G01X181165Y1259824D02*
Y1259712D01*
X180985Y1259532D01*
Y1253679D01*
X181435Y1253229D01*
X182030D01*
X182480Y1253679D01*
Y1254724D01*
G01X180055Y1259824D02*
Y1259712D01*
X180235Y1259532D01*
Y1253368D01*
X181124Y1252479D01*
X182030D01*
X182480Y1252029D01*
Y1250984D01*
G01X169944Y1259824D02*
Y1259712D01*
X169764Y1259532D01*
Y1246198D01*
X170214Y1245748D01*
X170809D01*
X171259Y1246198D01*
Y1247243D01*
G01X172574Y1259824D02*
Y1259712D01*
X172754Y1259532D01*
Y1253368D01*
X173643Y1252479D01*
X174549D01*
X174999Y1252029D01*
Y1250984D01*
G01X168834Y1259824D02*
Y1259712D01*
X169014Y1259532D01*
Y1245887D01*
X169903Y1244998D01*
X170809D01*
X171259Y1244548D01*
Y1243503D01*
G01X173684Y1259824D02*
Y1259712D01*
X173504Y1259532D01*
Y1253679D01*
X173954Y1253229D01*
X174549D01*
X174999Y1253679D01*
Y1254724D01*
G01X176315Y1259824D02*
Y1259712D01*
X176495Y1259532D01*
Y1245887D01*
X177384Y1244998D01*
X178290D01*
X178740Y1244548D01*
Y1243503D01*
G01X196125Y1259824D02*
Y1259712D01*
X195945Y1259532D01*
Y1253679D01*
X196395Y1253229D01*
X196990D01*
X197440Y1253679D01*
Y1254724D01*
G01X195015Y1259824D02*
Y1259712D01*
X195195Y1259532D01*
Y1253368D01*
X196084Y1252479D01*
X196990D01*
X197440Y1252029D01*
Y1250984D01*
G01X192385Y1259824D02*
Y1259712D01*
X192205Y1259532D01*
Y1246198D01*
X192655Y1245748D01*
X193250D01*
X193700Y1246198D01*
Y1247243D01*
G01X191275Y1259824D02*
Y1259712D01*
X191455Y1259532D01*
Y1245887D01*
X192344Y1244998D01*
X193250D01*
X193700Y1244548D01*
Y1243503D01*
G01X188645Y1259824D02*
Y1259712D01*
X188465Y1259532D01*
Y1253679D01*
X188915Y1253229D01*
X189510D01*
X189960Y1253679D01*
Y1254724D01*
G01X187535Y1259824D02*
Y1259712D01*
X187715Y1259532D01*
Y1253368D01*
X188604Y1252479D01*
X189510D01*
X189960Y1252029D01*
Y1250984D01*
G01X184905Y1259824D02*
Y1259712D01*
X184725Y1259532D01*
Y1246198D01*
X185175Y1245748D01*
X185770D01*
X186220Y1246198D01*
Y1247243D01*
G01X183795Y1259824D02*
Y1259712D01*
X183975Y1259532D01*
Y1245887D01*
X184864Y1244998D01*
X185770D01*
X186220Y1244548D01*
Y1243503D01*
G01X324606Y1123818D02*
X323561D01*
X323111Y1123368D01*
Y1122731D01*
X323519Y1122323D01*
X330220D01*
X330400Y1122503D01*
X330512D01*
G01X324606Y1131299D02*
X323561D01*
X323111Y1130849D01*
Y1130212D01*
X323519Y1129804D01*
X330220D01*
X330400Y1129984D01*
X330512D01*
G01X320866Y1131299D02*
X321911D01*
X322361Y1130849D01*
Y1129901D01*
X323208Y1129054D01*
X330220D01*
X330400Y1128874D01*
X330512D01*
G01X320866Y1123818D02*
X321911D01*
X322361Y1123368D01*
Y1122420D01*
X323208Y1121573D01*
X330220D01*
X330400Y1121393D01*
X330512D01*
G01X324606Y1116338D02*
X323561D01*
X323111Y1115888D01*
Y1115251D01*
X323519Y1114843D01*
X330092D01*
X330272Y1115023D01*
X330384D01*
G01X320866Y1116338D02*
X321911D01*
X322361Y1115888D01*
Y1114940D01*
X323208Y1114093D01*
X330092D01*
X330272Y1113913D01*
X330384D01*
G01X324606Y1108858D02*
X323561D01*
X323111Y1108408D01*
Y1107771D01*
X323519Y1107363D01*
X330220D01*
X330400Y1107543D01*
X330512D01*
G01Y1106433D02*
X330400D01*
X330220Y1106613D01*
X323208D01*
X322361Y1107460D01*
Y1108408D01*
X321911Y1108858D01*
X320866D01*
G01X314700Y1069976D02*
Y1070088D01*
X314880Y1070268D01*
Y1076595D01*
X315726Y1077441D01*
X316674D01*
X317124Y1077891D01*
Y1078936D01*
G01X315810Y1069976D02*
Y1070088D01*
X315630Y1070268D01*
Y1076284D01*
X316037Y1076691D01*
X316674D01*
X317124Y1076241D01*
Y1075196D01*
G01X307220Y1069976D02*
Y1070088D01*
X307400Y1070268D01*
Y1076595D01*
X308246Y1077441D01*
X309194D01*
X309644Y1077891D01*
Y1078936D01*
G01X308330Y1069976D02*
Y1070088D01*
X308150Y1070268D01*
Y1076284D01*
X308557Y1076691D01*
X309194D01*
X309644Y1076241D01*
Y1075196D01*
G01X299740Y1069976D02*
Y1070088D01*
X299920Y1070268D01*
Y1076595D01*
X300766Y1077441D01*
X301714D01*
X302164Y1077891D01*
Y1078936D01*
G01X300850Y1069976D02*
Y1070088D01*
X300670Y1070268D01*
Y1076284D01*
X301077Y1076691D01*
X301714D01*
X302164Y1076241D01*
Y1075196D01*
G01X293370Y1069976D02*
Y1070088D01*
X293190Y1070268D01*
Y1076284D01*
X293597Y1076691D01*
X294234D01*
X294684Y1076241D01*
Y1075196D01*
G01X292260Y1069976D02*
Y1070088D01*
X292440Y1070268D01*
Y1076595D01*
X293286Y1077441D01*
X294234D01*
X294684Y1077891D01*
Y1078936D01*
G01X262338Y1259824D02*
Y1259712D01*
X262518Y1259532D01*
Y1253368D01*
X263407Y1252479D01*
X264313D01*
X264763Y1252029D01*
Y1250984D01*
G01X258598Y1260112D02*
Y1260000D01*
X258778Y1259820D01*
Y1245887D01*
X259667Y1244998D01*
X260573D01*
X261023Y1244548D01*
Y1243503D01*
G01X259708Y1260112D02*
Y1260000D01*
X259528Y1259820D01*
Y1246198D01*
X259978Y1245748D01*
X260573D01*
X261023Y1246198D01*
Y1247243D01*
G01X317125Y1135039D02*
X316080D01*
X315630Y1134589D01*
Y1134066D01*
X316152Y1133544D01*
X330120D01*
X330300Y1133724D01*
X330412D01*
G01Y1132614D02*
X330300D01*
X330120Y1132794D01*
X315841D01*
X314880Y1133755D01*
Y1134589D01*
X314430Y1135039D01*
X313385D01*
G01X330412Y1125133D02*
X330300D01*
X330120Y1125313D01*
X315841D01*
X314880Y1126274D01*
Y1127108D01*
X314430Y1127558D01*
X313385D01*
G01X330412Y1126243D02*
X330300D01*
X330120Y1126063D01*
X316152D01*
X315630Y1126585D01*
Y1127108D01*
X316080Y1127558D01*
X317125D01*
G01X313385Y1120078D02*
X314430D01*
X314880Y1119628D01*
Y1118794D01*
X315841Y1117833D01*
X330120D01*
X330300Y1117653D01*
X330412D01*
G01X317125Y1120078D02*
X316080D01*
X315630Y1119628D01*
Y1119105D01*
X316152Y1118583D01*
X330120D01*
X330300Y1118763D01*
X330412D01*
G01X317125Y1112598D02*
X316080D01*
X315630Y1112148D01*
Y1111625D01*
X316152Y1111103D01*
X330120D01*
X330300Y1111283D01*
X330412D01*
G01X313385Y1112598D02*
X314430D01*
X314880Y1112148D01*
Y1111314D01*
X315841Y1110353D01*
X330120D01*
X330300Y1110173D01*
X330412D01*
G01X324606Y1082676D02*
X323561D01*
X323111Y1082226D01*
Y1077789D01*
X324120Y1076780D01*
Y1075903D01*
X324300Y1075723D01*
Y1075611D01*
G01X320866Y1082676D02*
X321911D01*
X322361Y1082226D01*
Y1077478D01*
X323370Y1076469D01*
Y1075903D01*
X323190Y1075723D01*
Y1075611D01*
G01X312070Y1069976D02*
Y1070088D01*
X311890Y1070268D01*
Y1083765D01*
X312297Y1084172D01*
X312934D01*
X313384Y1083722D01*
Y1082677D01*
G01X310960Y1069976D02*
Y1070088D01*
X311140Y1070268D01*
Y1084076D01*
X311986Y1084922D01*
X312934D01*
X313384Y1085372D01*
Y1086417D01*
G01X304590Y1069976D02*
Y1070088D01*
X304410Y1070268D01*
Y1083765D01*
X304817Y1084172D01*
X305454D01*
X305904Y1083722D01*
Y1082677D01*
G01X303480Y1069976D02*
Y1070088D01*
X303660Y1070268D01*
Y1084076D01*
X304506Y1084922D01*
X305454D01*
X305904Y1085372D01*
Y1086417D01*
G01X297110Y1069976D02*
Y1070088D01*
X296930Y1070268D01*
Y1083764D01*
X297337Y1084171D01*
X297974D01*
X298424Y1083721D01*
Y1082676D01*
G01X296000Y1069976D02*
Y1070088D01*
X296180Y1070268D01*
Y1084075D01*
X297026Y1084921D01*
X297974D01*
X298424Y1085371D01*
Y1086416D01*
G01X263448Y1259824D02*
Y1259712D01*
X263268Y1259532D01*
Y1253679D01*
X263718Y1253229D01*
X264313D01*
X264763Y1253679D01*
Y1254724D01*
G01X266078Y1259824D02*
Y1259712D01*
X266258Y1259532D01*
Y1245887D01*
X267147Y1244998D01*
X268053D01*
X268503Y1244548D01*
Y1243503D01*
G01X267188Y1259824D02*
Y1259712D01*
X267008Y1259532D01*
Y1246198D01*
X267458Y1245748D01*
X268053D01*
X268503Y1246198D01*
Y1247243D01*
G01X270929Y1259824D02*
Y1259712D01*
X270749Y1259532D01*
Y1253679D01*
X271199Y1253229D01*
X271794D01*
X272244Y1253679D01*
Y1254724D01*
G01X269819Y1259824D02*
Y1259712D01*
X269999Y1259532D01*
Y1253368D01*
X270888Y1252479D01*
X271794D01*
X272244Y1252029D01*
Y1250984D01*
G01X273559Y1259824D02*
Y1259712D01*
X273739Y1259532D01*
Y1245887D01*
X274628Y1244998D01*
X275534D01*
X275984Y1244548D01*
Y1243503D01*
G01X274669Y1259824D02*
Y1259712D01*
X274489Y1259532D01*
Y1246198D01*
X274939Y1245748D01*
X275534D01*
X275984Y1246198D01*
Y1247243D01*
G01X277299Y1259824D02*
Y1259712D01*
X277479Y1259532D01*
Y1253368D01*
X278368Y1252479D01*
X279274D01*
X279724Y1252029D01*
Y1250984D01*
G01X278409Y1259824D02*
Y1259712D01*
X278229Y1259532D01*
Y1253679D01*
X278679Y1253229D01*
X279274D01*
X279724Y1253679D01*
Y1254724D01*
G01X285889Y1259812D02*
Y1259700D01*
X285709Y1259520D01*
Y1253679D01*
X286159Y1253229D01*
X286754D01*
X287204Y1253679D01*
Y1254724D01*
G01X281039Y1259824D02*
Y1259712D01*
X281219Y1259532D01*
Y1245887D01*
X282108Y1244998D01*
X283014D01*
X283464Y1244548D01*
Y1243503D01*
G01X282149Y1259824D02*
Y1259712D01*
X281969Y1259532D01*
Y1246198D01*
X282419Y1245748D01*
X283014D01*
X283464Y1246198D01*
Y1247243D01*
G01X284779Y1259812D02*
Y1259700D01*
X284959Y1259520D01*
Y1253368D01*
X285848Y1252479D01*
X286754D01*
X287204Y1252029D01*
Y1250984D01*
G01X658268Y1247243D02*
Y1246198D01*
X657818Y1245748D01*
X657223D01*
X656773Y1246198D01*
Y1259331D01*
X655454Y1260650D01*
X653280D01*
X653100Y1260830D01*
X652988D01*
G01X658268Y1243503D02*
Y1244548D01*
X657818Y1244998D01*
X656912D01*
X656023Y1245887D01*
Y1259020D01*
X655143Y1259900D01*
X653280D01*
X653100Y1259720D01*
X652988D01*
G01X685764Y1259495D02*
Y1259383D01*
X685944Y1259203D01*
Y1245887D01*
X686833Y1244998D01*
X687739D01*
X688189Y1244548D01*
Y1243503D01*
G01X686874Y1259495D02*
Y1259383D01*
X686694Y1259203D01*
Y1246198D01*
X687144Y1245748D01*
X687739D01*
X688189Y1246198D01*
Y1247243D01*
G01X662008Y1254724D02*
Y1253679D01*
X661558Y1253229D01*
X660963D01*
X660513Y1253679D01*
Y1259083D01*
X660693Y1259263D01*
Y1259375D01*
G01X662008Y1250984D02*
Y1252029D01*
X661558Y1252479D01*
X660652D01*
X659763Y1253368D01*
Y1259083D01*
X659583Y1259263D01*
Y1259375D01*
G01X664433Y1259712D02*
Y1259600D01*
X664253Y1259420D01*
Y1246198D01*
X664703Y1245748D01*
X665298D01*
X665748Y1246198D01*
Y1247243D01*
G01Y1243503D02*
Y1244548D01*
X665298Y1244998D01*
X664392D01*
X663503Y1245887D01*
Y1259420D01*
X663323Y1259600D01*
Y1259712D01*
G01X689504Y1259495D02*
Y1259383D01*
X689684Y1259203D01*
Y1253368D01*
X690573Y1252479D01*
X691479D01*
X691929Y1252029D01*
Y1250984D01*
G01X690614Y1259495D02*
Y1259383D01*
X690434Y1259203D01*
Y1253679D01*
X690884Y1253229D01*
X691479D01*
X691929Y1253679D01*
Y1254724D01*
G01X693244Y1259495D02*
Y1259383D01*
X693424Y1259203D01*
Y1245887D01*
X694313Y1244998D01*
X695219D01*
X695669Y1244548D01*
Y1243503D01*
G01X694354Y1259495D02*
Y1259383D01*
X694174Y1259203D01*
Y1246198D01*
X694624Y1245748D01*
X695219D01*
X695669Y1246198D01*
Y1247243D01*
G01X667063Y1259512D02*
Y1259400D01*
X667243Y1259220D01*
Y1253368D01*
X668132Y1252479D01*
X669038D01*
X669488Y1252029D01*
Y1250984D01*
G01X668173Y1259512D02*
Y1259400D01*
X667993Y1259220D01*
Y1253679D01*
X668443Y1253229D01*
X669038D01*
X669488Y1253679D01*
Y1254724D01*
G01X698094Y1259495D02*
Y1259383D01*
X697914Y1259203D01*
Y1253679D01*
X698364Y1253229D01*
X698959D01*
X699409Y1253679D01*
Y1254724D01*
G01Y1250984D02*
Y1252029D01*
X698959Y1252479D01*
X698053D01*
X697164Y1253368D01*
Y1259203D01*
X696984Y1259383D01*
Y1259495D01*
G01X673228Y1243503D02*
Y1244548D01*
X672778Y1244998D01*
X671872D01*
X670980Y1245890D01*
Y1259295D01*
X670800Y1259475D01*
Y1259587D01*
G01X673228Y1247243D02*
Y1246198D01*
X672778Y1245748D01*
X672183D01*
X671730Y1246201D01*
Y1259295D01*
X671910Y1259475D01*
Y1259587D01*
G01X676968Y1250984D02*
Y1252029D01*
X676518Y1252479D01*
X675612D01*
X674723Y1253368D01*
Y1259220D01*
X674543Y1259400D01*
Y1259512D01*
G01X676968Y1254724D02*
Y1253679D01*
X676518Y1253229D01*
X675923D01*
X675473Y1253679D01*
Y1259220D01*
X675653Y1259400D01*
Y1259512D01*
G01X704465Y1259495D02*
Y1259383D01*
X704645Y1259203D01*
Y1253368D01*
X705534Y1252479D01*
X706440D01*
X706890Y1252029D01*
Y1250984D01*
G01X700724Y1259495D02*
Y1259383D01*
X700904Y1259203D01*
Y1245887D01*
X701793Y1244998D01*
X702699D01*
X703149Y1244548D01*
Y1243503D01*
G01X705575Y1259495D02*
Y1259383D01*
X705395Y1259203D01*
Y1253679D01*
X705845Y1253229D01*
X706440D01*
X706890Y1253679D01*
Y1254724D01*
G01X701834Y1259495D02*
Y1259383D01*
X701654Y1259203D01*
Y1246198D01*
X702104Y1245748D01*
X702699D01*
X703149Y1246198D01*
Y1247243D01*
G01X680709D02*
Y1246198D01*
X680259Y1245748D01*
X679664D01*
X679214Y1246198D01*
Y1259420D01*
X679394Y1259600D01*
Y1259712D01*
G01X680709Y1243503D02*
Y1244548D01*
X680259Y1244998D01*
X679353D01*
X678464Y1245887D01*
Y1259420D01*
X678284Y1259600D01*
Y1259712D01*
G01X684449Y1254724D02*
Y1253679D01*
X683999Y1253229D01*
X683404D01*
X682954Y1253679D01*
Y1259203D01*
X683134Y1259383D01*
Y1259495D01*
G01X684449Y1250984D02*
Y1252029D01*
X683999Y1252479D01*
X683093D01*
X682204Y1253368D01*
Y1259203D01*
X682024Y1259383D01*
Y1259495D01*
G01X713055Y1259612D02*
Y1259500D01*
X712875Y1259320D01*
Y1253679D01*
X713325Y1253229D01*
X713920D01*
X714370Y1253679D01*
Y1254724D01*
G01X711945Y1259612D02*
Y1259500D01*
X712125Y1259320D01*
Y1253368D01*
X713014Y1252479D01*
X713920D01*
X714370Y1252029D01*
Y1250984D01*
G01X709315Y1259495D02*
Y1259383D01*
X709135Y1259203D01*
Y1246198D01*
X709585Y1245748D01*
X710180D01*
X710630Y1246198D01*
Y1247243D01*
G01X708205Y1259495D02*
Y1259383D01*
X708385Y1259203D01*
Y1245887D01*
X709274Y1244998D01*
X710180D01*
X710630Y1244548D01*
Y1243503D01*
G01X689504Y1068999D02*
Y1069111D01*
X689684Y1069291D01*
Y1076594D01*
X690530Y1077440D01*
X691478D01*
X691928Y1077890D01*
Y1078935D01*
G01X690614Y1068999D02*
Y1069111D01*
X690434Y1069291D01*
Y1076283D01*
X690841Y1076690D01*
X691478D01*
X691928Y1076240D01*
Y1075195D01*
G01X693244Y1069176D02*
Y1069288D01*
X693424Y1069468D01*
Y1084075D01*
X694270Y1084921D01*
X695218D01*
X695668Y1085371D01*
Y1086416D01*
G01X696984Y1069000D02*
Y1069112D01*
X697164Y1069292D01*
Y1076595D01*
X698010Y1077441D01*
X698958D01*
X699408Y1077891D01*
Y1078936D01*
G01X698094Y1069000D02*
Y1069112D01*
X697914Y1069292D01*
Y1076284D01*
X698321Y1076691D01*
X698958D01*
X699408Y1076241D01*
Y1075196D01*
G01X695668Y1082676D02*
Y1083721D01*
X695218Y1084171D01*
X694581D01*
X694174Y1083764D01*
Y1069468D01*
X694354Y1069288D01*
Y1069176D01*
G01X703148Y1086417D02*
Y1085372D01*
X702698Y1084922D01*
X701750D01*
X700904Y1084076D01*
Y1069469D01*
X700724Y1069289D01*
Y1069177D01*
G01X703148Y1082677D02*
Y1083722D01*
X702698Y1084172D01*
X702061D01*
X701654Y1083765D01*
Y1069469D01*
X701834Y1069289D01*
Y1069177D01*
G01X704465Y1069000D02*
Y1069112D01*
X704645Y1069292D01*
Y1076595D01*
X705491Y1077441D01*
X706439D01*
X706889Y1077891D01*
Y1078936D01*
G01X705575Y1069000D02*
Y1069112D01*
X705395Y1069292D01*
Y1076284D01*
X705802Y1076691D01*
X706439D01*
X706889Y1076241D01*
Y1075196D01*
G01X708205Y1069176D02*
Y1069288D01*
X708385Y1069468D01*
Y1084075D01*
X709231Y1084921D01*
X710179D01*
X710629Y1085371D01*
Y1086416D01*
G01X709315Y1069176D02*
Y1069288D01*
X709135Y1069468D01*
Y1083764D01*
X709542Y1084171D01*
X710179D01*
X710629Y1083721D01*
Y1082676D01*
G01X711945Y1069000D02*
Y1069112D01*
X712125Y1069292D01*
Y1076595D01*
X712971Y1077441D01*
X713919D01*
X714369Y1077891D01*
Y1078936D01*
G01X713055Y1069000D02*
Y1069112D01*
X712875Y1069292D01*
Y1076284D01*
X713282Y1076691D01*
X713919D01*
X714369Y1076241D01*
Y1075196D01*
G01X718109Y1086417D02*
Y1085372D01*
X717659Y1084922D01*
X716711D01*
X715865Y1084076D01*
Y1069469D01*
X715685Y1069289D01*
Y1069177D01*
G01X719425Y1069000D02*
Y1069112D01*
X719605Y1069292D01*
Y1076595D01*
X720451Y1077441D01*
X721399D01*
X721849Y1077891D01*
Y1078936D01*
G01X718109Y1082677D02*
Y1083722D01*
X717659Y1084172D01*
X717022D01*
X716615Y1083765D01*
Y1069469D01*
X716795Y1069289D01*
Y1069177D01*
G01X720535Y1069000D02*
Y1069112D01*
X720355Y1069292D01*
Y1076284D01*
X720762Y1076691D01*
X721399D01*
X721849Y1076241D01*
Y1075196D01*
G01X748031Y1247243D02*
Y1246198D01*
X747581Y1245748D01*
X746986D01*
X746536Y1246198D01*
Y1260020D01*
X746716Y1260200D01*
Y1260312D01*
G01X748031Y1243503D02*
Y1244548D01*
X747581Y1244998D01*
X746675D01*
X745786Y1245887D01*
Y1260020D01*
X745606Y1260200D01*
Y1260312D01*
G01X749347D02*
Y1260200D01*
X749527Y1260020D01*
Y1253368D01*
X750416Y1252479D01*
X751322D01*
X751772Y1252029D01*
Y1250984D01*
G01X750457Y1260312D02*
Y1260200D01*
X750277Y1260020D01*
Y1253679D01*
X750727Y1253229D01*
X751322D01*
X751772Y1253679D01*
Y1254724D01*
G01X725589Y1086416D02*
Y1085372D01*
X725138Y1084921D01*
X724190D01*
X723344Y1084075D01*
Y1070268D01*
X723164Y1070088D01*
Y1069976D01*
G01X725589Y1082676D02*
Y1083720D01*
X725138Y1084171D01*
X724501D01*
X724094Y1083764D01*
Y1070268D01*
X724274Y1070088D01*
Y1069976D01*
G01X730644D02*
Y1070088D01*
X730824Y1070268D01*
Y1084076D01*
X731670Y1084922D01*
X732618D01*
X733069Y1085373D01*
Y1086417D01*
G01X729330Y1078936D02*
Y1077892D01*
X728879Y1077441D01*
X727931D01*
X727085Y1076595D01*
Y1070268D01*
X726905Y1070088D01*
Y1069976D01*
G01X733069Y1082677D02*
Y1083721D01*
X732618Y1084172D01*
X731981D01*
X731574Y1083765D01*
Y1070268D01*
X731754Y1070088D01*
Y1069976D01*
G01X729330Y1075196D02*
Y1076240D01*
X728879Y1076691D01*
X728242D01*
X727835Y1076284D01*
Y1070268D01*
X728015Y1070088D01*
Y1069976D01*
G01X736810Y1075196D02*
Y1076240D01*
X736359Y1076691D01*
X735722D01*
X735315Y1076284D01*
Y1070268D01*
X735495Y1070088D01*
Y1069976D01*
G01X736810Y1078936D02*
Y1077892D01*
X736359Y1077441D01*
X735411D01*
X734565Y1076595D01*
Y1070268D01*
X734385Y1070088D01*
Y1069976D01*
G01X753087Y1260312D02*
Y1260200D01*
X753267Y1260020D01*
Y1245887D01*
X754156Y1244998D01*
X755062D01*
X755512Y1244548D01*
Y1243503D01*
G01X764307Y1260312D02*
Y1260200D01*
X764487Y1260020D01*
Y1253368D01*
X765376Y1252479D01*
X766282D01*
X766732Y1252029D01*
Y1250984D01*
G01X760567Y1260312D02*
Y1260200D01*
X760747Y1260020D01*
Y1245887D01*
X761636Y1244998D01*
X762542D01*
X762992Y1244548D01*
Y1243503D01*
G01X761677Y1260312D02*
Y1260200D01*
X761497Y1260020D01*
Y1246198D01*
X761947Y1245748D01*
X762542D01*
X762992Y1246198D01*
Y1247243D01*
G01X757937Y1260312D02*
Y1260200D01*
X757757Y1260020D01*
Y1253679D01*
X758207Y1253229D01*
X758802D01*
X759252Y1253679D01*
Y1254724D01*
G01X765417Y1260312D02*
Y1260200D01*
X765237Y1260020D01*
Y1253679D01*
X765687Y1253229D01*
X766282D01*
X766732Y1253679D01*
Y1254724D01*
G01X756827Y1260312D02*
Y1260200D01*
X757007Y1260020D01*
Y1253368D01*
X757896Y1252479D01*
X758802D01*
X759252Y1252029D01*
Y1250984D01*
G01X754197Y1260312D02*
Y1260200D01*
X754017Y1260020D01*
Y1246198D01*
X754467Y1245748D01*
X755062D01*
X755512Y1246198D01*
Y1247243D01*
G01X768047Y1260312D02*
Y1260200D01*
X768227Y1260020D01*
Y1245887D01*
X769116Y1244998D01*
X770022D01*
X770472Y1244548D01*
Y1243503D01*
G01X740550Y1086416D02*
Y1085372D01*
X740099Y1084921D01*
X739151D01*
X738305Y1084075D01*
Y1070268D01*
X738125Y1070088D01*
Y1069976D01*
G01X744290Y1078936D02*
Y1077892D01*
X743839Y1077441D01*
X742891D01*
X742045Y1076595D01*
Y1069292D01*
X741865Y1069112D01*
Y1069000D01*
G01X740550Y1082676D02*
Y1083720D01*
X740099Y1084171D01*
X739462D01*
X739055Y1083764D01*
Y1070268D01*
X739235Y1070088D01*
Y1069976D01*
G01X744290Y1075196D02*
Y1076240D01*
X743839Y1076691D01*
X743202D01*
X742795Y1076284D01*
Y1069292D01*
X742975Y1069112D01*
Y1069000D01*
G01X745606Y1069177D02*
Y1069289D01*
X745786Y1069469D01*
Y1084076D01*
X746632Y1084922D01*
X747580D01*
X748030Y1085372D01*
Y1086417D01*
G01X746716Y1069177D02*
Y1069289D01*
X746536Y1069469D01*
Y1083765D01*
X746943Y1084172D01*
X747580D01*
X748030Y1083722D01*
Y1082677D01*
G01X769157Y1260312D02*
Y1260200D01*
X768977Y1260020D01*
Y1246198D01*
X769427Y1245748D01*
X770022D01*
X770472Y1246198D01*
Y1247243D01*
G01X771787Y1260312D02*
Y1260200D01*
X771967Y1260020D01*
Y1253368D01*
X772856Y1252479D01*
X773762D01*
X774212Y1252029D01*
Y1250984D01*
G01X772897Y1260312D02*
Y1260200D01*
X772717Y1260020D01*
Y1253679D01*
X773167Y1253229D01*
X773762D01*
X774212Y1253679D01*
Y1254724D01*
G01X779268Y1256712D02*
Y1256600D01*
X779448Y1256420D01*
Y1247693D01*
X778998Y1247243D01*
X777953D01*
G01X780378Y1256712D02*
Y1256600D01*
X780198Y1256420D01*
Y1247693D01*
X780648Y1247243D01*
X781693D01*
G01X777953Y1221062D02*
X778998D01*
X779448Y1221512D01*
Y1222418D01*
X780337Y1223307D01*
X783659D01*
X784136Y1223784D01*
Y1224036D01*
X784215Y1224115D01*
G01X781693Y1221062D02*
X780648D01*
X780198Y1221512D01*
Y1222107D01*
X780648Y1222557D01*
X783970D01*
X784664Y1223251D01*
X784921D01*
X785000Y1223330D01*
G01X770472Y1217322D02*
X771517D01*
X771967Y1217772D01*
Y1218678D01*
X772856Y1219567D01*
X786120D01*
X786300Y1219747D01*
X786412D01*
G01X774212Y1217322D02*
X773167D01*
X772717Y1217772D01*
Y1218367D01*
X773167Y1218817D01*
X786120D01*
X786300Y1218637D01*
X786412D01*
G01Y1214897D02*
X786300D01*
X786120Y1215077D01*
X780648D01*
X780198Y1214627D01*
Y1214032D01*
X780648Y1213582D01*
X781693D01*
G01X786412Y1216007D02*
X786300D01*
X786120Y1215827D01*
X780337D01*
X779448Y1214938D01*
Y1214032D01*
X778998Y1213582D01*
X777953D01*
G01X786512Y1212267D02*
X786400D01*
X786220Y1212087D01*
X772856D01*
X771967Y1211198D01*
Y1210292D01*
X771517Y1209842D01*
X770472D01*
G01X786512Y1211157D02*
X786400D01*
X786220Y1211337D01*
X773167D01*
X772717Y1210887D01*
Y1210292D01*
X773167Y1209842D01*
X774212D01*
G01X786812Y1208577D02*
X786700D01*
X786520Y1208397D01*
X780393D01*
X779448Y1207452D01*
Y1206552D01*
X778998Y1206102D01*
X777953D01*
G01X786812Y1207467D02*
X786700D01*
X786520Y1207647D01*
X780704D01*
X780198Y1207141D01*
Y1206552D01*
X780648Y1206102D01*
X781693D01*
G01X786612Y1204787D02*
X786500D01*
X786320Y1204607D01*
X772856D01*
X771967Y1203718D01*
Y1202812D01*
X771517Y1202362D01*
X770472D01*
G01X786612Y1203677D02*
X786500D01*
X786320Y1203857D01*
X773167D01*
X772717Y1203407D01*
Y1202812D01*
X773167Y1202362D01*
X774212D01*
G01X786412Y1199936D02*
X786300D01*
X786120Y1200116D01*
X780648D01*
X780198Y1199666D01*
Y1199071D01*
X780648Y1198621D01*
X781693D01*
G01X786412Y1201046D02*
X786300D01*
X786120Y1200866D01*
X780337D01*
X779448Y1199977D01*
Y1199071D01*
X778998Y1198621D01*
X777953D01*
G01X787599Y1129984D02*
X787487D01*
X787307Y1129804D01*
X780606D01*
X780198Y1130212D01*
Y1130849D01*
X780648Y1131299D01*
X781693D01*
G01X787599Y1122503D02*
X787487D01*
X787307Y1122323D01*
X780606D01*
X780198Y1122731D01*
Y1123368D01*
X780648Y1123818D01*
X781693D01*
G01X787599Y1128874D02*
X787487D01*
X787307Y1129054D01*
X780295D01*
X779448Y1129901D01*
Y1130849D01*
X778998Y1131299D01*
X777953D01*
G01X787599Y1121393D02*
X787487D01*
X787307Y1121573D01*
X780295D01*
X779448Y1122420D01*
Y1123368D01*
X778998Y1123818D01*
X777953D01*
G01X787471Y1115023D02*
X787359D01*
X787179Y1114843D01*
X780606D01*
X780198Y1115251D01*
Y1115888D01*
X780648Y1116338D01*
X781693D01*
G01X787471Y1113913D02*
X787359D01*
X787179Y1114093D01*
X780295D01*
X779448Y1114940D01*
Y1115888D01*
X778998Y1116338D01*
X777953D01*
G01X787599Y1106433D02*
X787487D01*
X787307Y1106613D01*
X780295D01*
X779448Y1107460D01*
Y1108408D01*
X778998Y1108858D01*
X777953D01*
G01X787599Y1107543D02*
X787487D01*
X787307Y1107363D01*
X780606D01*
X780198Y1107771D01*
Y1108408D01*
X780648Y1108858D01*
X781693D01*
G01X771787Y1069000D02*
Y1069112D01*
X771967Y1069292D01*
Y1076595D01*
X772813Y1077441D01*
X773761D01*
X774211Y1077891D01*
Y1078936D01*
G01X772897Y1069000D02*
Y1069112D01*
X772717Y1069292D01*
Y1076284D01*
X773124Y1076691D01*
X773761D01*
X774211Y1076241D01*
Y1075196D01*
G01X765417Y1069000D02*
Y1069112D01*
X765237Y1069292D01*
Y1076284D01*
X765644Y1076691D01*
X766281D01*
X766731Y1076241D01*
Y1075196D01*
G01X764307Y1069000D02*
Y1069112D01*
X764487Y1069292D01*
Y1076595D01*
X765333Y1077441D01*
X766281D01*
X766731Y1077891D01*
Y1078936D01*
G01X757937Y1069000D02*
Y1069112D01*
X757757Y1069292D01*
Y1076284D01*
X758164Y1076691D01*
X758801D01*
X759251Y1076241D01*
Y1075196D01*
G01X756827Y1069000D02*
Y1069112D01*
X757007Y1069292D01*
Y1076595D01*
X757853Y1077441D01*
X758801D01*
X759251Y1077891D01*
Y1078936D01*
G01X750457Y1069000D02*
Y1069112D01*
X750277Y1069292D01*
Y1076284D01*
X750684Y1076691D01*
X751321D01*
X751771Y1076241D01*
Y1075196D01*
G01Y1078936D02*
Y1077891D01*
X751321Y1077441D01*
X750373D01*
X749527Y1076595D01*
Y1069292D01*
X749347Y1069112D01*
Y1069000D01*
G01X787499Y1132614D02*
X787387D01*
X787207Y1132794D01*
X772928D01*
X771967Y1133755D01*
Y1134589D01*
X771517Y1135039D01*
X770472D01*
G01X787499Y1133724D02*
X787387D01*
X787207Y1133544D01*
X773239D01*
X772717Y1134066D01*
Y1134589D01*
X773167Y1135039D01*
X774212D01*
G01X787499Y1125133D02*
X787387D01*
X787207Y1125313D01*
X772928D01*
X771967Y1126274D01*
Y1127108D01*
X771517Y1127558D01*
X770472D01*
G01X787499Y1126243D02*
X787387D01*
X787207Y1126063D01*
X773239D01*
X772717Y1126585D01*
Y1127108D01*
X773167Y1127558D01*
X774212D01*
G01X787499Y1117653D02*
X787387D01*
X787207Y1117833D01*
X772928D01*
X771967Y1118794D01*
Y1119628D01*
X771517Y1120078D01*
X770472D01*
G01X787499Y1118763D02*
X787387D01*
X787207Y1118583D01*
X773239D01*
X772717Y1119105D01*
Y1119628D01*
X773167Y1120078D01*
X774212D01*
G01X787499Y1111283D02*
X787387D01*
X787207Y1111103D01*
X773239D01*
X772717Y1111625D01*
Y1112148D01*
X773167Y1112598D01*
X774212D01*
G01X787499Y1110173D02*
X787387D01*
X787207Y1110353D01*
X772928D01*
X771967Y1111314D01*
Y1112148D01*
X771517Y1112598D01*
X770472D01*
G01X782252Y1071163D02*
Y1071275D01*
X782072Y1071455D01*
Y1076215D01*
X780198Y1078089D01*
Y1082226D01*
X780648Y1082676D01*
X781693D01*
G01X781142Y1071163D02*
Y1071275D01*
X781322Y1071455D01*
Y1075904D01*
X779448Y1077778D01*
Y1082226D01*
X778998Y1082676D01*
X777953D01*
G01X768047Y1069177D02*
Y1069289D01*
X768227Y1069469D01*
Y1084076D01*
X769073Y1084922D01*
X770021D01*
X770471Y1085372D01*
Y1086417D01*
G01X769157Y1069177D02*
Y1069289D01*
X768977Y1069469D01*
Y1083765D01*
X769384Y1084172D01*
X770021D01*
X770471Y1083722D01*
Y1082677D01*
G01X760567Y1069177D02*
Y1069289D01*
X760747Y1069469D01*
Y1084076D01*
X761593Y1084922D01*
X762541D01*
X762991Y1085372D01*
Y1086417D01*
G01X754197Y1069176D02*
Y1069288D01*
X754017Y1069468D01*
Y1083764D01*
X754424Y1084171D01*
X755061D01*
X755511Y1083721D01*
Y1082676D01*
G01X761677Y1069177D02*
Y1069289D01*
X761497Y1069469D01*
Y1083765D01*
X761904Y1084172D01*
X762541D01*
X762991Y1083722D01*
Y1082677D01*
G01X755511Y1086416D02*
Y1085371D01*
X755061Y1084921D01*
X754113D01*
X753267Y1084075D01*
Y1069468D01*
X753087Y1069288D01*
Y1069176D01*
G01X900267Y838992D02*
X898691Y840568D01*
X892768D01*
G01X1057588Y1184976D02*
X1057700D01*
X1057880Y1185156D01*
X1068088D01*
X1068977Y1186045D01*
Y1186951D01*
X1069427Y1187401D01*
X1070472D01*
G01X1054300Y1188716D02*
X1054412D01*
X1054592Y1188896D01*
X1060607D01*
X1061496Y1189785D01*
Y1190691D01*
X1061946Y1191141D01*
X1062991D01*
G01X1057588Y1186086D02*
X1057700D01*
X1057880Y1185906D01*
X1067777D01*
X1068227Y1186356D01*
Y1186951D01*
X1067777Y1187401D01*
X1066732D01*
G01X1054300Y1193566D02*
X1054412D01*
X1054592Y1193386D01*
X1067777D01*
X1068227Y1193836D01*
Y1194431D01*
X1067777Y1194881D01*
X1066732D01*
G01X1054300Y1192456D02*
X1054412D01*
X1054592Y1192636D01*
X1068088D01*
X1068977Y1193525D01*
Y1194431D01*
X1069427Y1194881D01*
X1070472D01*
G01X1054300Y1189826D02*
X1054412D01*
X1054592Y1189646D01*
X1060296D01*
X1060746Y1190096D01*
Y1190691D01*
X1060296Y1191141D01*
X1059251D01*
G01X1062991Y1198621D02*
X1061946D01*
X1061496Y1198171D01*
Y1197265D01*
X1060607Y1196376D01*
X1054592D01*
X1054412Y1196196D01*
X1054300D01*
G01X1059251Y1198621D02*
X1060296D01*
X1060746Y1198171D01*
Y1197576D01*
X1060296Y1197126D01*
X1054592D01*
X1054412Y1197306D01*
X1054300D01*
G01X1070472Y1202362D02*
X1069427D01*
X1068977Y1201912D01*
Y1201006D01*
X1068088Y1200117D01*
X1054768D01*
X1054588Y1199937D01*
X1054476D01*
G01X1066732Y1202362D02*
X1067777D01*
X1068227Y1201912D01*
Y1201317D01*
X1067777Y1200867D01*
X1054768D01*
X1054588Y1201047D01*
X1054476D01*
G01X1054300Y1203677D02*
X1054412D01*
X1054592Y1203857D01*
X1060607D01*
X1061496Y1204746D01*
Y1205652D01*
X1061946Y1206102D01*
X1062991D01*
G01X1054300Y1207417D02*
X1054412D01*
X1054592Y1207597D01*
X1068088D01*
X1068977Y1208486D01*
Y1209392D01*
X1069427Y1209842D01*
X1070472D01*
G01X1054300Y1208527D02*
X1054412D01*
X1054592Y1208347D01*
X1067777D01*
X1068227Y1208797D01*
Y1209392D01*
X1067777Y1209842D01*
X1066732D01*
G01X1054300Y1204787D02*
X1054412D01*
X1054592Y1204607D01*
X1060296D01*
X1060746Y1205057D01*
Y1205652D01*
X1060296Y1206102D01*
X1059251D01*
G01X1054476Y1211157D02*
X1054588D01*
X1054768Y1211337D01*
X1060607D01*
X1061496Y1212226D01*
Y1213132D01*
X1061946Y1213582D01*
X1062991D01*
G01X1146590Y1068999D02*
Y1069111D01*
X1146770Y1069291D01*
Y1076594D01*
X1147616Y1077440D01*
X1148564D01*
X1149014Y1077890D01*
Y1078935D01*
G01X1147700Y1068999D02*
Y1069111D01*
X1147520Y1069291D01*
Y1076283D01*
X1147927Y1076690D01*
X1148564D01*
X1149014Y1076240D01*
Y1075195D01*
G01X1054476Y1212267D02*
X1054588D01*
X1054768Y1212087D01*
X1060296D01*
X1060746Y1212537D01*
Y1213132D01*
X1060296Y1213582D01*
X1059251D01*
G01X1150330Y1069176D02*
Y1069288D01*
X1150510Y1069468D01*
Y1084075D01*
X1151356Y1084921D01*
X1152304D01*
X1152754Y1085371D01*
Y1086416D01*
G01X1151440Y1069176D02*
Y1069288D01*
X1151260Y1069468D01*
Y1083764D01*
X1151667Y1084171D01*
X1152304D01*
X1152754Y1083721D01*
Y1082676D01*
G01X1155180Y1069000D02*
Y1069112D01*
X1155000Y1069292D01*
Y1076284D01*
X1155407Y1076691D01*
X1156044D01*
X1156494Y1076241D01*
Y1075196D01*
G01X1154070Y1069000D02*
Y1069112D01*
X1154250Y1069292D01*
Y1076595D01*
X1155096Y1077441D01*
X1156044D01*
X1156494Y1077891D01*
Y1078936D01*
G01X1157810Y1069177D02*
Y1069289D01*
X1157990Y1069469D01*
Y1084076D01*
X1158836Y1084922D01*
X1159784D01*
X1160234Y1085372D01*
Y1086417D01*
G01X1158920Y1069177D02*
Y1069289D01*
X1158740Y1069469D01*
Y1083765D01*
X1159147Y1084172D01*
X1159784D01*
X1160234Y1083722D01*
Y1082677D01*
G01X1161551Y1069000D02*
Y1069112D01*
X1161731Y1069292D01*
Y1076595D01*
X1162577Y1077441D01*
X1163525D01*
X1163975Y1077891D01*
Y1078936D01*
G01X1162661Y1069000D02*
Y1069112D01*
X1162481Y1069292D01*
Y1076284D01*
X1162888Y1076691D01*
X1163525D01*
X1163975Y1076241D01*
Y1075196D01*
G01X1165291Y1069176D02*
Y1069288D01*
X1165471Y1069468D01*
Y1084075D01*
X1166317Y1084921D01*
X1167265D01*
X1167715Y1085371D01*
Y1086416D01*
G01X1166401Y1069176D02*
Y1069288D01*
X1166221Y1069468D01*
Y1083764D01*
X1166628Y1084171D01*
X1167265D01*
X1167715Y1083721D01*
Y1082676D01*
G01X1172771Y1069177D02*
Y1069289D01*
X1172951Y1069469D01*
Y1084076D01*
X1173797Y1084922D01*
X1174745D01*
X1175195Y1085372D01*
Y1086417D01*
G01X1173881Y1069177D02*
Y1069289D01*
X1173701Y1069469D01*
Y1083765D01*
X1174108Y1084172D01*
X1174745D01*
X1175195Y1083722D01*
Y1082677D01*
G01X1170141Y1069000D02*
Y1069112D01*
X1169961Y1069292D01*
Y1076284D01*
X1170368Y1076691D01*
X1171005D01*
X1171455Y1076241D01*
Y1075196D01*
G01X1169031Y1069000D02*
Y1069112D01*
X1169211Y1069292D01*
Y1076595D01*
X1170057Y1077441D01*
X1171005D01*
X1171455Y1077891D01*
Y1078936D01*
G01X1176511Y1069000D02*
Y1069112D01*
X1176691Y1069292D01*
Y1076595D01*
X1177537Y1077441D01*
X1178485D01*
X1178935Y1077891D01*
Y1078936D01*
G01X1177621Y1069000D02*
Y1069112D01*
X1177441Y1069292D01*
Y1076284D01*
X1177848Y1076691D01*
X1178485D01*
X1178935Y1076241D01*
Y1075196D01*
G01X1070472Y1217322D02*
X1069427D01*
X1068977Y1216872D01*
Y1215966D01*
X1068088Y1215077D01*
X1054907D01*
X1054727Y1214897D01*
X1054615D01*
G01X1066732Y1217322D02*
X1067777D01*
X1068227Y1216872D01*
Y1216277D01*
X1067777Y1215827D01*
X1054907D01*
X1054727Y1216007D01*
X1054615D01*
G01X1059251Y1221062D02*
X1060296D01*
X1060746Y1221512D01*
Y1222107D01*
X1060296Y1222557D01*
X1057696D01*
X1056956Y1223297D01*
X1056704Y1223296D01*
X1056625Y1223375D01*
G01X1062991Y1221062D02*
X1061946D01*
X1061496Y1221512D01*
Y1222418D01*
X1060607Y1223307D01*
X1058007D01*
X1057489Y1223825D01*
Y1224081D01*
X1057410Y1224160D01*
G01X1180251Y1069176D02*
Y1069288D01*
X1180431Y1069468D01*
Y1084075D01*
X1181277Y1084921D01*
X1182225D01*
X1182675Y1085371D01*
Y1086416D01*
G01X1185102Y1069000D02*
Y1069112D01*
X1184922Y1069292D01*
Y1076284D01*
X1185329Y1076691D01*
X1185966D01*
X1186416Y1076241D01*
Y1075196D01*
G01X1181361Y1069176D02*
Y1069288D01*
X1181181Y1069468D01*
Y1083764D01*
X1181588Y1084171D01*
X1182225D01*
X1182675Y1083721D01*
Y1082676D01*
G01X1183992Y1069000D02*
Y1069112D01*
X1184172Y1069292D01*
Y1076595D01*
X1185018Y1077441D01*
X1185966D01*
X1186416Y1077891D01*
Y1078936D01*
G01X1187731Y1069177D02*
Y1069289D01*
X1187911Y1069469D01*
Y1084076D01*
X1188757Y1084922D01*
X1189705D01*
X1190155Y1085372D01*
Y1086417D01*
G01X1188841Y1069177D02*
Y1069289D01*
X1188661Y1069469D01*
Y1083765D01*
X1189068Y1084172D01*
X1189705D01*
X1190155Y1083722D01*
Y1082677D01*
G01X1191472Y1069000D02*
Y1069112D01*
X1191652Y1069292D01*
Y1076595D01*
X1192498Y1077441D01*
X1193446D01*
X1193896Y1077891D01*
Y1078936D01*
G01X1074212Y1250984D02*
Y1252029D01*
X1073762Y1252479D01*
X1072856D01*
X1071967Y1253368D01*
Y1259720D01*
X1071787Y1259900D01*
Y1260012D01*
G01X1066732Y1254724D02*
Y1253679D01*
X1066282Y1253229D01*
X1065687D01*
X1065237Y1253679D01*
Y1259720D01*
X1065417Y1259900D01*
Y1260012D01*
G01X1060566Y1256512D02*
Y1256400D01*
X1060746Y1256220D01*
Y1247693D01*
X1060296Y1247243D01*
X1059251D01*
G01X1069157Y1260012D02*
Y1259900D01*
X1068977Y1259720D01*
Y1246198D01*
X1069427Y1245748D01*
X1070022D01*
X1070472Y1246198D01*
Y1247243D01*
G01X1074212Y1254724D02*
Y1253679D01*
X1073762Y1253229D01*
X1073167D01*
X1072717Y1253679D01*
Y1259720D01*
X1072897Y1259900D01*
Y1260012D01*
G01X1062991Y1247243D02*
X1061946D01*
X1061496Y1247693D01*
Y1256220D01*
X1061676Y1256400D01*
Y1256512D01*
G01X1068047Y1260012D02*
Y1259900D01*
X1068227Y1259720D01*
Y1245887D01*
X1069116Y1244998D01*
X1070022D01*
X1070472Y1244548D01*
Y1243503D01*
G01X1064307Y1260012D02*
Y1259900D01*
X1064487Y1259720D01*
Y1253368D01*
X1065376Y1252479D01*
X1066282D01*
X1066732Y1252029D01*
Y1250984D01*
G01X1192582Y1069000D02*
Y1069112D01*
X1192402Y1069292D01*
Y1076284D01*
X1192809Y1076691D01*
X1193446D01*
X1193896Y1076241D01*
Y1075196D01*
G01X1196322Y1069176D02*
Y1069288D01*
X1196142Y1069468D01*
Y1083764D01*
X1196549Y1084171D01*
X1197186D01*
X1197636Y1083721D01*
Y1082676D01*
G01X1198952Y1069000D02*
Y1069112D01*
X1199132Y1069292D01*
Y1076595D01*
X1199978Y1077441D01*
X1200926D01*
X1201376Y1077891D01*
Y1078936D01*
G01X1200062Y1069000D02*
Y1069112D01*
X1199882Y1069292D01*
Y1076284D01*
X1200289Y1076691D01*
X1200926D01*
X1201376Y1076241D01*
Y1075196D01*
G01X1195212Y1069176D02*
Y1069288D01*
X1195392Y1069468D01*
Y1084075D01*
X1196238Y1084921D01*
X1197186D01*
X1197636Y1085371D01*
Y1086416D01*
G01X1202692Y1069177D02*
Y1069289D01*
X1202872Y1069469D01*
Y1084076D01*
X1203718Y1084922D01*
X1204666D01*
X1205116Y1085372D01*
Y1086417D01*
G01X1075527Y1260012D02*
Y1259900D01*
X1075707Y1259720D01*
Y1245887D01*
X1076596Y1244998D01*
X1077502D01*
X1077952Y1244548D01*
Y1243503D01*
G01X1079267Y1260012D02*
Y1259900D01*
X1079447Y1259720D01*
Y1253368D01*
X1080336Y1252479D01*
X1081242D01*
X1081692Y1252029D01*
Y1250984D01*
G01X1076637Y1260012D02*
Y1259900D01*
X1076457Y1259720D01*
Y1246198D01*
X1076907Y1245748D01*
X1077502D01*
X1077952Y1246198D01*
Y1247243D01*
G01X1080377Y1260012D02*
Y1259900D01*
X1080197Y1259720D01*
Y1253679D01*
X1080647Y1253229D01*
X1081242D01*
X1081692Y1253679D01*
Y1254724D01*
G01X1083007Y1260012D02*
Y1259900D01*
X1083187Y1259720D01*
Y1245887D01*
X1084076Y1244998D01*
X1084982D01*
X1085432Y1244548D01*
Y1243503D01*
G01X1091598Y1260012D02*
Y1259900D01*
X1091418Y1259720D01*
Y1246198D01*
X1091868Y1245748D01*
X1092463D01*
X1092913Y1246198D01*
Y1247243D01*
G01X1087857Y1260012D02*
Y1259900D01*
X1087677Y1259720D01*
Y1253679D01*
X1088127Y1253229D01*
X1088722D01*
X1089172Y1253679D01*
Y1254724D01*
G01X1090488Y1260012D02*
Y1259900D01*
X1090668Y1259720D01*
Y1245887D01*
X1091557Y1244998D01*
X1092463D01*
X1092913Y1244548D01*
Y1243503D01*
G01X1086747Y1260012D02*
Y1259900D01*
X1086927Y1259720D01*
Y1253368D01*
X1087816Y1252479D01*
X1088722D01*
X1089172Y1252029D01*
Y1250984D01*
G01X1084117Y1260012D02*
Y1259900D01*
X1083937Y1259720D01*
Y1246198D01*
X1084387Y1245748D01*
X1084982D01*
X1085432Y1246198D01*
Y1247243D01*
G01X1203802Y1069177D02*
Y1069289D01*
X1203622Y1069469D01*
Y1083765D01*
X1204029Y1084172D01*
X1204666D01*
X1205116Y1083722D01*
Y1082677D01*
G01X1096653Y1254724D02*
Y1253679D01*
X1096203Y1253229D01*
X1095608D01*
X1095158Y1253679D01*
Y1259532D01*
X1095338Y1259712D01*
Y1259824D01*
G01X1104133Y1254724D02*
Y1253679D01*
X1103683Y1253229D01*
X1103088D01*
X1102638Y1253679D01*
Y1259420D01*
X1102818Y1259600D01*
Y1259712D01*
G01X1094228Y1259824D02*
Y1259712D01*
X1094408Y1259532D01*
Y1253368D01*
X1095297Y1252479D01*
X1096203D01*
X1096653Y1252029D01*
Y1250984D01*
G01X1105448Y1259712D02*
Y1259600D01*
X1105628Y1259420D01*
Y1245887D01*
X1106517Y1244998D01*
X1107423D01*
X1107873Y1244548D01*
Y1243503D01*
G01X1097968Y1260012D02*
Y1259900D01*
X1098148Y1259720D01*
Y1245887D01*
X1099037Y1244998D01*
X1099943D01*
X1100393Y1244548D01*
Y1243503D01*
G01X1107873Y1247243D02*
Y1246198D01*
X1107423Y1245748D01*
X1106828D01*
X1106378Y1246198D01*
Y1259420D01*
X1106558Y1259600D01*
Y1259712D01*
G01X1100393Y1247243D02*
Y1246198D01*
X1099943Y1245748D01*
X1099348D01*
X1098898Y1246198D01*
Y1259720D01*
X1099078Y1259900D01*
Y1260012D01*
G01X1101708Y1259712D02*
Y1259600D01*
X1101888Y1259420D01*
Y1253368D01*
X1102777Y1252479D01*
X1103683D01*
X1104133Y1252029D01*
Y1250984D01*
G01X1111613Y1254724D02*
Y1253679D01*
X1111163Y1253229D01*
X1110568D01*
X1110118Y1253679D01*
Y1259220D01*
X1110298Y1259400D01*
Y1259512D01*
G01X1111613Y1250984D02*
Y1252029D01*
X1111163Y1252479D01*
X1110257D01*
X1109368Y1253368D01*
Y1259220D01*
X1109188Y1259400D01*
Y1259512D01*
G01X1238779Y1131299D02*
X1237734D01*
X1237284Y1130849D01*
Y1130212D01*
X1237692Y1129804D01*
X1244393D01*
X1244573Y1129984D01*
X1244685D01*
G01X1235039Y1131299D02*
X1236084D01*
X1236534Y1130849D01*
Y1129901D01*
X1237381Y1129054D01*
X1244393D01*
X1244573Y1128874D01*
X1244685D01*
G01X1238779Y1123818D02*
X1237734D01*
X1237284Y1123368D01*
Y1122731D01*
X1237692Y1122323D01*
X1244393D01*
X1244573Y1122503D01*
X1244685D01*
G01X1235039Y1123818D02*
X1236084D01*
X1236534Y1123368D01*
Y1122420D01*
X1237381Y1121573D01*
X1244393D01*
X1244573Y1121393D01*
X1244685D01*
G01X1238779Y1116338D02*
X1237734D01*
X1237284Y1115888D01*
Y1115251D01*
X1237692Y1114843D01*
X1244265D01*
X1244445Y1115023D01*
X1244557D01*
G01X1235039Y1116338D02*
X1236084D01*
X1236534Y1115888D01*
Y1114940D01*
X1237381Y1114093D01*
X1244265D01*
X1244445Y1113913D01*
X1244557D01*
G01X1238779Y1108858D02*
X1237734D01*
X1237284Y1108408D01*
Y1107771D01*
X1237692Y1107363D01*
X1244393D01*
X1244573Y1107543D01*
X1244685D01*
G01Y1106433D02*
X1244573D01*
X1244393Y1106613D01*
X1237381D01*
X1236534Y1107460D01*
Y1108408D01*
X1236084Y1108858D01*
X1235039D01*
G01X1231297Y1078936D02*
Y1077891D01*
X1230847Y1077441D01*
X1229899D01*
X1229053Y1076595D01*
Y1069292D01*
X1228873Y1069112D01*
Y1069000D01*
G01X1229983D02*
Y1069112D01*
X1229803Y1069292D01*
Y1076284D01*
X1230210Y1076691D01*
X1230847D01*
X1231297Y1076241D01*
Y1075196D01*
G01X1221393Y1069000D02*
Y1069112D01*
X1221573Y1069292D01*
Y1076595D01*
X1222419Y1077441D01*
X1223367D01*
X1223817Y1077891D01*
Y1078936D01*
G01X1222503Y1069000D02*
Y1069112D01*
X1222323Y1069292D01*
Y1076284D01*
X1222730Y1076691D01*
X1223367D01*
X1223817Y1076241D01*
Y1075196D01*
G01X1215023Y1069000D02*
Y1069112D01*
X1214843Y1069292D01*
Y1076284D01*
X1215250Y1076691D01*
X1215887D01*
X1216337Y1076241D01*
Y1075196D01*
G01X1213913Y1069000D02*
Y1069112D01*
X1214093Y1069292D01*
Y1076595D01*
X1214939Y1077441D01*
X1215887D01*
X1216337Y1077891D01*
Y1078936D01*
G01X1206433Y1069000D02*
Y1069112D01*
X1206613Y1069292D01*
Y1076595D01*
X1207459Y1077441D01*
X1208407D01*
X1208857Y1077891D01*
Y1078936D01*
G01Y1075196D02*
Y1076241D01*
X1208407Y1076691D01*
X1207770D01*
X1207363Y1076284D01*
Y1069292D01*
X1207543Y1069112D01*
Y1069000D01*
G01X1231298Y1135039D02*
X1230253D01*
X1229803Y1134589D01*
Y1134066D01*
X1230325Y1133544D01*
X1244293D01*
X1244473Y1133724D01*
X1244585D01*
G01X1227558Y1135039D02*
X1228603D01*
X1229053Y1134589D01*
Y1133755D01*
X1230014Y1132794D01*
X1244293D01*
X1244473Y1132614D01*
X1244585D01*
G01Y1125133D02*
X1244473D01*
X1244293Y1125313D01*
X1230014D01*
X1229053Y1126274D01*
Y1127108D01*
X1228603Y1127558D01*
X1227558D01*
G01X1244585Y1126243D02*
X1244473D01*
X1244293Y1126063D01*
X1230325D01*
X1229803Y1126585D01*
Y1127108D01*
X1230253Y1127558D01*
X1231298D01*
G01Y1120078D02*
X1230253D01*
X1229803Y1119628D01*
Y1119105D01*
X1230325Y1118583D01*
X1244293D01*
X1244473Y1118763D01*
X1244585D01*
G01X1227558Y1120078D02*
X1228603D01*
X1229053Y1119628D01*
Y1118794D01*
X1230014Y1117833D01*
X1244293D01*
X1244473Y1117653D01*
X1244585D01*
G01X1227558Y1112598D02*
X1228603D01*
X1229053Y1112148D01*
Y1111314D01*
X1230014Y1110353D01*
X1244293D01*
X1244473Y1110173D01*
X1244585D01*
G01X1231298Y1112598D02*
X1230253D01*
X1229803Y1112148D01*
Y1111625D01*
X1230325Y1111103D01*
X1244293D01*
X1244473Y1111283D01*
X1244585D01*
G01X1235039Y1082676D02*
X1236084D01*
X1236534Y1082226D01*
Y1078380D01*
X1236354Y1078200D01*
Y1078088D01*
G01X1238779Y1082676D02*
X1237734D01*
X1237284Y1082226D01*
Y1078380D01*
X1237464Y1078200D01*
Y1078088D01*
G01X1225133Y1069177D02*
Y1069289D01*
X1225313Y1069469D01*
Y1084076D01*
X1226159Y1084922D01*
X1227107D01*
X1227557Y1085372D01*
Y1086417D01*
G01X1226243Y1069177D02*
Y1069289D01*
X1226063Y1069469D01*
Y1083765D01*
X1226470Y1084172D01*
X1227107D01*
X1227557Y1083722D01*
Y1082677D01*
G01X1211283Y1069176D02*
Y1069288D01*
X1211103Y1069468D01*
Y1083764D01*
X1211510Y1084171D01*
X1212147D01*
X1212597Y1083721D01*
Y1082676D01*
G01X1217653Y1069177D02*
Y1069289D01*
X1217833Y1069469D01*
Y1084076D01*
X1218679Y1084922D01*
X1219627D01*
X1220077Y1085372D01*
Y1086417D01*
G01X1218763Y1069177D02*
Y1069289D01*
X1218583Y1069469D01*
Y1083765D01*
X1218990Y1084172D01*
X1219627D01*
X1220077Y1083722D01*
Y1082677D01*
G01X1210173Y1069176D02*
Y1069288D01*
X1210353Y1069468D01*
Y1084075D01*
X1211199Y1084921D01*
X1212147D01*
X1212597Y1085371D01*
Y1086416D01*
G01X1187732Y1259724D02*
Y1259612D01*
X1187912Y1259432D01*
Y1245887D01*
X1188801Y1244998D01*
X1189707D01*
X1190157Y1244548D01*
Y1243503D01*
G01X1178936Y1254724D02*
Y1253679D01*
X1178486Y1253229D01*
X1177891D01*
X1177441Y1253679D01*
Y1259432D01*
X1177621Y1259612D01*
Y1259724D01*
G01X1172771Y1259812D02*
Y1259700D01*
X1172951Y1259520D01*
Y1245887D01*
X1173840Y1244998D01*
X1174746D01*
X1175196Y1244548D01*
Y1243503D01*
G01X1181361Y1259724D02*
Y1259612D01*
X1181181Y1259432D01*
Y1246198D01*
X1181631Y1245748D01*
X1182226D01*
X1182676Y1246198D01*
Y1247243D01*
G01X1176511Y1259724D02*
Y1259612D01*
X1176691Y1259432D01*
Y1253368D01*
X1177580Y1252479D01*
X1178486D01*
X1178936Y1252029D01*
Y1250984D01*
G01X1183992Y1259724D02*
Y1259612D01*
X1184172Y1259432D01*
Y1253368D01*
X1185061Y1252479D01*
X1185967D01*
X1186417Y1252029D01*
Y1250984D01*
G01X1180251Y1259724D02*
Y1259612D01*
X1180431Y1259432D01*
Y1245887D01*
X1181320Y1244998D01*
X1182226D01*
X1182676Y1244548D01*
Y1243503D01*
G01X1190157Y1247243D02*
Y1246198D01*
X1189707Y1245748D01*
X1189112D01*
X1188662Y1246198D01*
Y1259432D01*
X1188842Y1259612D01*
Y1259724D01*
G01X1185102D02*
Y1259612D01*
X1184922Y1259432D01*
Y1253679D01*
X1185372Y1253229D01*
X1185967D01*
X1186417Y1253679D01*
Y1254724D01*
G01X1173881Y1259812D02*
Y1259700D01*
X1173701Y1259520D01*
Y1246198D01*
X1174151Y1245748D01*
X1174746D01*
X1175196Y1246198D01*
Y1247243D01*
G01X1198952Y1259512D02*
Y1259400D01*
X1199132Y1259220D01*
Y1253368D01*
X1200021Y1252479D01*
X1200927D01*
X1201377Y1252029D01*
Y1250984D01*
G01X1196322Y1259724D02*
Y1259612D01*
X1196142Y1259432D01*
Y1246198D01*
X1196592Y1245748D01*
X1197187D01*
X1197637Y1246198D01*
Y1247243D01*
G01X1191472Y1259724D02*
Y1259612D01*
X1191652Y1259432D01*
Y1253368D01*
X1192541Y1252479D01*
X1193447D01*
X1193897Y1252029D01*
Y1250984D01*
G01X1200062Y1259512D02*
Y1259400D01*
X1199882Y1259220D01*
Y1253679D01*
X1200332Y1253229D01*
X1200927D01*
X1201377Y1253679D01*
Y1254724D01*
G01X1197637Y1243503D02*
Y1244548D01*
X1197187Y1244998D01*
X1196281D01*
X1195392Y1245887D01*
Y1259432D01*
X1195212Y1259612D01*
Y1259724D01*
G01X1193897Y1254724D02*
Y1253679D01*
X1193447Y1253229D01*
X1192852D01*
X1192402Y1253679D01*
Y1259432D01*
X1192582Y1259612D01*
Y1259724D01*
G01X1572441Y1243503D02*
Y1244548D01*
X1571991Y1244998D01*
X1571085D01*
X1570196Y1245887D01*
Y1259603D01*
X1570016Y1259783D01*
Y1259895D01*
G01X1572441Y1247243D02*
Y1246198D01*
X1571991Y1245748D01*
X1571396D01*
X1570946Y1246198D01*
Y1259603D01*
X1571126Y1259783D01*
Y1259895D01*
G01X1573756Y1259824D02*
Y1259712D01*
X1573936Y1259532D01*
Y1253368D01*
X1574795Y1252509D01*
X1575701D01*
X1576181Y1252029D01*
Y1250984D01*
G01X1579921Y1247243D02*
Y1246198D01*
X1579471Y1245748D01*
X1578876D01*
X1578426Y1246198D01*
Y1259532D01*
X1578606Y1259712D01*
Y1259824D01*
G01X1576181Y1254724D02*
Y1253740D01*
X1575700Y1253259D01*
X1575106D01*
X1574686Y1253679D01*
Y1259532D01*
X1574866Y1259712D01*
Y1259824D01*
G01X1577496D02*
Y1259712D01*
X1577676Y1259532D01*
Y1245887D01*
X1578565Y1244998D01*
X1579471D01*
X1579921Y1244548D01*
Y1243503D01*
G01X1583661Y1254724D02*
Y1253679D01*
X1583211Y1253229D01*
X1582616D01*
X1582166Y1253679D01*
Y1259403D01*
X1582346Y1259583D01*
Y1259695D01*
G01X1584976D02*
Y1259583D01*
X1585156Y1259403D01*
Y1245887D01*
X1586045Y1244998D01*
X1586951D01*
X1587401Y1244548D01*
Y1243503D01*
G01X1583661Y1250984D02*
Y1252029D01*
X1583211Y1252479D01*
X1582305D01*
X1581416Y1253368D01*
Y1259403D01*
X1581236Y1259583D01*
Y1259695D01*
G01X1599937D02*
Y1259583D01*
X1600117Y1259403D01*
Y1245887D01*
X1601006Y1244998D01*
X1601912D01*
X1602362Y1244548D01*
Y1243503D01*
G01X1601047Y1259695D02*
Y1259583D01*
X1600867Y1259403D01*
Y1246198D01*
X1601317Y1245748D01*
X1601912D01*
X1602362Y1246198D01*
Y1247243D01*
G01X1607417Y1069176D02*
Y1069288D01*
X1607597Y1069468D01*
Y1084075D01*
X1608443Y1084921D01*
X1609391D01*
X1609841Y1085371D01*
Y1086416D01*
G01X1603677Y1068999D02*
Y1069111D01*
X1603857Y1069291D01*
Y1076594D01*
X1604703Y1077440D01*
X1605651D01*
X1606101Y1077890D01*
Y1078935D01*
G01X1604787Y1068999D02*
Y1069111D01*
X1604607Y1069291D01*
Y1076283D01*
X1605014Y1076690D01*
X1605651D01*
X1606101Y1076240D01*
Y1075195D01*
G01X1608527Y1069176D02*
Y1069288D01*
X1608347Y1069468D01*
Y1083764D01*
X1608754Y1084171D01*
X1609391D01*
X1609841Y1083721D01*
Y1082676D01*
G01X1612267Y1069000D02*
Y1069112D01*
X1612087Y1069292D01*
Y1076284D01*
X1612494Y1076691D01*
X1613131D01*
X1613581Y1076241D01*
Y1075196D01*
G01X1611157Y1069000D02*
Y1069112D01*
X1611337Y1069292D01*
Y1076595D01*
X1612183Y1077441D01*
X1613131D01*
X1613581Y1077891D01*
Y1078936D01*
G01X1614897Y1069177D02*
Y1069289D01*
X1615077Y1069469D01*
Y1084076D01*
X1615923Y1084922D01*
X1616871D01*
X1617321Y1085372D01*
Y1086417D01*
G01X1616007Y1069177D02*
Y1069289D01*
X1615827Y1069469D01*
Y1083765D01*
X1616234Y1084172D01*
X1616871D01*
X1617321Y1083722D01*
Y1082677D01*
G01X1586086Y1259695D02*
Y1259583D01*
X1585906Y1259403D01*
Y1246198D01*
X1586356Y1245748D01*
X1586951D01*
X1587401Y1246198D01*
Y1247243D01*
G01X1589826Y1259695D02*
Y1259583D01*
X1589646Y1259403D01*
Y1253679D01*
X1590096Y1253229D01*
X1590691D01*
X1591141Y1253679D01*
Y1254724D01*
G01X1588716Y1259695D02*
Y1259583D01*
X1588896Y1259403D01*
Y1253368D01*
X1589785Y1252479D01*
X1590691D01*
X1591141Y1252029D01*
Y1250984D01*
G01X1603677Y1259512D02*
Y1259400D01*
X1603857Y1259220D01*
Y1253368D01*
X1604746Y1252479D01*
X1605652D01*
X1606102Y1252029D01*
Y1250984D01*
G01X1604787Y1259512D02*
Y1259400D01*
X1604607Y1259220D01*
Y1253679D01*
X1605057Y1253229D01*
X1605652D01*
X1606102Y1253679D01*
Y1254724D01*
G01X1607417Y1259512D02*
Y1259400D01*
X1607597Y1259220D01*
Y1245887D01*
X1608486Y1244998D01*
X1609392D01*
X1609842Y1244548D01*
Y1243503D01*
G01X1608527Y1259512D02*
Y1259400D01*
X1608347Y1259220D01*
Y1246198D01*
X1608797Y1245748D01*
X1609392D01*
X1609842Y1246198D01*
Y1247243D01*
G01X1618638Y1069000D02*
Y1069112D01*
X1618818Y1069292D01*
Y1076595D01*
X1619664Y1077441D01*
X1620612D01*
X1621062Y1077891D01*
Y1078936D01*
G01X1619748Y1069000D02*
Y1069112D01*
X1619568Y1069292D01*
Y1076284D01*
X1619975Y1076691D01*
X1620612D01*
X1621062Y1076241D01*
Y1075196D01*
G01X1622378Y1069176D02*
Y1069288D01*
X1622558Y1069468D01*
Y1084075D01*
X1623404Y1084921D01*
X1624352D01*
X1624802Y1085371D01*
Y1086416D01*
G01X1623488Y1069176D02*
Y1069288D01*
X1623308Y1069468D01*
Y1083764D01*
X1623715Y1084171D01*
X1624352D01*
X1624802Y1083721D01*
Y1082676D01*
G01X1626118Y1069000D02*
Y1069112D01*
X1626298Y1069292D01*
Y1076595D01*
X1627144Y1077441D01*
X1628092D01*
X1628542Y1077891D01*
Y1078936D01*
G01X1629858Y1069177D02*
Y1069289D01*
X1630038Y1069469D01*
Y1084076D01*
X1630884Y1084922D01*
X1631832D01*
X1632282Y1085372D01*
Y1086417D01*
G01X1627228Y1069000D02*
Y1069112D01*
X1627048Y1069292D01*
Y1076284D01*
X1627455Y1076691D01*
X1628092D01*
X1628542Y1076241D01*
Y1075196D01*
G01X1630968Y1069177D02*
Y1069289D01*
X1630788Y1069469D01*
Y1083765D01*
X1631195Y1084172D01*
X1631832D01*
X1632282Y1083722D01*
Y1082677D01*
G01X1633598Y1069000D02*
Y1069112D01*
X1633778Y1069292D01*
Y1076595D01*
X1634624Y1077441D01*
X1635572D01*
X1636022Y1077891D01*
Y1078936D01*
G01X1592457Y1259695D02*
Y1259583D01*
X1592637Y1259403D01*
Y1245887D01*
X1593526Y1244998D01*
X1594432D01*
X1594882Y1244548D01*
Y1243503D01*
G01X1593567Y1259695D02*
Y1259583D01*
X1593387Y1259403D01*
Y1246198D01*
X1593837Y1245748D01*
X1594432D01*
X1594882Y1246198D01*
Y1247243D01*
G01X1611157Y1259495D02*
Y1259383D01*
X1611337Y1259203D01*
Y1253368D01*
X1612226Y1252479D01*
X1613132D01*
X1613582Y1252029D01*
Y1250984D01*
G01X1614897Y1259512D02*
Y1259400D01*
X1615077Y1259220D01*
Y1245887D01*
X1615966Y1244998D01*
X1616872D01*
X1617322Y1244548D01*
Y1243503D01*
G01X1612267Y1259495D02*
Y1259383D01*
X1612087Y1259203D01*
Y1253679D01*
X1612537Y1253229D01*
X1613132D01*
X1613582Y1253679D01*
Y1254724D01*
G01X1616007Y1259512D02*
Y1259400D01*
X1615827Y1259220D01*
Y1246198D01*
X1616277Y1245748D01*
X1616872D01*
X1617322Y1246198D01*
Y1247243D01*
G01X1634708Y1069000D02*
Y1069112D01*
X1634528Y1069292D01*
Y1076284D01*
X1634935Y1076691D01*
X1635572D01*
X1636022Y1076241D01*
Y1075196D01*
G01X1641079Y1069000D02*
Y1069112D01*
X1641259Y1069292D01*
Y1076595D01*
X1642105Y1077441D01*
X1643053D01*
X1643503Y1077891D01*
Y1078936D01*
G01X1637338Y1069176D02*
Y1069288D01*
X1637518Y1069468D01*
Y1084075D01*
X1638364Y1084921D01*
X1639312D01*
X1639762Y1085371D01*
Y1086416D01*
G01X1642189Y1069000D02*
Y1069112D01*
X1642009Y1069292D01*
Y1076284D01*
X1642416Y1076691D01*
X1643053D01*
X1643503Y1076241D01*
Y1075196D01*
G01X1638448Y1069176D02*
Y1069288D01*
X1638268Y1069468D01*
Y1083764D01*
X1638675Y1084171D01*
X1639312D01*
X1639762Y1083721D01*
Y1082676D01*
G01X1645928Y1069177D02*
Y1069289D01*
X1645748Y1069469D01*
Y1083765D01*
X1646155Y1084172D01*
X1646792D01*
X1647242Y1083722D01*
Y1082677D01*
G01X1644818Y1069177D02*
Y1069289D01*
X1644998Y1069469D01*
Y1084076D01*
X1645844Y1084922D01*
X1646792D01*
X1647242Y1085372D01*
Y1086417D01*
G01X1596197Y1259695D02*
Y1259583D01*
X1596377Y1259403D01*
Y1253368D01*
X1597266Y1252479D01*
X1598172D01*
X1598622Y1252029D01*
Y1250984D01*
G01X1597307Y1259695D02*
Y1259583D01*
X1597127Y1259403D01*
Y1253679D01*
X1597577Y1253229D01*
X1598172D01*
X1598622Y1253679D01*
Y1254724D01*
G01X1619748Y1259512D02*
Y1259400D01*
X1619568Y1259220D01*
Y1253679D01*
X1620018Y1253229D01*
X1620613D01*
X1621063Y1253679D01*
Y1254724D01*
G01X1618638Y1259512D02*
Y1259400D01*
X1618818Y1259220D01*
Y1253368D01*
X1619707Y1252479D01*
X1620613D01*
X1621063Y1252029D01*
Y1250984D01*
G01X1649669Y1069000D02*
Y1069112D01*
X1649489Y1069292D01*
Y1076284D01*
X1649896Y1076691D01*
X1650533D01*
X1650983Y1076241D01*
Y1075196D01*
G01X1648559Y1069000D02*
Y1069112D01*
X1648739Y1069292D01*
Y1076595D01*
X1649585Y1077441D01*
X1650533D01*
X1650983Y1077891D01*
Y1078936D01*
G01X1652299Y1069176D02*
Y1069288D01*
X1652479Y1069468D01*
Y1084075D01*
X1653325Y1084921D01*
X1654273D01*
X1654723Y1085371D01*
Y1086416D01*
G01X1653409Y1069176D02*
Y1069288D01*
X1653229Y1069468D01*
Y1083764D01*
X1653636Y1084171D01*
X1654273D01*
X1654723Y1083721D01*
Y1082676D01*
G01X1657149Y1069000D02*
Y1069112D01*
X1656969Y1069292D01*
Y1076284D01*
X1657376Y1076691D01*
X1658013D01*
X1658463Y1076241D01*
Y1075196D01*
G01X1656039Y1069000D02*
Y1069112D01*
X1656219Y1069292D01*
Y1076595D01*
X1657065Y1077441D01*
X1658013D01*
X1658463Y1077891D01*
Y1078936D01*
G01X1623488Y1259612D02*
Y1259500D01*
X1623308Y1259320D01*
Y1246198D01*
X1623758Y1245748D01*
X1624353D01*
X1624803Y1246198D01*
Y1247243D01*
G01X1622378Y1259612D02*
Y1259500D01*
X1622558Y1259320D01*
Y1245887D01*
X1623447Y1244998D01*
X1624353D01*
X1624803Y1244548D01*
Y1243503D01*
G01X1626118Y1259712D02*
Y1259600D01*
X1626298Y1259420D01*
Y1253368D01*
X1627187Y1252479D01*
X1628093D01*
X1628543Y1252029D01*
Y1250984D01*
G01X1627228Y1259712D02*
Y1259600D01*
X1627048Y1259420D01*
Y1253679D01*
X1627498Y1253229D01*
X1628093D01*
X1628543Y1253679D01*
Y1254724D01*
G01X1659779Y1069177D02*
Y1069289D01*
X1659959Y1069469D01*
Y1084076D01*
X1660805Y1084922D01*
X1661753D01*
X1662203Y1085372D01*
Y1086417D01*
G01X1660889Y1069177D02*
Y1069289D01*
X1660709Y1069469D01*
Y1083765D01*
X1661116Y1084172D01*
X1661753D01*
X1662203Y1083722D01*
Y1082677D01*
G01X1660889Y1259600D02*
Y1259488D01*
X1660709Y1259308D01*
Y1246198D01*
X1661159Y1245748D01*
X1661754D01*
X1662204Y1246198D01*
Y1247243D01*
G01X1659779Y1259600D02*
Y1259488D01*
X1659959Y1259308D01*
Y1245887D01*
X1660848Y1244998D01*
X1661754D01*
X1662204Y1244548D01*
Y1243503D01*
G01X1664630Y1259600D02*
Y1259488D01*
X1664450Y1259308D01*
Y1253679D01*
X1664900Y1253229D01*
X1665495D01*
X1665945Y1253679D01*
Y1254724D01*
G01Y1250984D02*
Y1252029D01*
X1665495Y1252479D01*
X1664589D01*
X1663700Y1253368D01*
Y1259308D01*
X1663520Y1259488D01*
Y1259600D01*
G01X1668370D02*
Y1259488D01*
X1668190Y1259308D01*
Y1246198D01*
X1668640Y1245748D01*
X1669235D01*
X1669685Y1246198D01*
Y1247243D01*
G01X1667260Y1259600D02*
Y1259488D01*
X1667440Y1259308D01*
Y1245887D01*
X1668329Y1244998D01*
X1669235D01*
X1669685Y1244548D01*
Y1243503D01*
G01X1701672Y1132614D02*
X1701560D01*
X1701380Y1132794D01*
X1687101D01*
X1686140Y1133755D01*
Y1134589D01*
X1685690Y1135039D01*
X1684645D01*
G01X1688385D02*
X1687340D01*
X1686890Y1134589D01*
Y1134066D01*
X1687412Y1133544D01*
X1701380D01*
X1701560Y1133724D01*
X1701672D01*
G01X1695866Y1123818D02*
X1694821D01*
X1694371Y1123368D01*
Y1122731D01*
X1694779Y1122323D01*
X1701480D01*
X1701660Y1122503D01*
X1701772D01*
G01X1695866Y1131299D02*
X1694821D01*
X1694371Y1130849D01*
Y1130212D01*
X1694779Y1129804D01*
X1701480D01*
X1701660Y1129984D01*
X1701772D01*
G01X1701672Y1125133D02*
X1701560D01*
X1701380Y1125313D01*
X1687101D01*
X1686140Y1126274D01*
Y1127108D01*
X1685690Y1127558D01*
X1684645D01*
G01X1692126Y1131299D02*
X1693171D01*
X1693621Y1130849D01*
Y1129901D01*
X1694468Y1129054D01*
X1701480D01*
X1701660Y1128874D01*
X1701772D01*
G01X1701672Y1126243D02*
X1701560D01*
X1701380Y1126063D01*
X1687412D01*
X1686890Y1126585D01*
Y1127108D01*
X1687340Y1127558D01*
X1688385D01*
G01X1692126Y1123818D02*
X1693171D01*
X1693621Y1123368D01*
Y1122420D01*
X1694468Y1121573D01*
X1701480D01*
X1701660Y1121393D01*
X1701772D01*
G01X1692126Y1116338D02*
X1693171D01*
X1693621Y1115888D01*
Y1114940D01*
X1694468Y1114093D01*
X1701352D01*
X1701532Y1113913D01*
X1701644D01*
G01X1684645Y1120078D02*
X1685690D01*
X1686140Y1119628D01*
Y1118794D01*
X1687101Y1117833D01*
X1701380D01*
X1701560Y1117653D01*
X1701672D01*
G01X1688385Y1120078D02*
X1687340D01*
X1686890Y1119628D01*
Y1119105D01*
X1687412Y1118583D01*
X1701380D01*
X1701560Y1118763D01*
X1701672D01*
G01X1695866Y1116338D02*
X1694821D01*
X1694371Y1115888D01*
Y1115251D01*
X1694779Y1114843D01*
X1701352D01*
X1701532Y1115023D01*
X1701644D01*
G01X1701772Y1106433D02*
X1701660D01*
X1701480Y1106613D01*
X1694468D01*
X1693621Y1107460D01*
Y1108408D01*
X1693171Y1108858D01*
X1692126D01*
G01X1684645Y1112598D02*
X1685690D01*
X1686140Y1112148D01*
Y1111314D01*
X1687101Y1110353D01*
X1701380D01*
X1701560Y1110173D01*
X1701672D01*
G01X1701772Y1107543D02*
X1701660D01*
X1701480Y1107363D01*
X1694779D01*
X1694371Y1107771D01*
Y1108408D01*
X1694821Y1108858D01*
X1695866D01*
G01X1688385Y1112598D02*
X1687340D01*
X1686890Y1112148D01*
Y1111625D01*
X1687412Y1111103D01*
X1701380D01*
X1701560Y1111283D01*
X1701672D01*
G01X1695315Y1071163D02*
Y1071275D01*
X1695495Y1071455D01*
Y1075904D01*
X1693621Y1077778D01*
Y1082226D01*
X1693171Y1082676D01*
X1692126D01*
G01X1685960Y1069000D02*
Y1069112D01*
X1686140Y1069292D01*
Y1076595D01*
X1686986Y1077441D01*
X1687934D01*
X1688384Y1077891D01*
Y1078936D01*
G01X1687070Y1069000D02*
Y1069112D01*
X1686890Y1069292D01*
Y1076284D01*
X1687297Y1076691D01*
X1687934D01*
X1688384Y1076241D01*
Y1075196D01*
G01X1696425Y1071163D02*
Y1071275D01*
X1696245Y1071455D01*
Y1076215D01*
X1694371Y1078089D01*
Y1082226D01*
X1694821Y1082676D01*
X1695866D01*
G01X1683330Y1069177D02*
Y1069289D01*
X1683150Y1069469D01*
Y1083765D01*
X1683557Y1084172D01*
X1684194D01*
X1684644Y1083722D01*
Y1082677D01*
G01X1682220Y1069177D02*
Y1069289D01*
X1682400Y1069469D01*
Y1084076D01*
X1683246Y1084922D01*
X1684194D01*
X1684644Y1085372D01*
Y1086417D01*
G01X1679590Y1069000D02*
Y1069112D01*
X1679410Y1069292D01*
Y1076284D01*
X1679817Y1076691D01*
X1680454D01*
X1680904Y1076241D01*
Y1075196D01*
G01X1678480Y1069000D02*
Y1069112D01*
X1678660Y1069292D01*
Y1076595D01*
X1679506Y1077441D01*
X1680454D01*
X1680904Y1077891D01*
Y1078936D01*
G01X1672110Y1069000D02*
Y1069112D01*
X1671930Y1069292D01*
Y1076284D01*
X1672337Y1076691D01*
X1672974D01*
X1673424Y1076241D01*
Y1075196D01*
G01X1671000Y1069000D02*
Y1069112D01*
X1671180Y1069292D01*
Y1076595D01*
X1672026Y1077441D01*
X1672974D01*
X1673424Y1077891D01*
Y1078936D01*
G01X1674740Y1069177D02*
Y1069289D01*
X1674920Y1069469D01*
Y1084076D01*
X1675766Y1084922D01*
X1676714D01*
X1677164Y1085372D01*
Y1086417D01*
G01X1668370Y1069176D02*
Y1069288D01*
X1668190Y1069468D01*
Y1083764D01*
X1668597Y1084171D01*
X1669234D01*
X1669684Y1083721D01*
Y1082676D01*
G01X1675850Y1069177D02*
Y1069289D01*
X1675670Y1069469D01*
Y1083765D01*
X1676077Y1084172D01*
X1676714D01*
X1677164Y1083722D01*
Y1082677D01*
G01X1667260Y1069176D02*
Y1069288D01*
X1667440Y1069468D01*
Y1084075D01*
X1668286Y1084921D01*
X1669234D01*
X1669684Y1085371D01*
Y1086416D01*
G01X1665944Y1078936D02*
Y1077891D01*
X1665494Y1077441D01*
X1664546D01*
X1663700Y1076595D01*
Y1069292D01*
X1663520Y1069112D01*
Y1069000D01*
G01X1665944Y1075196D02*
Y1076241D01*
X1665494Y1076691D01*
X1664857D01*
X1664450Y1076284D01*
Y1069292D01*
X1664630Y1069112D01*
Y1069000D01*
G01X1673425Y1250984D02*
Y1252029D01*
X1672975Y1252479D01*
X1672069D01*
X1671180Y1253368D01*
Y1259308D01*
X1671000Y1259488D01*
Y1259600D01*
G01X1672110D02*
Y1259488D01*
X1671930Y1259308D01*
Y1253679D01*
X1672380Y1253229D01*
X1672975D01*
X1673425Y1253679D01*
Y1254724D01*
G01X1674740Y1259600D02*
Y1259488D01*
X1674920Y1259308D01*
Y1245887D01*
X1675809Y1244998D01*
X1676715D01*
X1677165Y1244548D01*
Y1243503D01*
G01X1675850Y1259600D02*
Y1259488D01*
X1675670Y1259308D01*
Y1246198D01*
X1676120Y1245748D01*
X1676715D01*
X1677165Y1246198D01*
Y1247243D01*
G01X1679590Y1259600D02*
Y1259488D01*
X1679410Y1259308D01*
Y1253679D01*
X1679860Y1253229D01*
X1680455D01*
X1680905Y1253679D01*
Y1254724D01*
G01X1678480Y1259600D02*
Y1259488D01*
X1678660Y1259308D01*
Y1253368D01*
X1679549Y1252479D01*
X1680455D01*
X1680905Y1252029D01*
Y1250984D01*
G01X1682220Y1259600D02*
Y1259488D01*
X1682400Y1259308D01*
Y1245887D01*
X1683289Y1244998D01*
X1684195D01*
X1684645Y1244548D01*
Y1243503D01*
G01X1683330Y1259600D02*
Y1259488D01*
X1683150Y1259308D01*
Y1246198D01*
X1683600Y1245748D01*
X1684195D01*
X1684645Y1246198D01*
Y1247243D01*
G01X1693441Y1256012D02*
Y1255900D01*
X1693621Y1255720D01*
Y1247693D01*
X1693171Y1247243D01*
X1692126D01*
G01X1688385Y1254724D02*
Y1253679D01*
X1687935Y1253229D01*
X1687340D01*
X1686890Y1253679D01*
Y1259320D01*
X1687070Y1259500D01*
Y1259612D01*
G01X1688385Y1250984D02*
Y1252029D01*
X1687935Y1252479D01*
X1687029D01*
X1686140Y1253368D01*
Y1259320D01*
X1685960Y1259500D01*
Y1259612D01*
G01X1694551Y1256012D02*
Y1255900D01*
X1694371Y1255720D01*
Y1247693D01*
X1694821Y1247243D01*
X1695866D01*
G01Y1221062D02*
X1694821D01*
X1694371Y1221512D01*
Y1222107D01*
X1694821Y1222557D01*
X1700420D01*
X1700600Y1222377D01*
X1700712D01*
G01X1692126Y1221062D02*
X1693171D01*
X1693621Y1221512D01*
Y1222418D01*
X1694510Y1223307D01*
X1700420D01*
X1700600Y1223487D01*
X1700712D01*
G01X1700612Y1219747D02*
X1700500D01*
X1700320Y1219567D01*
X1687029D01*
X1686140Y1218678D01*
Y1217772D01*
X1685690Y1217322D01*
X1684645D01*
G01X1700612Y1218637D02*
X1700500D01*
X1700320Y1218817D01*
X1687340D01*
X1686890Y1218367D01*
Y1217772D01*
X1687340Y1217322D01*
X1688385D01*
G01X1684645Y1202362D02*
X1685690D01*
X1686140Y1202812D01*
Y1203718D01*
X1687029Y1204607D01*
X1700532D01*
X1700712Y1204787D01*
X1700824D01*
G01X1700854Y1201046D02*
X1700742D01*
X1700562Y1200866D01*
X1694510D01*
X1693621Y1199977D01*
Y1199071D01*
X1693171Y1198621D01*
X1692126D01*
G01X1688385Y1202362D02*
X1687340D01*
X1686890Y1202812D01*
Y1203407D01*
X1687340Y1203857D01*
X1700532D01*
X1700712Y1203677D01*
X1700824D01*
G01X1692126Y1213582D02*
X1693171D01*
X1693621Y1214032D01*
Y1214938D01*
X1694510Y1215827D01*
X1700452D01*
X1700632Y1216007D01*
X1700744D01*
G01X1684645Y1209842D02*
X1685690D01*
X1686140Y1210292D01*
Y1211198D01*
X1687029Y1212087D01*
X1700696D01*
X1700876Y1212267D01*
X1700988D01*
G01X1692126Y1206102D02*
X1693171D01*
X1693621Y1206552D01*
Y1207458D01*
X1694510Y1208347D01*
X1700232D01*
X1700412Y1208527D01*
X1700524D01*
G01X1688385Y1209842D02*
X1687340D01*
X1686890Y1210292D01*
Y1210887D01*
X1687340Y1211337D01*
X1700696D01*
X1700876Y1211157D01*
X1700988D01*
G01X1695866Y1213582D02*
X1694821D01*
X1694371Y1214032D01*
Y1214627D01*
X1694821Y1215077D01*
X1700452D01*
X1700632Y1214897D01*
X1700744D01*
G01X1700854Y1199936D02*
X1700742D01*
X1700562Y1200116D01*
X1694821D01*
X1694371Y1199666D01*
Y1199071D01*
X1694821Y1198621D01*
X1695866D01*
G01Y1206102D02*
X1694821D01*
X1694371Y1206552D01*
Y1207147D01*
X1694821Y1207597D01*
X1700232D01*
X1700412Y1207417D01*
X1700524D01*
G54D25*
X1250055Y1739208D03*
Y1749208D03*
G54D16*
X145078Y1198621D03*
Y1191141D03*
X148818D03*
Y1198621D03*
X145078Y1221062D03*
X148818D03*
Y1213582D03*
X145078D03*
Y1206102D03*
X148818D03*
Y1247243D03*
X145078D03*
X161909Y1073326D03*
Y1077066D03*
X165649Y1080807D03*
Y1088287D03*
X161909D03*
X158169Y1080807D03*
Y1084547D03*
Y1088287D03*
X165649Y1084547D03*
X156299Y1187401D03*
X152559D03*
X156299Y1202362D03*
Y1194881D03*
X152559Y1202362D03*
Y1194881D03*
X156299Y1217322D03*
Y1209842D03*
X152559D03*
Y1217322D03*
Y1250984D03*
Y1254724D03*
X160039D03*
X156299Y1243503D03*
Y1247243D03*
X163779Y1243503D03*
X160039Y1250984D03*
X163779Y1247243D03*
X174998Y1071455D03*
X182479D03*
X178740Y1075196D03*
X171259D03*
X178740Y1078936D03*
X174999Y1086417D03*
Y1082677D03*
X171259Y1078936D03*
X182480Y1086417D03*
Y1082677D03*
X176870Y1151870D03*
Y1148129D03*
Y1144389D03*
Y1166830D03*
Y1159350D03*
Y1174310D03*
Y1178051D03*
Y1181791D03*
X167519Y1254724D03*
Y1250984D03*
X178740Y1247243D03*
X182480Y1254724D03*
Y1250984D03*
X171259Y1247243D03*
X174999Y1250984D03*
X171259Y1243503D03*
X174999Y1254724D03*
X178740Y1243503D03*
X197439Y1071455D03*
X189959D03*
X186220Y1075196D03*
X193700D03*
X189960Y1086417D03*
Y1082677D03*
X193700Y1078936D03*
X186220D03*
X197440Y1086417D03*
Y1082677D03*
X191830Y1136909D03*
X184350Y1144389D03*
Y1185531D03*
X191830Y1193011D03*
X197440Y1254724D03*
Y1250984D03*
X193700Y1247243D03*
Y1243503D03*
X189960Y1254724D03*
Y1250984D03*
X186220Y1247243D03*
Y1243503D03*
X201181Y1075196D03*
X208661D03*
X204920Y1071455D03*
X212400D03*
X208661Y1078936D03*
X212401Y1086417D03*
Y1082677D03*
X204921Y1086417D03*
Y1082677D03*
X201181Y1078936D03*
X213969Y1445013D03*
Y1453293D03*
Y1456013D03*
Y1464293D03*
X219880Y1071455D03*
X227361D03*
X223622Y1075196D03*
X216141D03*
X227362Y1086417D03*
Y1082677D03*
X219881Y1086417D03*
Y1082677D03*
X223622Y1078936D03*
X216141D03*
X227249Y1445013D03*
Y1464293D03*
Y1456013D03*
Y1453293D03*
X234841Y1075195D03*
X242321Y1075196D03*
Y1078936D03*
X246061Y1082677D03*
X238581Y1082676D03*
X234841Y1078935D03*
X246061Y1086417D03*
X238581Y1086416D03*
X249802Y1075196D03*
X257282D03*
X249802Y1078936D03*
X261022Y1086417D03*
X253542Y1082676D03*
X257282Y1078936D03*
X253542Y1086416D03*
X261022Y1082677D03*
X253543Y1221062D03*
X261023D03*
X257283D03*
X247932Y1211711D03*
X251673D03*
X257283Y1228543D03*
X253543Y1236023D03*
X257283Y1224803D03*
X261023Y1236023D03*
X253543Y1232283D03*
X261023D03*
X253543Y1239763D03*
X257283D03*
X261023Y1243503D03*
Y1247243D03*
X279723Y1075196D03*
X264762D03*
X272243D03*
X275982Y1082677D03*
Y1086417D03*
X268502Y1082676D03*
X272243Y1078936D03*
X268502Y1086416D03*
X279723Y1078936D03*
X264762D03*
X274114Y1129429D03*
Y1140649D03*
Y1136909D03*
Y1144389D03*
X270373Y1181791D03*
X274114Y1185531D03*
Y1189271D03*
Y1200491D03*
Y1193011D03*
X264763Y1221062D03*
X272244D03*
X268503D03*
X274114Y1211712D03*
X281594D03*
X270374Y1215452D03*
X272244Y1224803D03*
X268503Y1236023D03*
Y1232283D03*
X272244Y1228543D03*
X264763Y1224803D03*
X275984Y1232283D03*
Y1236023D03*
X264763Y1228543D03*
Y1254724D03*
Y1250984D03*
X268503Y1243503D03*
Y1247243D03*
X272244Y1254724D03*
Y1250984D03*
X275984Y1243503D03*
Y1247243D03*
X279724Y1250984D03*
Y1239763D03*
X264763D03*
X272244D03*
X279724Y1254724D03*
X287203Y1075196D03*
X294684D03*
X290943Y1086417D03*
X287203Y1078936D03*
X290943Y1082677D03*
X283463Y1082676D03*
Y1086416D03*
X294684Y1078936D03*
X281594Y1181791D03*
X285334Y1204232D03*
X281594Y1200491D03*
X285334Y1211712D03*
X290944Y1236023D03*
X283464D03*
X287204Y1254724D03*
X283464Y1243503D03*
X294685Y1247243D03*
Y1243503D03*
X287204Y1239763D03*
X294685D03*
X290944D03*
X283464Y1247243D03*
X287204Y1250984D03*
X294685Y1258465D03*
X302164Y1075196D03*
X309644D03*
X305904Y1082677D03*
X302164Y1078936D03*
X305904Y1086417D03*
X309644Y1078936D03*
X298424Y1086416D03*
Y1082676D03*
X298425Y1236023D03*
X305905D03*
X309645Y1247243D03*
Y1243503D03*
X298425Y1250984D03*
X302165Y1247243D03*
Y1243503D03*
X305905Y1239763D03*
X302165D03*
X305905Y1250984D03*
X298425Y1254724D03*
X305905D03*
X298425Y1239763D03*
X309645D03*
Y1258465D03*
X302165D03*
X317124Y1075196D03*
X324606Y1082676D03*
X317124Y1078936D03*
X313384Y1082677D03*
Y1086417D03*
X320866Y1082676D03*
X313385Y1120078D03*
X324606Y1123818D03*
Y1108858D03*
X320866D03*
X317125Y1112598D03*
X324606Y1116338D03*
X313385Y1112598D03*
X317125Y1120078D03*
X320866Y1116338D03*
Y1123818D03*
X313385Y1127558D03*
X317125Y1135039D03*
X313385D03*
X324606Y1131299D03*
X317125Y1127558D03*
X320866Y1131299D03*
X328347Y1221062D03*
Y1213582D03*
X324606Y1217322D03*
X320866Y1236023D03*
Y1232283D03*
X313385Y1236023D03*
X324606Y1232283D03*
Y1236023D03*
Y1224803D03*
X328347Y1228543D03*
Y1239762D03*
Y1247243D03*
X320866Y1250984D03*
Y1243503D03*
X313385Y1250984D03*
X317125Y1247243D03*
Y1243503D03*
X324606D03*
Y1250984D03*
X313385Y1254724D03*
X317125Y1239763D03*
X313385D03*
X320866Y1254724D03*
X317125Y1258465D03*
X438162Y1348187D03*
Y1360099D03*
Y1384297D03*
Y1372385D03*
X450402Y1348187D03*
X458282D03*
X446042D03*
X450402Y1360099D03*
X458282D03*
X446042D03*
X458282Y1372385D03*
X446042D03*
X458282Y1384297D03*
X446042D03*
X450402D03*
Y1372385D03*
X458282Y1396583D03*
X450402D03*
X458282Y1408495D03*
X450402D03*
X641437Y1151870D03*
X645177Y1148129D03*
X641437Y1170570D03*
Y1159350D03*
Y1178051D03*
X645177Y1181791D03*
X667618Y1144389D03*
X663878D03*
X660138D03*
X656398D03*
X667618Y1151870D03*
X663878D03*
X660138D03*
X656398D03*
X667618Y1185531D03*
X660138D03*
X656398D03*
X663878D03*
X667618Y1178051D03*
X663878D03*
X660138D03*
X656398D03*
X662008Y1254724D03*
X665748Y1247243D03*
X669488Y1250984D03*
X658268Y1247243D03*
X662008Y1250984D03*
X665748Y1243503D03*
X669488Y1254724D03*
X658268Y1243503D03*
X678839Y1151870D03*
X675098D03*
X671358D03*
X682579D03*
Y1144389D03*
X671358D03*
X678838D03*
X675098D03*
X682579Y1185531D03*
X675098D03*
X671358D03*
X678838D03*
X682579Y1178051D03*
X678838D03*
X675098D03*
X671358D03*
X673228Y1243503D03*
X680709Y1247243D03*
X673228D03*
X684449Y1254724D03*
Y1250984D03*
X676968Y1254724D03*
Y1250984D03*
X680709Y1243503D03*
X699408Y1075196D03*
X691928Y1075195D03*
Y1078935D03*
X699408Y1078936D03*
X695668Y1086416D03*
Y1082676D03*
X701279Y1151869D03*
X697539D03*
X693799D03*
X701279Y1144389D03*
X697539D03*
X693799D03*
X686319D03*
Y1151870D03*
X701279Y1185531D03*
X697539D03*
X693799D03*
X701279Y1178051D03*
X697539D03*
X693799D03*
X686319Y1185531D03*
Y1178051D03*
X699409Y1254724D03*
X691929Y1250984D03*
X688189Y1247243D03*
Y1243503D03*
X691929Y1254724D03*
X695669Y1247243D03*
X699409Y1250984D03*
X695669Y1243503D03*
X706889Y1075196D03*
X714369D03*
X706889Y1078936D03*
X718109Y1086417D03*
X714369Y1078936D03*
X703148Y1082677D03*
X710629Y1086416D03*
X703148Y1086417D03*
X718109Y1082677D03*
X710629Y1082676D03*
X716240Y1151869D03*
X708760D03*
X712500D03*
X705020D03*
X712500Y1144389D03*
X705020D03*
X708760D03*
X716240D03*
Y1185531D03*
X708760D03*
X712500D03*
X705020D03*
X716240Y1178051D03*
X712500D03*
X705020D03*
X708760D03*
X705019Y1211711D03*
X708760D03*
X706890Y1250984D03*
X703149Y1243503D03*
X714370Y1254724D03*
Y1250984D03*
X710630Y1247243D03*
X706890Y1254724D03*
X710630Y1243503D03*
X703149Y1247243D03*
X721849Y1075196D03*
X729330D03*
X725589Y1086416D03*
X733069Y1086417D03*
X721849Y1078936D03*
X729330D03*
X733069Y1082677D03*
X725589Y1082676D03*
X719980Y1151869D03*
X723720D03*
Y1144389D03*
X719980D03*
Y1159350D03*
X727460D03*
X723720D03*
Y1166830D03*
X727460D03*
X719980Y1170570D03*
X727460D03*
X723720D03*
X719980Y1185531D03*
Y1178051D03*
X723720D03*
Y1185531D03*
X731201Y1211712D03*
X727461Y1215452D03*
X736810Y1075196D03*
X744290D03*
Y1078936D03*
X748030Y1086417D03*
X740550Y1086416D03*
Y1082676D03*
X736810Y1078936D03*
X748030Y1082677D03*
X738681Y1118208D03*
X742421D03*
X738681Y1200491D03*
X742421Y1204232D03*
Y1211712D03*
X738681D03*
X748031Y1247243D03*
Y1243503D03*
X751771Y1075196D03*
X766731D03*
X759251D03*
X762991Y1086417D03*
X766731Y1078936D03*
X755511Y1086416D03*
X759251Y1078936D03*
X755511Y1082676D03*
X762991Y1082677D03*
X751771Y1078936D03*
X766732Y1250984D03*
X755512Y1243503D03*
X762992D03*
Y1247243D03*
X751772Y1250984D03*
Y1254724D03*
X759252D03*
X766732D03*
X759252Y1250984D03*
X755512Y1247243D03*
X774211Y1075196D03*
X781693Y1082676D03*
X774211Y1078936D03*
X770471Y1086417D03*
Y1082677D03*
X777953Y1082676D03*
X774212Y1112598D03*
X770472D03*
X781693Y1123818D03*
X777953D03*
X781693Y1116338D03*
X777953Y1108858D03*
X770472Y1120078D03*
X781693Y1108858D03*
X777953Y1116338D03*
X774212Y1120078D03*
X770472Y1127558D03*
Y1135039D03*
X781693Y1131299D03*
X774212Y1127558D03*
Y1135039D03*
X777953Y1131299D03*
X781693Y1198621D03*
X774212Y1202362D03*
X770472D03*
X777953Y1198621D03*
Y1206102D03*
X770472Y1209842D03*
X781693Y1213582D03*
X774212Y1209842D03*
X777953Y1221062D03*
X781693D03*
Y1206102D03*
X770472Y1217322D03*
X774212D03*
X777953Y1213582D03*
Y1247243D03*
X770472Y1243503D03*
X781693Y1247243D03*
X770472D03*
X774212Y1250984D03*
Y1254724D03*
X1057381Y1084547D03*
X1059251Y1198621D03*
Y1191141D03*
Y1221062D03*
Y1206102D03*
Y1213582D03*
Y1247243D03*
X1068602Y1073326D03*
X1072342Y1088287D03*
Y1084547D03*
Y1080807D03*
X1064861Y1077066D03*
X1064862Y1088287D03*
X1068602D03*
X1061121Y1084547D03*
X1064862D03*
Y1080807D03*
X1061121Y1080806D03*
Y1077066D03*
X1068602D03*
X1070472Y1187401D03*
X1066732D03*
X1062991Y1198621D03*
X1066732Y1194881D03*
X1062991Y1191141D03*
X1070472Y1194881D03*
Y1202362D03*
X1066732D03*
X1070472Y1217322D03*
X1066732D03*
X1062991Y1221062D03*
Y1206102D03*
X1070472Y1209842D03*
X1062991Y1213582D03*
X1066732Y1209842D03*
X1074212Y1250984D03*
X1066732Y1254724D03*
X1070472Y1247243D03*
X1074212Y1254724D03*
X1062991Y1247243D03*
X1070472Y1243503D03*
X1066732Y1250984D03*
X1083562Y1073326D03*
X1076082D03*
X1089171Y1071455D03*
X1083562Y1088287D03*
Y1077066D03*
X1079822Y1088287D03*
Y1084547D03*
Y1080807D03*
X1076082Y1088287D03*
Y1077066D03*
X1089172Y1082677D03*
Y1086417D03*
X1091043Y1151870D03*
Y1148129D03*
Y1144389D03*
Y1166830D03*
Y1159350D03*
Y1181791D03*
Y1178051D03*
Y1174310D03*
X1077952Y1243503D03*
X1081692Y1250984D03*
X1077952Y1247243D03*
X1081692Y1254724D03*
X1085432Y1243503D03*
X1089172Y1254724D03*
Y1250984D03*
X1085432Y1247243D03*
X1092913Y1075196D03*
X1107873D03*
X1100393D03*
X1104132Y1071455D03*
X1096652D03*
X1092913Y1078936D03*
X1104133Y1086417D03*
Y1082677D03*
X1107873Y1078936D03*
X1100393D03*
X1096653Y1082677D03*
Y1086417D03*
X1106003Y1136909D03*
X1098523Y1144389D03*
Y1185531D03*
X1106003Y1193011D03*
X1096653Y1254724D03*
X1104133D03*
X1092913Y1247243D03*
X1096653Y1250984D03*
X1092913Y1243503D03*
X1107873D03*
X1100393D03*
X1107873Y1247243D03*
X1100393D03*
X1104133Y1250984D03*
X1115354Y1075196D03*
X1122834D03*
X1119093Y1071455D03*
X1111612D03*
X1115354Y1078936D03*
X1119094Y1082677D03*
Y1086417D03*
X1122834Y1078936D03*
X1111613Y1082677D03*
Y1086417D03*
Y1254724D03*
Y1250984D03*
X1130314Y1075196D03*
X1137795D03*
X1134053Y1071455D03*
X1126573D03*
X1126574Y1086417D03*
Y1082677D03*
X1130314Y1078936D03*
X1134054Y1082677D03*
Y1086417D03*
X1137795Y1078936D03*
X1141534Y1071455D03*
X1156494Y1075196D03*
X1149014Y1075195D03*
X1141535Y1082677D03*
Y1086417D03*
X1149014Y1078935D03*
X1156494Y1078936D03*
X1152754Y1086416D03*
Y1082676D03*
X1163975Y1075196D03*
X1171455D03*
X1160234Y1086417D03*
X1167715Y1086416D03*
X1163975Y1078936D03*
X1160234Y1082677D03*
X1171455Y1078936D03*
X1167715Y1082676D03*
X1171456Y1221062D03*
X1167716D03*
X1162105Y1211711D03*
X1165846D03*
X1171456Y1228543D03*
Y1224803D03*
X1167716Y1232283D03*
Y1236023D03*
Y1239763D03*
X1171456D03*
X1178935Y1075196D03*
X1186416D03*
X1175195Y1086417D03*
X1182675Y1086416D03*
X1175195Y1082677D03*
X1178935Y1078936D03*
X1182675Y1082676D03*
X1186416Y1078936D03*
X1188287Y1129429D03*
Y1136909D03*
Y1140649D03*
Y1144389D03*
X1184546Y1181791D03*
X1188287Y1185531D03*
Y1189271D03*
Y1200491D03*
Y1193011D03*
X1186417Y1221062D03*
X1182676D03*
X1178936D03*
X1175196D03*
X1188287Y1211712D03*
X1175196Y1232283D03*
Y1236023D03*
X1178936Y1228543D03*
Y1224803D03*
X1182676Y1232283D03*
Y1236023D03*
X1186417Y1228543D03*
Y1224803D03*
X1178936Y1239763D03*
X1186417D03*
X1178936Y1254724D03*
X1175196Y1243503D03*
X1182676Y1247243D03*
X1178936Y1250984D03*
X1186417D03*
X1182676Y1243503D03*
X1186417Y1254724D03*
X1175196Y1247243D03*
X1193896Y1075196D03*
X1201376D03*
X1190155Y1086417D03*
X1205116Y1082677D03*
X1190155D03*
X1197636Y1082676D03*
X1193896Y1078936D03*
X1205116Y1086417D03*
X1201376Y1078936D03*
X1197636Y1086416D03*
X1195767Y1181791D03*
X1199507Y1204232D03*
X1195767Y1200491D03*
X1205117Y1221062D03*
X1201377D03*
X1197637D03*
X1193897D03*
X1190157D03*
X1199507Y1211712D03*
X1190157Y1232283D03*
Y1236023D03*
X1197637Y1232283D03*
X1201377Y1228543D03*
X1197637Y1236023D03*
X1201377Y1224803D03*
X1205117Y1232283D03*
Y1236023D03*
X1193897Y1228543D03*
Y1224803D03*
X1201377Y1239763D03*
X1205117D03*
X1193897D03*
X1190157Y1243503D03*
X1201377Y1250984D03*
X1197637Y1247243D03*
X1193897Y1250984D03*
X1201377Y1254724D03*
X1197637Y1243503D03*
X1193897Y1254724D03*
X1190157Y1247243D03*
X1216337Y1075196D03*
X1208857D03*
X1212597Y1082676D03*
Y1086416D03*
X1220077Y1086417D03*
X1208857Y1078936D03*
X1216337D03*
X1220077Y1082677D03*
X1220078Y1221062D03*
X1216338D03*
X1212598D03*
X1208858D03*
X1216338Y1224803D03*
Y1228543D03*
X1212598Y1232283D03*
Y1236023D03*
X1220078Y1232283D03*
Y1236023D03*
X1208858Y1224803D03*
Y1228543D03*
X1212598Y1250984D03*
Y1254724D03*
X1216338Y1247243D03*
Y1243503D03*
X1220078Y1250984D03*
Y1254724D03*
X1212598Y1239763D03*
X1216338D03*
X1220078D03*
X1208858Y1247243D03*
Y1243503D03*
Y1239763D03*
X1216338Y1258465D03*
X1208858D03*
X1231297Y1075196D03*
X1223817D03*
X1231297Y1078936D03*
X1235039Y1082676D03*
X1227557Y1086417D03*
X1223817Y1078936D03*
X1227557Y1082677D03*
X1227558Y1112598D03*
X1235039Y1123818D03*
X1231298Y1120078D03*
Y1112598D03*
X1235039Y1108858D03*
Y1116338D03*
X1227558Y1120078D03*
X1231298Y1135039D03*
X1227558Y1127558D03*
X1235039Y1131299D03*
X1231298Y1127558D03*
X1227558Y1135039D03*
X1229428Y1196751D03*
X1233169D03*
X1235039Y1202362D03*
X1231298Y1198621D03*
X1223818Y1221062D03*
X1231298Y1206102D03*
X1235039Y1217322D03*
X1231298Y1221062D03*
X1227558D03*
X1235039Y1209842D03*
X1231298Y1213582D03*
X1223818Y1224803D03*
Y1228543D03*
X1235039Y1224803D03*
X1231298D03*
Y1228543D03*
X1227558Y1236023D03*
Y1232283D03*
X1235039D03*
Y1236023D03*
X1225688Y1222932D03*
X1223818Y1247243D03*
Y1243503D03*
Y1239763D03*
X1227558Y1250984D03*
Y1254724D03*
X1235039Y1250984D03*
X1231298Y1247243D03*
Y1243503D03*
X1235039D03*
X1227558Y1239763D03*
X1231298D03*
X1235039Y1254724D03*
X1231298Y1258465D03*
X1223818D03*
X1238779Y1082676D03*
Y1108858D03*
Y1116338D03*
Y1123818D03*
Y1131299D03*
Y1202362D03*
X1242520Y1198621D03*
X1238779Y1217322D03*
Y1209842D03*
X1242520Y1221062D03*
Y1213582D03*
Y1206102D03*
X1238779Y1224803D03*
Y1232283D03*
Y1236023D03*
X1242520Y1228543D03*
X1238779Y1250984D03*
Y1243503D03*
X1242520Y1247243D03*
Y1239762D03*
X1555610Y1151870D03*
X1559350Y1148129D03*
X1555610Y1170570D03*
Y1159350D03*
X1559350Y1181791D03*
X1555610Y1178051D03*
X1578051Y1144389D03*
X1574311D03*
X1570571D03*
X1578051Y1151870D03*
X1574311D03*
X1570571D03*
X1574311Y1185531D03*
X1570571D03*
X1578051D03*
Y1178051D03*
X1574311D03*
X1570571D03*
X1572441Y1247243D03*
X1576181Y1254724D03*
Y1250984D03*
X1572441Y1243503D03*
X1585531Y1144389D03*
X1581791D03*
X1593011D03*
X1589271D03*
X1593012Y1151870D03*
X1589271D03*
X1585531D03*
X1581791D03*
X1589271Y1185531D03*
X1585531D03*
X1581791D03*
X1593011D03*
X1581791Y1178051D03*
X1593011D03*
X1589271D03*
X1585531D03*
X1583661Y1254724D03*
X1579921Y1247243D03*
X1591141Y1254724D03*
X1587401Y1247243D03*
Y1243503D03*
X1594882D03*
X1579921D03*
X1594882Y1247243D03*
X1583661Y1250984D03*
X1591141D03*
X1606101Y1075195D03*
X1609841Y1086416D03*
X1606101Y1078935D03*
X1609841Y1082676D03*
X1600492Y1144389D03*
X1596752D03*
X1611712Y1151869D03*
X1607972D03*
X1611712Y1144389D03*
X1607972D03*
X1600492Y1151870D03*
X1596752D03*
X1600492Y1185531D03*
X1596752D03*
X1600492Y1178051D03*
X1596752D03*
X1611712Y1185531D03*
X1607972D03*
X1611712Y1178051D03*
X1607972D03*
X1598622Y1254724D03*
Y1250984D03*
X1609842Y1247243D03*
X1606102Y1250984D03*
Y1254724D03*
X1609842Y1243503D03*
X1602362Y1247243D03*
Y1243503D03*
X1613581Y1075196D03*
X1621062D03*
X1613581Y1078936D03*
X1624802Y1082676D03*
X1617321Y1082677D03*
X1621062Y1078936D03*
X1617321Y1086417D03*
X1624802Y1086416D03*
X1615452Y1151869D03*
X1619193D03*
X1626673D03*
X1622933D03*
Y1144389D03*
X1615452D03*
X1619193D03*
X1626673D03*
X1619193Y1185531D03*
X1626673D03*
X1622933D03*
Y1178051D03*
X1615452D03*
X1619193D03*
X1626673D03*
X1615452Y1185531D03*
X1619192Y1211711D03*
X1622933D03*
X1624803Y1247243D03*
Y1243503D03*
X1621063Y1254724D03*
X1613582Y1250984D03*
X1617322Y1243503D03*
Y1247243D03*
X1613582Y1254724D03*
X1621063Y1250984D03*
X1636022Y1075196D03*
X1643503D03*
X1628542D03*
X1632282Y1082677D03*
X1643503Y1078936D03*
X1628542D03*
X1639762Y1086416D03*
X1632282Y1086417D03*
X1636022Y1078936D03*
X1639762Y1082676D03*
X1630413Y1151869D03*
X1637893D03*
X1634153D03*
Y1144389D03*
X1630413D03*
X1637893D03*
Y1170570D03*
X1641633D03*
X1634153D03*
X1641633Y1166830D03*
X1637893D03*
Y1159350D03*
X1641633D03*
X1634153D03*
X1630413Y1185531D03*
X1634153D03*
X1630413Y1178051D03*
X1634153D03*
X1637893Y1185531D03*
Y1178051D03*
X1628543Y1250984D03*
Y1254724D03*
X1650983Y1075196D03*
X1658463D03*
X1654723Y1086416D03*
Y1082676D03*
X1650983Y1078936D03*
X1647242Y1082677D03*
Y1086417D03*
X1658463Y1078936D03*
X1656594Y1118208D03*
X1652854D03*
X1656594Y1204232D03*
X1652854Y1200491D03*
X1656594Y1211712D03*
X1645374D03*
X1673424Y1075196D03*
X1665944D03*
X1662203Y1086417D03*
Y1082677D03*
X1669684Y1086416D03*
X1665944Y1078936D03*
X1673424D03*
X1669684Y1082676D03*
X1673425Y1250984D03*
X1662204Y1247243D03*
X1665945Y1254724D03*
X1673425D03*
X1662204Y1243503D03*
X1665945Y1250984D03*
X1669685Y1247243D03*
Y1243503D03*
X1680904Y1075196D03*
X1688384D03*
X1692126Y1082676D03*
X1684644Y1082677D03*
Y1086417D03*
X1680904Y1078936D03*
X1688384D03*
X1677164Y1086417D03*
Y1082677D03*
X1692126Y1116338D03*
Y1108858D03*
X1684645Y1120078D03*
X1688385D03*
X1684645Y1112598D03*
X1692126Y1123818D03*
X1688385Y1112598D03*
X1684645Y1135039D03*
Y1127558D03*
X1692126Y1131299D03*
X1688385Y1127558D03*
Y1135039D03*
X1684645Y1202362D03*
X1692126Y1198621D03*
X1688385Y1202362D03*
X1692126Y1213582D03*
X1684645Y1217322D03*
Y1209842D03*
X1692126Y1206102D03*
Y1221062D03*
X1688385Y1209842D03*
Y1217322D03*
X1684645Y1243503D03*
X1677165D03*
X1692126Y1247243D03*
X1684645D03*
X1677165D03*
X1688385Y1254724D03*
Y1250984D03*
X1680905Y1254724D03*
Y1250984D03*
X1695866Y1082676D03*
Y1123818D03*
Y1116338D03*
Y1108858D03*
Y1131299D03*
Y1198621D03*
Y1221062D03*
Y1213582D03*
Y1206102D03*
Y1247243D03*
G54D35*
G01X1169123Y1776014D02*
Y1779850D01*
X1168609Y1780364D01*
X1154730D01*
X1154230Y1779864D01*
Y1772047D01*
X1152969Y1770786D01*
X1146381D01*
X1145120Y1772047D01*
Y1782878D01*
X1144620Y1783378D01*
X1139110D01*
X1138610Y1782878D01*
Y1772047D01*
X1137349Y1770786D01*
X1130761D01*
X1129500Y1772047D01*
Y1782878D01*
X1129000Y1783378D01*
X1123490D01*
X1122990Y1782878D01*
Y1772047D01*
X1121729Y1770786D01*
X1115141D01*
X1113880Y1772047D01*
Y1782878D01*
X1113380Y1783378D01*
X1107870D01*
X1107370Y1782878D01*
Y1772047D01*
X1106109Y1770786D01*
X1099521D01*
X1098260Y1772047D01*
Y1782878D01*
X1097760Y1783378D01*
X1092250D01*
X1091750Y1782878D01*
Y1772047D01*
X1090489Y1770786D01*
X1083901D01*
X1082640Y1772047D01*
Y1782878D01*
X1082140Y1783378D01*
X1076630D01*
X1076130Y1782878D01*
Y1772047D01*
X1074869Y1770786D01*
X1068281D01*
X1067020Y1772047D01*
Y1782878D01*
X1066520Y1783378D01*
X1061010D01*
X1060510Y1782878D01*
Y1772047D01*
X1059249Y1770786D01*
X1052661D01*
X1051400Y1772047D01*
Y1782878D01*
X1050900Y1783378D01*
X1045390D01*
X1044890Y1782878D01*
Y1772047D01*
X1043629Y1770786D01*
X1037041D01*
X1035780Y1772047D01*
Y1782878D01*
X1035280Y1783378D01*
X1029770D01*
X1029270Y1782878D01*
Y1772047D01*
X1028009Y1770786D01*
X1021421D01*
X1020160Y1772047D01*
Y1782878D01*
X1019660Y1783378D01*
X1014150D01*
X1013650Y1782878D01*
Y1772047D01*
X1012389Y1770786D01*
X1005801D01*
X1004540Y1772047D01*
Y1782878D01*
X1004040Y1783378D01*
X998530D01*
X998030Y1782878D01*
Y1772047D01*
X996769Y1770786D01*
X990181D01*
X988920Y1772047D01*
Y1782878D01*
X988420Y1783378D01*
X982910D01*
X982410Y1782878D01*
Y1772047D01*
X981149Y1770786D01*
X974561D01*
X973300Y1772047D01*
Y1782878D01*
X972800Y1783378D01*
X967290D01*
X966790Y1782878D01*
Y1772047D01*
X965529Y1770786D01*
X958941D01*
X957680Y1772047D01*
Y1782878D01*
X957180Y1783378D01*
X951670D01*
X951170Y1782878D01*
Y1772047D01*
X949909Y1770786D01*
X943321D01*
X942060Y1772047D01*
Y1782740D01*
X941560Y1783240D01*
X936050D01*
X935550Y1782740D01*
Y1772047D01*
X934289Y1770786D01*
X927701D01*
X926440Y1772047D01*
Y1779864D01*
X925940Y1780364D01*
X917573D01*
X917073Y1779864D01*
Y1776014D01*
G01X1169123Y1786014D02*
Y1782086D01*
X1168701Y1781664D01*
X1154191D01*
X1152930Y1780403D01*
Y1772596D01*
X1152430Y1772096D01*
X1146920D01*
X1146420Y1772596D01*
Y1783417D01*
X1145159Y1784678D01*
X1138571D01*
X1137310Y1783417D01*
Y1772596D01*
X1136810Y1772096D01*
X1131300D01*
X1130800Y1772596D01*
Y1783417D01*
X1129539Y1784678D01*
X1122951D01*
X1121690Y1783417D01*
Y1772596D01*
X1121190Y1772096D01*
X1115680D01*
X1115180Y1772596D01*
Y1783417D01*
X1113919Y1784678D01*
X1107331D01*
X1106070Y1783417D01*
Y1772596D01*
X1105570Y1772096D01*
X1100060D01*
X1099560Y1772596D01*
Y1783417D01*
X1098299Y1784678D01*
X1091711D01*
X1090450Y1783417D01*
Y1772596D01*
X1089950Y1772096D01*
X1084440D01*
X1083940Y1772596D01*
Y1783417D01*
X1082679Y1784678D01*
X1076091D01*
X1074830Y1783417D01*
Y1772596D01*
X1074330Y1772096D01*
X1068820D01*
X1068320Y1772596D01*
Y1783417D01*
X1067059Y1784678D01*
X1060471D01*
X1059210Y1783417D01*
Y1772596D01*
X1058710Y1772096D01*
X1053200D01*
X1052700Y1772596D01*
Y1783417D01*
X1051439Y1784678D01*
X1044851D01*
X1043590Y1783417D01*
Y1772596D01*
X1043090Y1772096D01*
X1037580D01*
X1037080Y1772596D01*
Y1783417D01*
X1035819Y1784678D01*
X1029231D01*
X1027970Y1783417D01*
Y1772596D01*
X1027470Y1772096D01*
X1021960D01*
X1021460Y1772596D01*
Y1783417D01*
X1020199Y1784678D01*
X1013611D01*
X1012350Y1783417D01*
Y1772596D01*
X1011850Y1772096D01*
X1006340D01*
X1005840Y1772596D01*
Y1783417D01*
X1004579Y1784678D01*
X997991D01*
X996730Y1783417D01*
Y1772596D01*
X996230Y1772096D01*
X990720D01*
X990220Y1772596D01*
Y1783417D01*
X988959Y1784678D01*
X982371D01*
X981110Y1783417D01*
Y1772596D01*
X980610Y1772096D01*
X975100D01*
X974600Y1772596D01*
Y1783417D01*
X973339Y1784678D01*
X966751D01*
X965490Y1783417D01*
Y1772596D01*
X964990Y1772096D01*
X959480D01*
X958980Y1772596D01*
Y1783417D01*
X957719Y1784678D01*
X951131D01*
X949870Y1783417D01*
Y1772596D01*
X949370Y1772096D01*
X943860D01*
X943360Y1772596D01*
Y1783279D01*
X942099Y1784540D01*
X935511D01*
X934250Y1783279D01*
Y1772596D01*
X933750Y1772096D01*
X928240D01*
X927740Y1772596D01*
Y1780403D01*
X926479Y1781664D01*
X917573D01*
X917073Y1782164D01*
Y1786014D01*
G54D26*
X1795453Y812874D03*
Y834922D03*
G54D17*
X190325Y368760D03*
X647411D03*
X1104498D03*
X1561585D03*
G54D36*
G01X109882Y1607048D02*
Y1608552D01*
X110382Y1609052D01*
X111678D01*
X113295Y1607435D01*
Y1556837D01*
X112599Y1555155D01*
X112598Y1555154D01*
X111903Y1553474D01*
X92727Y1540660D01*
X83604Y1531537D01*
X79301Y1521152D01*
X66262Y1455597D01*
X55590Y1383657D01*
Y1348896D01*
X61356Y1302136D01*
X71301Y1250491D01*
X73195Y1243309D01*
X81558Y1223121D01*
X87818Y1211406D01*
X95655Y1199675D01*
X102839Y1192491D01*
X102838D01*
X102995Y1192334D01*
X105766Y1191187D01*
X105765D01*
X113588Y1187946D01*
X128523Y1184976D01*
X142988D01*
G01X109882Y1612166D02*
Y1610662D01*
X110382Y1610162D01*
X112138D01*
X114405Y1607895D01*
Y1556616D01*
X112800Y1552738D01*
X93435Y1539798D01*
X84545Y1530908D01*
X80369Y1520828D01*
X67356Y1455407D01*
X56700Y1383575D01*
Y1348965D01*
X62454Y1302309D01*
X72384Y1250738D01*
X74250Y1243665D01*
X82563Y1223596D01*
X84325Y1220299D01*
X84866Y1220135D01*
X85786Y1218414D01*
X85622Y1217873D01*
X86541Y1216154D01*
X87082Y1215989D01*
X88002Y1214269D01*
X87838Y1213727D01*
X88772Y1211978D01*
X96517Y1200383D01*
X103624Y1193276D01*
X105766Y1192389D01*
X106289Y1192606D01*
X108091Y1191858D01*
X108308Y1191336D01*
X113912Y1189014D01*
X128633Y1186086D01*
X142988D01*
G01X118543Y1616496D02*
Y1614992D01*
X119043Y1614492D01*
X121007D01*
X123067Y1612432D01*
Y1561339D01*
X119428Y1552553D01*
X95559Y1536604D01*
X87757Y1528802D01*
X83971Y1519659D01*
X71058Y1454729D01*
X60700Y1384906D01*
Y1347263D01*
X66171Y1302910D01*
X75747Y1253164D01*
X77166Y1247807D01*
X85591Y1227462D01*
X87224Y1224407D01*
X87765Y1224242D01*
X88685Y1222522D01*
X88521Y1221980D01*
X89440Y1220261D01*
X89981Y1220097D01*
X90901Y1218377D01*
X90737Y1217835D01*
X91656Y1216116D01*
X92197Y1215951D01*
X93118Y1214231D01*
X92953Y1213689D01*
X94511Y1210775D01*
X99278Y1203640D01*
X103178Y1199740D01*
X103800D01*
X105145Y1198395D01*
Y1197773D01*
X106074Y1196844D01*
X107875Y1196098D01*
X108398Y1196314D01*
X110200Y1195566D01*
X110416Y1195044D01*
X112217Y1194298D01*
X112740Y1194514D01*
X114542Y1193766D01*
X114758Y1193244D01*
X117134Y1192259D01*
X129353Y1189826D01*
X140000D01*
G01X118543Y1611378D02*
Y1612882D01*
X119043Y1613382D01*
X120547D01*
X121957Y1611972D01*
Y1561560D01*
X120244Y1557424D01*
X120243Y1557423D01*
X118531Y1553289D01*
X94851Y1537466D01*
X86816Y1529431D01*
X82903Y1519983D01*
X69964Y1454919D01*
X59590Y1384988D01*
Y1347194D01*
X65073Y1302737D01*
X74664Y1252917D01*
X76112Y1247451D01*
X84586Y1226987D01*
X93557Y1210203D01*
X98416Y1202932D01*
X105445Y1195903D01*
X116810Y1191191D01*
X129243Y1188716D01*
X140000D01*
G01X127205Y1607048D02*
Y1608552D01*
X127705Y1609052D01*
X129001D01*
X130618Y1607435D01*
Y1557287D01*
X130018Y1555838D01*
X130017Y1555837D01*
X129418Y1554390D01*
X127751Y1552723D01*
X96985Y1534281D01*
X90299Y1527595D01*
X86364Y1518101D01*
X74154Y1456707D01*
X63490Y1384823D01*
Y1346309D01*
X68791Y1303319D01*
X78098Y1254992D01*
X79117Y1251131D01*
X88461Y1228577D01*
X97831Y1211041D01*
X100871Y1206495D01*
X107752Y1199614D01*
X120036Y1194519D01*
X130392Y1192456D01*
X140000D01*
G01X127205Y1612166D02*
Y1610662D01*
X127705Y1610162D01*
X129461D01*
X131728Y1607895D01*
Y1557066D01*
X130359Y1553761D01*
X128439Y1551841D01*
X97673Y1533399D01*
X91240Y1526966D01*
X87432Y1517777D01*
X75248Y1456517D01*
X64600Y1384741D01*
Y1346378D01*
X69889Y1303492D01*
X79181Y1255239D01*
X80172Y1251487D01*
X89466Y1229052D01*
X91818Y1224650D01*
X92359Y1224486D01*
X93279Y1222765D01*
X93115Y1222223D01*
X94033Y1220504D01*
X94575Y1220340D01*
X95495Y1218619D01*
X95330Y1218077D01*
X96249Y1216358D01*
X96790Y1216194D01*
X97710Y1214473D01*
X97546Y1213932D01*
X98785Y1211613D01*
X101733Y1207203D01*
X108381Y1200555D01*
X120360Y1195587D01*
X130502Y1193566D01*
X140000D01*
G01X135866Y1611378D02*
Y1612882D01*
X136366Y1613382D01*
X137870D01*
X139280Y1611972D01*
Y1561619D01*
X136261Y1554331D01*
X133660Y1551730D01*
X98959Y1530929D01*
X93510Y1525480D01*
X90034Y1517092D01*
X78115Y1457168D01*
X67290Y1384193D01*
Y1346227D01*
X69901Y1325054D01*
X69900D01*
X72508Y1303910D01*
X81765Y1255837D01*
X81866Y1255454D01*
X92107Y1230734D01*
X100712Y1214627D01*
X100715Y1214628D01*
X102421Y1212079D01*
X112947Y1201553D01*
X119962Y1198647D01*
X132274Y1196196D01*
X140000D01*
G01X56248Y1806941D02*
Y1803146D01*
X56898Y1802496D01*
X65043D01*
X66343Y1803796D01*
Y1805770D01*
X68293Y1807720D01*
X71273D01*
X73223Y1805770D01*
Y1798572D01*
X74523Y1797272D01*
X76583D01*
X77883Y1798572D01*
Y1805770D01*
X79833Y1807720D01*
X82813D01*
X84763Y1805770D01*
Y1798572D01*
X86063Y1797272D01*
X88123D01*
X89423Y1798572D01*
Y1805770D01*
X91373Y1807720D01*
X94353D01*
X96303Y1805770D01*
Y1798572D01*
X97603Y1797272D01*
X99663D01*
X100963Y1798572D01*
Y1805770D01*
X102913Y1807720D01*
X105893D01*
X107843Y1805770D01*
Y1798572D01*
X109143Y1797272D01*
X111203D01*
X112503Y1798572D01*
Y1805770D01*
X114453Y1807720D01*
X117433D01*
X119383Y1805770D01*
Y1798572D01*
X120683Y1797272D01*
X122743D01*
X124043Y1798572D01*
Y1805770D01*
X125993Y1807720D01*
X128973D01*
X130923Y1805770D01*
Y1798572D01*
X132223Y1797272D01*
X134283D01*
X135583Y1798572D01*
Y1805770D01*
X137533Y1807720D01*
X140513D01*
X142463Y1805770D01*
Y1798572D01*
X143763Y1797272D01*
X145823D01*
X147123Y1798572D01*
Y1805770D01*
X149073Y1807720D01*
X152053D01*
X154003Y1805770D01*
Y1798572D01*
X155303Y1797272D01*
X157363D01*
X158663Y1798572D01*
Y1805770D01*
X160613Y1807720D01*
X163593D01*
X165543Y1805770D01*
Y1798572D01*
X166843Y1797272D01*
X168903D01*
X170203Y1798572D01*
Y1805770D01*
X172153Y1807720D01*
X175133D01*
X177083Y1805770D01*
Y1798572D01*
X178383Y1797272D01*
X180443D01*
X181743Y1798572D01*
Y1805770D01*
X183693Y1807720D01*
X186673D01*
X188623Y1805770D01*
Y1798572D01*
X189923Y1797272D01*
X191983D01*
X193283Y1798572D01*
Y1805770D01*
X195233Y1807720D01*
X198213D01*
X200163Y1805770D01*
Y1798572D01*
X201463Y1797272D01*
X203523D01*
X204823Y1798572D01*
Y1805770D01*
X206773Y1807720D01*
X209753D01*
X211703Y1805770D01*
Y1798572D01*
X213003Y1797272D01*
X215063D01*
X216363Y1798572D01*
Y1805770D01*
X218313Y1807720D01*
X221293D01*
X223243Y1805770D01*
Y1798572D01*
X224543Y1797272D01*
X226603D01*
X227903Y1798572D01*
Y1805770D01*
X229853Y1807720D01*
X232833D01*
X234783Y1805770D01*
Y1798572D01*
X236083Y1797272D01*
X238143D01*
X239443Y1798572D01*
Y1805770D01*
X241393Y1807720D01*
X244373D01*
X246323Y1805770D01*
Y1798572D01*
X247623Y1797272D01*
X249683D01*
X250983Y1798572D01*
Y1805770D01*
X252933Y1807720D01*
X255913D01*
X257863Y1805770D01*
Y1798572D01*
X259163Y1797272D01*
X261223D01*
X262523Y1798572D01*
Y1805770D01*
X264473Y1807720D01*
X267453D01*
X269403Y1805770D01*
Y1798572D01*
X270703Y1797272D01*
X272763D01*
X274063Y1798572D01*
Y1805770D01*
X276013Y1807720D01*
X278993D01*
X280943Y1805770D01*
Y1798572D01*
X282243Y1797272D01*
X284303D01*
X285603Y1798572D01*
Y1805770D01*
X287553Y1807720D01*
X290533D01*
X292483Y1805770D01*
Y1798572D01*
X293783Y1797272D01*
X295843D01*
X297143Y1798572D01*
Y1800546D01*
X299093Y1802496D01*
X307698D01*
X308348Y1803146D01*
Y1806941D01*
G01X56248Y1796941D02*
Y1800736D01*
X56898Y1801386D01*
X65503D01*
X67453Y1803336D01*
Y1805310D01*
X68753Y1806610D01*
X70813D01*
X72113Y1805310D01*
Y1798112D01*
X74063Y1796162D01*
X77043D01*
X78993Y1798112D01*
Y1805310D01*
X80293Y1806610D01*
X82353D01*
X83653Y1805310D01*
Y1798112D01*
X85603Y1796162D01*
X88583D01*
X90533Y1798112D01*
Y1805310D01*
X91833Y1806610D01*
X93893D01*
X95193Y1805310D01*
Y1798112D01*
X97143Y1796162D01*
X100123D01*
X102073Y1798112D01*
Y1805310D01*
X103373Y1806610D01*
X105433D01*
X106733Y1805310D01*
Y1798112D01*
X108683Y1796162D01*
X111663D01*
X113613Y1798112D01*
Y1805310D01*
X114913Y1806610D01*
X116973D01*
X118273Y1805310D01*
Y1798112D01*
X120223Y1796162D01*
X123203D01*
X125153Y1798112D01*
Y1805310D01*
X126453Y1806610D01*
X128513D01*
X129813Y1805310D01*
Y1798112D01*
X131763Y1796162D01*
X134743D01*
X136693Y1798112D01*
Y1805310D01*
X137993Y1806610D01*
X140053D01*
X141353Y1805310D01*
Y1798112D01*
X143303Y1796162D01*
X146283D01*
X148233Y1798112D01*
Y1805310D01*
X149533Y1806610D01*
X151593D01*
X152893Y1805310D01*
Y1798112D01*
X154843Y1796162D01*
X157823D01*
X159773Y1798112D01*
Y1805310D01*
X161073Y1806610D01*
X163133D01*
X164433Y1805310D01*
Y1798112D01*
X166383Y1796162D01*
X169363D01*
X171313Y1798112D01*
Y1805310D01*
X172613Y1806610D01*
X174673D01*
X175973Y1805310D01*
Y1798112D01*
X177923Y1796162D01*
X180903D01*
X182853Y1798112D01*
Y1805310D01*
X184153Y1806610D01*
X186213D01*
X187513Y1805310D01*
Y1798112D01*
X189463Y1796162D01*
X192443D01*
X194393Y1798112D01*
Y1805310D01*
X195693Y1806610D01*
X197753D01*
X199053Y1805310D01*
Y1798112D01*
X201003Y1796162D01*
X203983D01*
X205933Y1798112D01*
Y1805310D01*
X207233Y1806610D01*
X209293D01*
X210593Y1805310D01*
Y1798112D01*
X212543Y1796162D01*
X215523D01*
X217473Y1798112D01*
Y1805310D01*
X218773Y1806610D01*
X220833D01*
X222133Y1805310D01*
Y1798112D01*
X224083Y1796162D01*
X227063D01*
X229013Y1798112D01*
Y1805310D01*
X230313Y1806610D01*
X232373D01*
X233673Y1805310D01*
Y1798112D01*
X235623Y1796162D01*
X238603D01*
X240553Y1798112D01*
Y1805310D01*
X241853Y1806610D01*
X243913D01*
X245213Y1805310D01*
Y1798112D01*
X247163Y1796162D01*
X250143D01*
X252093Y1798112D01*
Y1805310D01*
X253393Y1806610D01*
X255453D01*
X256753Y1805310D01*
Y1798112D01*
X258703Y1796162D01*
X261683D01*
X263633Y1798112D01*
Y1805310D01*
X264933Y1806610D01*
X266993D01*
X268293Y1805310D01*
Y1798112D01*
X270243Y1796162D01*
X273223D01*
X275173Y1798112D01*
Y1805310D01*
X276473Y1806610D01*
X278533D01*
X279833Y1805310D01*
Y1798112D01*
X281783Y1796162D01*
X284763D01*
X286713Y1798112D01*
Y1805310D01*
X288013Y1806610D01*
X290073D01*
X291373Y1805310D01*
Y1798112D01*
X293323Y1796162D01*
X296303D01*
X298253Y1798112D01*
Y1800086D01*
X299553Y1801386D01*
X307698D01*
X308348Y1800736D01*
Y1796941D01*
G01X135866Y1616496D02*
Y1614992D01*
X136366Y1614492D01*
X138330D01*
X140390Y1612432D01*
Y1561398D01*
X137202Y1553702D01*
X134348Y1550848D01*
X99647Y1530047D01*
X94451Y1524851D01*
X91102Y1516768D01*
X79209Y1456978D01*
X68400Y1384111D01*
Y1346296D01*
X73606Y1304083D01*
X82849Y1256083D01*
X82921Y1255808D01*
X93112Y1231209D01*
X94277Y1229028D01*
X94818Y1228864D01*
X95738Y1227143D01*
X95574Y1226601D01*
X96492Y1224882D01*
X97033Y1224718D01*
X97953Y1222997D01*
X97789Y1222455D01*
X98707Y1220736D01*
X99248Y1220572D01*
X100168Y1218851D01*
X100004Y1218310D01*
X101665Y1215200D01*
X101668D01*
X103283Y1212787D01*
X106101Y1209969D01*
X106667D01*
X108047Y1208589D01*
Y1208023D01*
X109425Y1206645D01*
X110047D01*
X111392Y1205300D01*
Y1204678D01*
X113576Y1202494D01*
X115323Y1201771D01*
X115846Y1201988D01*
X117648Y1201240D01*
X117865Y1200718D01*
X120286Y1199715D01*
X132384Y1197306D01*
X140000D01*
G01X144528Y1607048D02*
Y1608552D01*
X145028Y1609052D01*
X146324D01*
X147941Y1607435D01*
Y1557286D01*
X146741Y1554389D01*
X146192Y1553840D01*
X131961Y1544331D01*
X101454Y1528025D01*
X96790Y1523360D01*
X93636Y1515750D01*
X81720Y1455842D01*
X71090Y1384184D01*
Y1346137D01*
X82082Y1283842D01*
X85434Y1256674D01*
X91661Y1241638D01*
X95718Y1233062D01*
X104880Y1215919D01*
X107645Y1213155D01*
Y1213154D01*
X115946Y1204854D01*
X122298Y1202222D01*
X133785Y1199937D01*
X140000D01*
G01X144528Y1612166D02*
Y1610662D01*
X145028Y1610162D01*
X146784D01*
X149051Y1607895D01*
Y1557065D01*
X147682Y1553760D01*
X146900Y1552978D01*
X132533Y1543377D01*
X102123Y1527123D01*
X97731Y1522731D01*
X94704Y1515426D01*
X82814Y1455652D01*
X72200Y1384102D01*
Y1346235D01*
X83181Y1284007D01*
X86518Y1256960D01*
X92677Y1242088D01*
X96710Y1233561D01*
X98196Y1230780D01*
X98805Y1230595D01*
X99725Y1228875D01*
X99541Y1228266D01*
X100460Y1226547D01*
X101069Y1226362D01*
X101989Y1224641D01*
X101804Y1224032D01*
X105782Y1216588D01*
X111077Y1211293D01*
X111713D01*
X113093Y1209913D01*
Y1209277D01*
X116575Y1205795D01*
X122622Y1203290D01*
X133895Y1201047D01*
X140000D01*
G01X153189Y1611378D02*
Y1612882D01*
X153689Y1613382D01*
X155193D01*
X156603Y1611972D01*
Y1561621D01*
X154702Y1557032D01*
X146629Y1548959D01*
X138631Y1543615D01*
X103857Y1525028D01*
X100086Y1521256D01*
X97203Y1514299D01*
X87027Y1445691D01*
X83377Y1408631D01*
Y1345975D01*
X86112Y1318202D01*
X89075Y1257879D01*
X93344Y1247574D01*
X110794Y1221460D01*
X125430Y1206824D01*
X130335Y1204792D01*
X135937Y1203677D01*
X140000D01*
G01X170512Y1611378D02*
Y1612882D01*
X171012Y1613382D01*
X172516D01*
X173926Y1611972D01*
Y1561213D01*
X170014Y1551767D01*
X108686Y1518987D01*
X106483Y1516783D01*
X104734Y1512561D01*
Y1456371D01*
X106305Y1424370D01*
X107849Y1408692D01*
X107857Y1408537D01*
Y1346450D01*
X103638Y1303615D01*
X96596Y1268211D01*
Y1259380D01*
X98920Y1253769D01*
X114121Y1231019D01*
X132097Y1213043D01*
X136651Y1211157D01*
X140000D01*
G01X170512Y1616496D02*
Y1614992D01*
X171012Y1614492D01*
X172976D01*
X175036Y1612432D01*
Y1560992D01*
X170888Y1550975D01*
X109355Y1518085D01*
X107424Y1516154D01*
X105844Y1512340D01*
Y1456399D01*
X107413Y1424452D01*
X108957Y1408773D01*
X108967Y1408564D01*
Y1346395D01*
X104738Y1303452D01*
X97706Y1268101D01*
Y1259601D01*
X99904Y1254295D01*
X106040Y1245111D01*
X106525Y1245015D01*
X107610Y1243392D01*
X107513Y1242907D01*
X108596Y1241286D01*
X109081Y1241190D01*
X110166Y1239567D01*
X110069Y1239082D01*
X111152Y1237461D01*
X111637Y1237364D01*
X112722Y1235742D01*
X112625Y1235256D01*
X114983Y1231727D01*
X119652Y1227058D01*
X120274D01*
X121619Y1225713D01*
Y1225091D01*
X122962Y1223748D01*
X123584D01*
X124929Y1222403D01*
Y1221781D01*
X126272Y1220438D01*
X126894D01*
X128238Y1219094D01*
Y1218472D01*
X132726Y1213984D01*
X136872Y1212267D01*
X140000D01*
G01X153189Y1616496D02*
Y1614992D01*
X153689Y1614492D01*
X155653D01*
X157713Y1612432D01*
Y1561400D01*
X155643Y1556403D01*
X147337Y1548097D01*
X139203Y1542661D01*
X104526Y1524126D01*
X101027Y1520627D01*
X98282Y1514000D01*
X88129Y1445555D01*
X84487Y1408576D01*
Y1346030D01*
X87220Y1318284D01*
X90175Y1258126D01*
X94328Y1248100D01*
X106454Y1229953D01*
X107065Y1229831D01*
X108121Y1228251D01*
X108000Y1227640D01*
X109055Y1226061D01*
Y1226060D01*
X109666Y1225938D01*
X110722Y1224358D01*
X110601Y1223747D01*
X111656Y1222168D01*
X113919Y1219905D01*
X114495D01*
X115886Y1218514D01*
Y1217938D01*
X117229Y1216595D01*
X118005D01*
X119195Y1215405D01*
Y1214629D01*
X122579Y1211245D01*
X123201D01*
X124545Y1209901D01*
Y1209279D01*
X126059Y1207765D01*
X130659Y1205860D01*
X136047Y1204787D01*
X140000D01*
G01X161850Y1607048D02*
Y1608552D01*
X162350Y1609052D01*
X163646D01*
X165263Y1607435D01*
Y1556380D01*
X164704Y1555030D01*
X160759Y1551085D01*
X157432Y1549307D01*
X156958Y1549451D01*
X155238Y1548531D01*
X155094Y1548057D01*
X153375Y1547138D01*
X152901Y1547282D01*
X151180Y1546362D01*
X151037Y1545888D01*
X149318Y1544969D01*
X148844Y1545113D01*
X147123Y1544193D01*
X146980Y1543719D01*
X146979Y1543720D01*
X106098Y1521869D01*
X103320Y1519090D01*
X100949Y1513367D01*
X100582Y1509654D01*
X95617Y1408563D01*
Y1332001D01*
X93718Y1293331D01*
X93717Y1293330D01*
Y1293323D01*
X92836Y1275388D01*
Y1258628D01*
X95730Y1251641D01*
X112125Y1227105D01*
Y1227075D01*
X129858Y1209342D01*
X134505Y1207417D01*
X140000D01*
G01X161850Y1612166D02*
Y1610662D01*
X162350Y1610162D01*
X164106D01*
X166373Y1607895D01*
Y1556159D01*
X165645Y1554401D01*
X161428Y1550183D01*
X106767Y1520967D01*
X104261Y1518461D01*
X102038Y1513094D01*
X101690Y1509572D01*
X96727Y1408535D01*
Y1331973D01*
X94827Y1293277D01*
X95207Y1292858D01*
X95111Y1290909D01*
X94691Y1290529D01*
X94596Y1288582D01*
X94976Y1288163D01*
X94880Y1286214D01*
X94460Y1285835D01*
X94461D01*
X93946Y1275360D01*
Y1258849D01*
X96714Y1252167D01*
X113048Y1227722D01*
X115989Y1224781D01*
X116484D01*
X117864Y1223401D01*
Y1222906D01*
X119242Y1221528D01*
X119737D01*
X121117Y1220148D01*
Y1219653D01*
X122495Y1218275D01*
X122990D01*
X124370Y1216895D01*
Y1216400D01*
X125748Y1215022D01*
X126243D01*
X127622Y1213643D01*
Y1213148D01*
X130487Y1210283D01*
X134726Y1208527D01*
X140000D01*
G01X212980Y394395D02*
X211835Y393250D01*
X204562D01*
X199989Y395536D01*
X199788Y396140D01*
X198043Y397013D01*
X197439Y396812D01*
X195695Y397683D01*
X195494Y398287D01*
X193749Y399160D01*
X193145Y398959D01*
X191401Y399830D01*
X191200Y400434D01*
X189455Y401307D01*
X188851Y401106D01*
X187107Y401977D01*
X186906Y402581D01*
X185161Y403454D01*
X184557Y403253D01*
X182813Y404124D01*
X182612Y404728D01*
X180867Y405601D01*
X180263Y405400D01*
X177399Y406831D01*
X174562Y409084D01*
X174489Y409717D01*
X172961Y410930D01*
X172329Y410858D01*
X170803Y412070D01*
X170730Y412703D01*
X169202Y413916D01*
X168570Y413844D01*
X167043Y415056D01*
X166971Y415688D01*
X165443Y416902D01*
X164811Y416830D01*
X154324Y425157D01*
X144735Y431518D01*
X142070Y433925D01*
X135653Y436535D01*
X134131Y438094D01*
X123199Y471339D01*
X116843Y497639D01*
X111405Y590300D01*
X114051Y628092D01*
X118973Y653566D01*
X233527Y1063253D01*
Y1069788D01*
G01X212980Y390995D02*
X211835Y392140D01*
X204299D01*
X176799Y405889D01*
X153671Y424258D01*
X144052Y430639D01*
X141471Y432970D01*
X135020Y435594D01*
X133156Y437502D01*
X122130Y471034D01*
X115740Y497475D01*
X110292Y590306D01*
X110296Y590377D01*
X110297D01*
X112948Y628237D01*
X117891Y653821D01*
X232417Y1063406D01*
Y1069788D01*
G01X205680Y398082D02*
X204535Y399227D01*
X202599D01*
X202453Y399373D01*
X176071Y414426D01*
X131237Y461192D01*
X125842Y471867D01*
X119925Y498317D01*
X114312Y591264D01*
X116556Y625484D01*
X121260Y651241D01*
X236157Y1062754D01*
Y1069976D01*
G01X237267D02*
Y1062601D01*
X122343Y650992D01*
X117660Y625347D01*
X115425Y591261D01*
X121028Y498473D01*
X126896Y472245D01*
X132153Y461841D01*
X164221Y428391D01*
X164857Y428378D01*
X166207Y426969D01*
X166194Y426333D01*
X167543Y424926D01*
X168179Y424913D01*
X169529Y423504D01*
X169516Y422868D01*
X170865Y421461D01*
X171502Y421448D01*
X172852Y420039D01*
X172839Y419403D01*
X176762Y415311D01*
X179779Y413589D01*
X180393Y413757D01*
X182087Y412790D01*
X182255Y412176D01*
X186326Y409853D01*
X186940Y410021D01*
X188635Y409054D01*
X188803Y408440D01*
X190496Y407474D01*
X191109Y407642D01*
X192804Y406675D01*
X192972Y406061D01*
X194665Y405095D01*
X195278Y405263D01*
X196973Y404296D01*
X197141Y403682D01*
X198834Y402716D01*
X199448Y402884D01*
X201143Y401917D01*
X201311Y401303D01*
X203004Y400337D01*
X204535D01*
X205680Y401482D01*
G01X139488Y1214897D02*
X138168D01*
X135855Y1215856D01*
X131940Y1219771D01*
Y1228175D01*
X131000Y1230445D01*
Y1248119D01*
X135890Y1259925D01*
Y1266206D01*
X120097Y1345610D01*
Y1408620D01*
X113295Y1454459D01*
Y1505235D01*
X111840Y1506690D01*
X110382D01*
X109882Y1506190D01*
Y1504685D01*
G01X139488Y1216007D02*
X138389D01*
X136484Y1216797D01*
X133050Y1220231D01*
Y1222975D01*
X133500Y1223425D01*
Y1225375D01*
X133050Y1225825D01*
Y1228396D01*
X132110Y1230666D01*
Y1236375D01*
X132460Y1236725D01*
Y1238675D01*
X132110Y1239025D01*
Y1240975D01*
X132460Y1241325D01*
Y1243275D01*
X132110Y1243625D01*
Y1247898D01*
X137000Y1259704D01*
Y1266316D01*
X121207Y1345720D01*
Y1408702D01*
X114405Y1454541D01*
Y1505695D01*
X112300Y1507800D01*
X110382D01*
X109882Y1508300D01*
Y1509804D01*
G01X212980Y405168D02*
X211835Y406313D01*
X204452D01*
X176107Y420858D01*
X133220Y465777D01*
X129305Y473934D01*
X124826Y498436D01*
X118511Y591895D01*
X119613Y608536D01*
X120715Y625162D01*
X125150Y650804D01*
X239897Y1062098D01*
Y1069976D01*
G01X212980Y408568D02*
X211835Y407423D01*
X204721D01*
X200510Y409584D01*
Y409583D01*
X200316Y410189D01*
X198580Y411081D01*
X197974Y410886D01*
X196240Y411776D01*
X196045Y412382D01*
X194309Y413273D01*
X193703Y413078D01*
X191969Y413968D01*
X191774Y414574D01*
X190038Y415465D01*
X189432Y415270D01*
X187698Y416160D01*
X187503Y416765D01*
X185767Y417657D01*
X185161Y417462D01*
X183426Y418352D01*
X183232Y418957D01*
X181495Y419848D01*
X180890Y419653D01*
X176781Y421761D01*
X174939Y423690D01*
X174954Y424327D01*
X173606Y425738D01*
X172970Y425753D01*
X171624Y427163D01*
X171639Y427799D01*
X170291Y429210D01*
X169655Y429225D01*
X168309Y430635D01*
X168324Y431271D01*
X166976Y432682D01*
X166340Y432697D01*
X134145Y466417D01*
X130371Y474280D01*
X125930Y498574D01*
X119624Y591896D01*
X121819Y625030D01*
X126235Y650559D01*
X241007Y1061946D01*
Y1069976D01*
G01X205680Y415655D02*
X204535Y414510D01*
X202656D01*
X200941Y415436D01*
X200759Y416046D01*
X199042Y416974D01*
X198433Y416792D01*
X196718Y417718D01*
X196536Y418328D01*
X194819Y419256D01*
X194210Y419074D01*
X192495Y420000D01*
X192313Y420610D01*
X190596Y421538D01*
X189987Y421356D01*
X188272Y422282D01*
X188090Y422892D01*
X186373Y423820D01*
X185763Y423638D01*
X184048Y424564D01*
X183866Y425174D01*
X182149Y426102D01*
X181540Y425920D01*
X177964Y427852D01*
X174370Y431331D01*
X174360Y431967D01*
X172958Y433325D01*
X172322Y433315D01*
X170921Y434671D01*
X170911Y435307D01*
X169509Y436665D01*
X168873Y436654D01*
X167472Y438010D01*
X167462Y438646D01*
X166060Y440004D01*
X165424Y439993D01*
X160984Y444292D01*
X148565Y469752D01*
X143180Y476308D01*
X135165Y480623D01*
X132548Y483806D01*
X129938Y497588D01*
X126788Y545023D01*
X126786Y545024D01*
X123635Y592456D01*
X125705Y624941D01*
X130022Y650081D01*
X244747Y1060983D01*
Y1069976D01*
G01X205680Y412255D02*
X204535Y413400D01*
X202375D01*
X177301Y426947D01*
X160071Y443630D01*
X147624Y469148D01*
X142461Y475434D01*
X134446Y479749D01*
X131510Y483320D01*
X128834Y497447D01*
X122522Y592455D01*
X123561Y608768D01*
X123562D01*
X124079Y616889D01*
X124078D01*
X124079Y616890D01*
X124601Y625071D01*
X128937Y650325D01*
X243637Y1061136D01*
Y1069976D01*
G01X212980Y419341D02*
X211835Y420486D01*
X203108D01*
X174460Y435738D01*
X164106Y445743D01*
X160808Y451562D01*
X153927Y481096D01*
X151312Y484085D01*
X144353Y486769D01*
X144160Y487152D01*
X144161D01*
X132823Y509734D01*
X126365Y592559D01*
X127391Y608789D01*
X128416Y625001D01*
X132453Y648527D01*
X247378Y1060437D01*
Y1069976D01*
G01X212980Y422741D02*
X211835Y421596D01*
X203386D01*
X201665Y422512D01*
X201479Y423121D01*
X199757Y424038D01*
X199149Y423852D01*
X197428Y424768D01*
X197242Y425377D01*
X195520Y426294D01*
X194912Y426108D01*
X193191Y427024D01*
X193005Y427633D01*
X191283Y428550D01*
X190674Y428364D01*
X188953Y429280D01*
X188767Y429889D01*
X187045Y430806D01*
X186437Y430620D01*
X184716Y431536D01*
X184530Y432144D01*
X182808Y433062D01*
X182199Y432876D01*
X180478Y433792D01*
X180292Y434401D01*
X178570Y435318D01*
X177961Y435132D01*
X175119Y436645D01*
X173717Y438000D01*
X173706Y438636D01*
X172303Y439992D01*
X171667Y439981D01*
X170265Y441336D01*
X170254Y441972D01*
X168851Y443328D01*
X168215Y443317D01*
X164993Y446430D01*
X161853Y451970D01*
X154946Y481619D01*
X151968Y485023D01*
X145153Y487651D01*
X133913Y510037D01*
X127478Y592567D01*
X129521Y624872D01*
X133538Y648283D01*
X248488Y1060285D01*
Y1069976D01*
G01X205680Y429828D02*
X204535Y428683D01*
X203225D01*
X203229Y428687D01*
Y428689D01*
X201153Y429867D01*
X200984Y430480D01*
X199286Y431443D01*
X198673Y431274D01*
X196977Y432236D01*
X196808Y432849D01*
X195111Y433812D01*
X194498Y433643D01*
X191961Y435082D01*
X191792Y435695D01*
X190095Y436658D01*
X189482Y436489D01*
X187786Y437451D01*
X187617Y438064D01*
X185920Y439027D01*
X185306Y438858D01*
X168203Y448560D01*
X167999Y448758D01*
X165398Y453382D01*
X157095Y489649D01*
X153157Y498819D01*
X153393Y499410D01*
X152624Y501203D01*
X152032Y501439D01*
X151263Y503230D01*
X151499Y503821D01*
X150730Y505614D01*
X150138Y505850D01*
X149369Y507641D01*
X149605Y508232D01*
X148835Y510025D01*
X148243Y510261D01*
X147474Y512052D01*
X147710Y512643D01*
X146941Y514436D01*
X146349Y514672D01*
X143909Y520353D01*
Y537137D01*
X139212Y550147D01*
X131398Y593246D01*
X133306Y624061D01*
X137447Y648070D01*
X252228Y1059624D01*
Y1069976D01*
G01X205680Y426428D02*
X204535Y427573D01*
X202832D01*
X202682Y427723D01*
X167531Y447664D01*
X167110Y448073D01*
X164351Y452977D01*
X156035Y489303D01*
X142799Y520124D01*
Y536942D01*
X138136Y549858D01*
X130281Y593180D01*
X130289Y593314D01*
X130290D01*
X132201Y624190D01*
X136362Y648314D01*
X251118Y1059776D01*
Y1069976D01*
G01X140347Y1224439D02*
X137973Y1226813D01*
Y1254289D01*
X139690Y1258435D01*
Y1271136D01*
X136093Y1307657D01*
X136094D01*
X135655Y1308015D01*
X135464Y1309957D01*
X135823Y1310394D01*
X134236Y1326513D01*
X133798Y1326872D01*
X133607Y1328814D01*
X133966Y1329251D01*
X133775Y1331191D01*
X133337Y1331550D01*
X133146Y1333492D01*
X133505Y1333929D01*
X133314Y1335869D01*
X133315D01*
X132877Y1336227D01*
X132686Y1338169D01*
X133045Y1338606D01*
X132337Y1345795D01*
Y1408601D01*
X131897Y1412162D01*
X121957Y1451846D01*
Y1509610D01*
X120547Y1511020D01*
X119043D01*
X118543Y1510520D01*
Y1509016D01*
G01Y1514134D02*
Y1512630D01*
X119043Y1512130D01*
X121007D01*
X123067Y1510070D01*
Y1451983D01*
X132991Y1412366D01*
X133447Y1408670D01*
Y1345850D01*
X140800Y1271191D01*
Y1258214D01*
X139083Y1254068D01*
Y1227273D01*
X141132Y1225224D01*
G01X127205Y1509804D02*
Y1508300D01*
X127705Y1507800D01*
X129623D01*
X131728Y1505695D01*
Y1458211D01*
X144673Y1415539D01*
X145687Y1408701D01*
Y1345069D01*
X143500Y1322866D01*
Y1296239D01*
X147495Y1264230D01*
X147503Y1264222D01*
Y1256412D01*
G01X127205Y1504685D02*
Y1506190D01*
X127705Y1506690D01*
X129163D01*
X130618Y1505235D01*
Y1458046D01*
X143587Y1415295D01*
X144577Y1408619D01*
Y1345124D01*
X142390Y1322921D01*
Y1316525D01*
X141940Y1316075D01*
Y1314125D01*
X142390Y1313675D01*
Y1311725D01*
X141940Y1311275D01*
Y1309325D01*
X142390Y1308875D01*
Y1306925D01*
X141940Y1306475D01*
Y1304525D01*
X142390Y1304075D01*
Y1296170D01*
X144312Y1280760D01*
X143964Y1280314D01*
X144206Y1278378D01*
X144653Y1278031D01*
X144894Y1276096D01*
X144590Y1275705D01*
X144831Y1273769D01*
X145223Y1273465D01*
X145464Y1271531D01*
X145160Y1271141D01*
X145402Y1269205D01*
X145793Y1268901D01*
X146393Y1264093D01*
Y1256412D01*
G01X212980Y433515D02*
X211835Y434660D01*
X203887D01*
X187341Y441396D01*
X175152Y449519D01*
X174501Y449790D01*
X172723D01*
X170265Y450923D01*
X168963Y452451D01*
X167721Y455114D01*
X153578Y539070D01*
X145950Y553504D01*
X138520Y570047D01*
X134182Y594454D01*
X134181D01*
X134158Y594584D01*
X135964Y623640D01*
X140255Y647567D01*
X254858Y1058368D01*
Y1069976D01*
G01X212980Y436915D02*
X211835Y435770D01*
X208905D01*
X208455Y436220D01*
X206505D01*
X206055Y435770D01*
X204105D01*
X202300Y436505D01*
X202052Y437092D01*
X200245Y437828D01*
X199659Y437581D01*
X197853Y438316D01*
X197606Y438903D01*
X195799Y439639D01*
X195213Y439392D01*
X193407Y440127D01*
X193160Y440714D01*
X191353Y441449D01*
X190767Y441202D01*
X187864Y442383D01*
X183668Y445179D01*
X183543Y445803D01*
X181919Y446885D01*
X181295Y446760D01*
X179673Y447841D01*
X179548Y448465D01*
X177924Y449547D01*
X177300Y449422D01*
X175678Y450503D01*
X174723Y450900D01*
X172968D01*
X170952Y451830D01*
X169906Y453057D01*
X168791Y455447D01*
X165893Y472653D01*
X166262Y473172D01*
X165938Y475096D01*
X165418Y475465D01*
X165095Y477387D01*
X165464Y477906D01*
X165140Y479830D01*
X164621Y480199D01*
X154643Y539431D01*
X146949Y553992D01*
X139590Y570377D01*
X135275Y594648D01*
X137068Y623507D01*
X141339Y647319D01*
X255968Y1058216D01*
Y1069976D01*
G01X205680Y440602D02*
X204535Y441747D01*
X201836D01*
X185110Y448587D01*
X183535Y450089D01*
Y450090D01*
X181959Y451593D01*
X179098Y457745D01*
X176535Y461407D01*
X169660Y476186D01*
X163172Y505391D01*
X157412Y540921D01*
X149578Y555079D01*
X142542Y571121D01*
X140325Y583211D01*
Y583212D01*
X138106Y595311D01*
X139023Y609377D01*
X139935Y623365D01*
X143820Y646036D01*
X258598Y1057515D01*
Y1069976D01*
G01X205680Y444002D02*
X204535Y442857D01*
X202055D01*
X200251Y443595D01*
X200004Y444183D01*
X198199Y444921D01*
X197612Y444675D01*
X195808Y445413D01*
X195561Y446000D01*
X193755Y446738D01*
X193169Y446492D01*
X185725Y449536D01*
X182878Y452252D01*
X180064Y458302D01*
X177501Y461964D01*
X174770Y467834D01*
X174988Y468432D01*
X174165Y470201D01*
X173567Y470419D01*
X172745Y472187D01*
X172963Y472784D01*
X172140Y474554D01*
X171542Y474772D01*
X170718Y476545D01*
X170200Y478878D01*
X170542Y479415D01*
X170119Y481320D01*
X169581Y481661D01*
X169159Y483564D01*
X169500Y484101D01*
X169077Y486006D01*
X168540Y486347D01*
X168118Y488250D01*
X168459Y488787D01*
X168036Y490692D01*
X167499Y491033D01*
X167077Y492936D01*
X167418Y493473D01*
X166995Y495378D01*
X166458Y495719D01*
X164263Y505600D01*
X158477Y541289D01*
X150574Y555572D01*
X143611Y571449D01*
X139223Y595376D01*
X141039Y623235D01*
X144905Y645792D01*
X259708Y1057363D01*
Y1069976D01*
G01X212980Y469381D02*
X211835Y470526D01*
X204949D01*
X196898Y473033D01*
X174789Y494002D01*
X168402Y503906D01*
X167014Y507516D01*
X161429Y541787D01*
X154719Y553631D01*
X146642Y571525D01*
X141996Y596701D01*
X143712Y622860D01*
X147664Y645427D01*
X262338Y1056771D01*
Y1069976D01*
G01X212980Y472781D02*
X211835Y471636D01*
X205118D01*
X197475Y474016D01*
X192141Y479075D01*
X192124Y479711D01*
X190708Y481054D01*
X190072Y481038D01*
X188658Y482379D01*
X188641Y483016D01*
X187225Y484358D01*
X186589Y484342D01*
X185175Y485683D01*
X185158Y486320D01*
X183742Y487662D01*
X183106Y487645D01*
X181692Y488986D01*
X181675Y489623D01*
X180259Y490965D01*
X179623Y490949D01*
X175650Y494716D01*
X174594Y496354D01*
X174728Y496976D01*
X173670Y498616D01*
X173048Y498751D01*
X169398Y504412D01*
X168092Y507808D01*
X162493Y542161D01*
X161255Y544347D01*
X161424Y544960D01*
X160462Y546658D01*
X159849Y546828D01*
X158888Y548524D01*
X159058Y549137D01*
X158096Y550835D01*
X157483Y551005D01*
X155710Y554134D01*
X154596Y556602D01*
X154821Y557198D01*
X154019Y558976D01*
X153423Y559201D01*
X147710Y571859D01*
X143113Y596766D01*
X144816Y622728D01*
X148749Y645181D01*
X263448Y1056619D01*
Y1069976D01*
G01X205680Y476468D02*
X204535Y477613D01*
X203671D01*
X196801Y480353D01*
X180222Y495401D01*
X171973Y505743D01*
X171231Y507433D01*
X165046Y543036D01*
X159745Y561559D01*
X150738Y573178D01*
X149019Y579791D01*
X149029Y579966D01*
X149030D01*
X151432Y619118D01*
X155139Y639472D01*
X266078Y1055410D01*
Y1069976D01*
G01X135866Y1509016D02*
Y1510520D01*
X136366Y1511020D01*
X137870D01*
X139280Y1509610D01*
Y1456660D01*
X139492Y1455590D01*
X154864Y1418478D01*
X156817Y1408661D01*
Y1344139D01*
X152671Y1323299D01*
X152672D01*
X152142Y1322946D01*
X151761Y1321032D01*
X152115Y1320503D01*
X150134Y1310542D01*
Y1259824D01*
G01X135866Y1514134D02*
Y1512630D01*
X136366Y1512130D01*
X138330D01*
X140390Y1510070D01*
Y1456770D01*
X140560Y1455914D01*
X155932Y1418802D01*
X157927Y1408771D01*
Y1344029D01*
X151244Y1310432D01*
Y1259824D01*
G01X144528Y1504685D02*
Y1506190D01*
X145028Y1506690D01*
X146486D01*
X147941Y1505235D01*
Y1455246D01*
X149299Y1449823D01*
X167727Y1415344D01*
X169057Y1408659D01*
Y1347121D01*
X165534Y1323258D01*
X162886Y1314533D01*
X162888D01*
X162450Y1314300D01*
X161884Y1312433D01*
X162118Y1311997D01*
X162117D01*
X161551Y1310131D01*
X161552D01*
X161114Y1309898D01*
X160548Y1308031D01*
X160782Y1307595D01*
X160216Y1305729D01*
X159778Y1305495D01*
X159212Y1303628D01*
X159445Y1303192D01*
X153874Y1284828D01*
Y1259824D01*
G01X144528Y1509804D02*
Y1508300D01*
X145028Y1507800D01*
X146946D01*
X149051Y1505695D01*
Y1455383D01*
X150343Y1450226D01*
X168784Y1415722D01*
X170167Y1408769D01*
Y1347039D01*
X166621Y1323014D01*
X161279Y1305408D01*
X161278Y1305405D01*
X160509Y1302871D01*
X160508Y1302868D01*
X154984Y1284663D01*
Y1259824D01*
G01X205680Y479868D02*
X204535Y478723D01*
X203885D01*
X201858Y479531D01*
X201607Y480117D01*
X199794Y480839D01*
X199210Y480588D01*
X197399Y481310D01*
X195956Y482620D01*
X195925Y483256D01*
X194480Y484567D01*
X193844Y484537D01*
X192401Y485847D01*
X192370Y486483D01*
X190925Y487794D01*
X190289Y487764D01*
X188846Y489074D01*
X188815Y489710D01*
X187370Y491021D01*
X186734Y490991D01*
X185291Y492301D01*
X185260Y492937D01*
X183815Y494248D01*
X183179Y494218D01*
X181035Y496164D01*
X179819Y497688D01*
X179891Y498320D01*
X178674Y499846D01*
X178041Y499917D01*
X176826Y501441D01*
X176897Y502073D01*
X175680Y503599D01*
X175047Y503670D01*
X172932Y506322D01*
X172302Y507756D01*
X166130Y543285D01*
X162287Y556714D01*
X162596Y557270D01*
X162060Y559146D01*
X161502Y559455D01*
X160754Y562071D01*
X151755Y573678D01*
X150138Y579899D01*
X152536Y618984D01*
X156224Y639229D01*
X267188Y1055264D01*
Y1069976D01*
G01X205680Y494041D02*
X204535Y492896D01*
X203251D01*
X201608Y494539D01*
X199895Y498675D01*
Y505078D01*
X199144Y506877D01*
X199386Y507465D01*
X198634Y509266D01*
X198044Y509508D01*
X195889Y514667D01*
X194798Y516282D01*
X194919Y516907D01*
X193826Y518524D01*
X193201Y518645D01*
X190816Y522174D01*
X189986Y523938D01*
X190201Y524536D01*
X189369Y526302D01*
X188770Y526517D01*
X187940Y528281D01*
X188155Y528880D01*
X187324Y530645D01*
X186725Y530860D01*
X185796Y532834D01*
X184466Y537213D01*
X184766Y537774D01*
X184199Y539641D01*
X183636Y539941D01*
X183070Y541806D01*
X183369Y542368D01*
X182803Y544234D01*
X182240Y544534D01*
X182241D01*
X181674Y546399D01*
X181974Y546961D01*
X181407Y548828D01*
X180844Y549127D01*
X180846D01*
X180279Y550992D01*
X180579Y551554D01*
X180012Y553420D01*
X179450Y553720D01*
X178898Y555538D01*
X170061Y563571D01*
X166276Y567307D01*
X158761Y577393D01*
X157798Y581059D01*
X160192Y618140D01*
X163224Y635250D01*
X274668Y1054128D01*
Y1069976D01*
G01X205680Y490641D02*
X204535Y491786D01*
X202791D01*
X200667Y493910D01*
X198785Y498454D01*
Y504855D01*
X197020Y509079D01*
X197019Y509081D01*
X194907Y514137D01*
X189847Y521623D01*
X187766Y526043D01*
X187765Y526045D01*
X184757Y532434D01*
X178520Y552957D01*
X178521D01*
X177923Y554923D01*
X169297Y562765D01*
X165436Y566576D01*
X157741Y576902D01*
X156678Y580951D01*
X156689Y581130D01*
X156690D01*
X159088Y618273D01*
X162139Y635490D01*
X273558Y1054274D01*
Y1069976D01*
G01X212980Y483554D02*
X211835Y484699D01*
X204013D01*
X186613Y495431D01*
X183833Y497905D01*
X175273Y508737D01*
X174603Y510215D01*
X168027Y548303D01*
X164010Y562168D01*
X154154Y575398D01*
X152859Y580339D01*
X155416Y619759D01*
X158628Y637579D01*
X269819Y1054845D01*
Y1069976D01*
G01X212980Y486954D02*
X211835Y485809D01*
X209128D01*
X208678Y486259D01*
X206728D01*
X206278Y485809D01*
X204328D01*
X201089Y487807D01*
X200943Y488426D01*
X199282Y489451D01*
X198663Y489304D01*
X197004Y490327D01*
X196857Y490946D01*
X195196Y491971D01*
X194577Y491824D01*
X192918Y492847D01*
X192771Y493467D01*
X191110Y494491D01*
X190491Y494345D01*
X187279Y496326D01*
X184644Y498670D01*
X182182Y501786D01*
Y501787D01*
X182256Y502419D01*
X181046Y503950D01*
X180414Y504024D01*
X179205Y505553D01*
X179279Y506185D01*
X178069Y507716D01*
X177437Y507790D01*
X176228Y509319D01*
X175673Y510544D01*
X175167Y513477D01*
X175534Y513997D01*
X175202Y515920D01*
X174681Y516287D01*
X174682D01*
X174351Y518208D01*
X174718Y518728D01*
X174386Y520651D01*
X173865Y521018D01*
X169111Y548553D01*
X165021Y562670D01*
X155174Y575889D01*
X153979Y580447D01*
X156520Y619624D01*
X159713Y637337D01*
X270929Y1054699D01*
Y1069976D01*
G01X205680Y524002D02*
X204535Y522857D01*
X203681D01*
X202861Y523197D01*
X202588Y523470D01*
X201026Y524949D01*
X201009Y525586D01*
X199592Y526928D01*
X198956Y526910D01*
X197172Y528600D01*
X196397Y530473D01*
X196640Y531061D01*
X195894Y532863D01*
X195306Y533107D01*
X194560Y534908D01*
X194804Y535496D01*
X194058Y537298D01*
X193469Y537542D01*
X192723Y539343D01*
Y544610D01*
X193173Y545060D01*
Y547010D01*
X192723Y547460D01*
Y549410D01*
X193173Y549860D01*
Y551810D01*
X192723Y552260D01*
Y554210D01*
X191161Y557982D01*
X191405Y558570D01*
X190659Y560373D01*
X190071Y560616D01*
X189220Y562671D01*
X187776Y563980D01*
X187744Y564616D01*
X186298Y565926D01*
X185663Y565895D01*
X181645Y569536D01*
X180059Y571908D01*
X178103Y573864D01*
X176247Y574459D01*
X175956Y575026D01*
X174098Y575621D01*
X173532Y575330D01*
X169308Y576684D01*
X167871Y577889D01*
X167133Y578792D01*
X165395Y581984D01*
X167680Y617115D01*
X170536Y633242D01*
X282149Y1052997D01*
Y1069976D01*
G01X212980Y516915D02*
X211835Y515770D01*
X209752D01*
X209302Y516220D01*
X207352D01*
X206902Y515770D01*
X201639D01*
X200402Y517277D01*
X200464Y517910D01*
X199226Y519418D01*
X198593Y519480D01*
X197356Y520987D01*
X197419Y521620D01*
X196180Y523128D01*
X195547Y523191D01*
X194147Y524896D01*
X193401Y526697D01*
X193645Y527285D01*
X192899Y529088D01*
X192310Y529331D01*
X191564Y531132D01*
X191808Y531720D01*
X191062Y533523D01*
X190473Y533766D01*
X188963Y537412D01*
Y552553D01*
X188093Y554658D01*
X184431Y558319D01*
X181100Y560545D01*
X180976Y561169D01*
X179354Y562253D01*
X178730Y562129D01*
X177109Y563212D01*
X176985Y563836D01*
X175363Y564920D01*
X174739Y564796D01*
X173118Y565879D01*
X168840Y570160D01*
X167680Y571727D01*
X167774Y572356D01*
X166612Y573924D01*
X165983Y574018D01*
X162253Y579054D01*
X161591Y581436D01*
X163931Y617686D01*
X166897Y634420D01*
X278409Y1053564D01*
Y1069976D01*
G01X212980Y513515D02*
X211835Y514660D01*
X201114D01*
X193184Y524319D01*
X189624Y532914D01*
X189623Y532915D01*
X187853Y537191D01*
Y552332D01*
X187151Y554029D01*
X183723Y557457D01*
X172410Y565017D01*
X167997Y569433D01*
X161238Y578558D01*
X160471Y581320D01*
X162827Y617819D01*
X165812Y634660D01*
X277299Y1053710D01*
Y1069976D01*
G01X205680Y520602D02*
X204535Y521747D01*
X203460D01*
X202232Y522256D01*
X201814Y522674D01*
X196236Y527956D01*
X191613Y539122D01*
Y553989D01*
X188289Y562015D01*
X180798Y568805D01*
X179197Y571200D01*
X177508Y572889D01*
X168761Y575693D01*
X167078Y577105D01*
X166207Y578169D01*
X164266Y581735D01*
X166576Y617248D01*
X169451Y633482D01*
X281039Y1053143D01*
Y1069976D01*
G01X153189Y1514134D02*
Y1512630D01*
X153689Y1512130D01*
X155653D01*
X157713Y1510070D01*
Y1456504D01*
X161379Y1444419D01*
X178155Y1419312D01*
X182407Y1409040D01*
Y1347912D01*
X179183Y1331702D01*
X158725Y1282310D01*
X158724Y1282309D01*
Y1259824D01*
G01X161850Y1504685D02*
Y1506190D01*
X162350Y1506690D01*
X163808D01*
X165263Y1505235D01*
Y1455367D01*
X165931Y1453164D01*
X190245Y1416777D01*
X193537Y1408821D01*
Y1347945D01*
X191912Y1342585D01*
Y1342584D01*
X185232Y1328455D01*
X184766Y1328288D01*
X183931Y1326524D01*
X184098Y1326058D01*
X183265Y1324296D01*
X183266Y1324295D01*
X182800Y1324128D01*
X181965Y1322364D01*
X182132Y1321898D01*
X181299Y1320136D01*
X180833Y1319969D01*
X179998Y1318205D01*
X180165Y1317739D01*
X174475Y1305704D01*
X162961Y1285373D01*
X161354Y1280076D01*
Y1259824D01*
G01X153189Y1509016D02*
Y1510520D01*
X153689Y1511020D01*
X155193D01*
X156603Y1509610D01*
Y1456339D01*
X160364Y1443939D01*
X177171Y1418786D01*
X181297Y1408819D01*
Y1348022D01*
X178115Y1332026D01*
X172032Y1317340D01*
X171443Y1317096D01*
X170697Y1315294D01*
X170941Y1314706D01*
X166983Y1305150D01*
X166982D01*
X157615Y1282532D01*
X157614D01*
Y1259824D01*
G01X161850Y1509804D02*
Y1508300D01*
X162350Y1507800D01*
X164268D01*
X166373Y1505695D01*
Y1455532D01*
X166946Y1453644D01*
X191229Y1417303D01*
X194647Y1409042D01*
Y1347780D01*
X192951Y1342184D01*
X175462Y1305192D01*
X163988Y1284933D01*
X162464Y1279911D01*
Y1259824D01*
G01X170512Y1509016D02*
Y1510520D01*
X171012Y1511020D01*
X172516D01*
X173926Y1509610D01*
Y1454030D01*
X178335Y1443386D01*
X204086Y1412010D01*
X205061Y1410550D01*
X205777Y1408821D01*
Y1345328D01*
X203159Y1339007D01*
X186964Y1314771D01*
X186340Y1314647D01*
X185255Y1313024D01*
X185379Y1312400D01*
X169302Y1288340D01*
X165094Y1278179D01*
Y1259824D01*
G01X205680Y534775D02*
X204535Y535920D01*
X203051D01*
X200836Y538135D01*
X200345Y539321D01*
Y556025D01*
X195535Y567778D01*
X186078Y577086D01*
X183494Y578144D01*
X182263Y579356D01*
X180436Y583461D01*
X180435Y583468D01*
X178890Y602410D01*
X178888D01*
X176815Y627849D01*
X176817Y627918D01*
X176818D01*
X176977Y631549D01*
X288270Y1049597D01*
X288519Y1051495D01*
Y1069976D01*
G01X212980Y527688D02*
X211835Y528833D01*
X204258D01*
X200706Y530304D01*
X199964Y531010D01*
X195930Y539539D01*
X195824Y539645D01*
Y555723D01*
X192534Y563666D01*
X188967Y567233D01*
X183275Y571901D01*
X182015Y573784D01*
X179281Y576518D01*
X174978Y578300D01*
X173094D01*
X171669Y578715D01*
X170928Y579086D01*
X169345Y580274D01*
X168107Y582851D01*
X170380Y617118D01*
X173199Y632944D01*
X284779Y1052247D01*
Y1068491D01*
X284777Y1068493D01*
Y1068495D01*
X284779Y1068497D01*
Y1069000D01*
G01X205680Y538175D02*
X204535Y537030D01*
X203511D01*
X201777Y538764D01*
X201455Y539542D01*
Y541975D01*
X201905Y542425D01*
Y544375D01*
X201455Y544825D01*
Y549075D01*
X201905Y549525D01*
Y551475D01*
X201455Y551925D01*
Y556244D01*
X200699Y558092D01*
X200945Y558679D01*
X200207Y560485D01*
X199619Y560731D01*
X198881Y562535D01*
X199127Y563122D01*
X198389Y564928D01*
X197801Y565174D01*
X196477Y568410D01*
X195088Y569777D01*
X195082Y570414D01*
X193692Y571782D01*
X193055Y571777D01*
X191666Y573144D01*
X191660Y573781D01*
X190270Y575149D01*
X189634Y575145D01*
X186701Y578031D01*
X184117Y579089D01*
X183192Y580000D01*
X181527Y583746D01*
X180620Y594869D01*
X181032Y595354D01*
X180873Y597299D01*
X180387Y597711D01*
X180229Y599654D01*
X180641Y600139D01*
X180482Y602084D01*
X179996Y602496D01*
X177927Y627870D01*
X178081Y631380D01*
X289362Y1049381D01*
X289629Y1051422D01*
Y1069976D01*
G01X212980Y531088D02*
X211826Y529934D01*
X211802Y529943D01*
X209279D01*
X208829Y530393D01*
X206879D01*
X206429Y529943D01*
X204479D01*
X201322Y531251D01*
X200879Y531672D01*
X200046Y533434D01*
X200260Y534033D01*
X199425Y535797D01*
X198826Y536012D01*
Y536013D01*
X196934Y540013D01*
Y546344D01*
X197384Y546794D01*
Y548744D01*
X196934Y549194D01*
Y551144D01*
X197384Y551594D01*
Y553544D01*
X196934Y553994D01*
Y555944D01*
X195680Y558973D01*
X195923Y559561D01*
X195177Y561363D01*
X194588Y561607D01*
Y561608D01*
X193475Y564295D01*
X189713Y568057D01*
X184107Y572656D01*
X182877Y574492D01*
X179910Y577459D01*
X175199Y579410D01*
X173253D01*
X172076Y579753D01*
X171515Y580034D01*
X170229Y581000D01*
X169234Y583069D01*
X169881Y592819D01*
X169880D01*
X170360Y593238D01*
X170489Y595185D01*
X170070Y595664D01*
X170199Y597609D01*
X170633Y597989D01*
X170768Y600020D01*
X170388Y600454D01*
X170517Y602399D01*
X170890Y602725D01*
X171019Y604672D01*
X170693Y605044D01*
X170821Y606989D01*
X171138Y607266D01*
X171274Y609319D01*
X170998Y609634D01*
X171484Y616984D01*
X174284Y632704D01*
X285889Y1052101D01*
Y1069000D01*
G01X170512Y1514134D02*
Y1512630D01*
X171012Y1512130D01*
X172976D01*
X175036Y1510070D01*
Y1454251D01*
X179298Y1443963D01*
X204979Y1412672D01*
X206045Y1411076D01*
X206887Y1409042D01*
Y1345107D01*
X204143Y1338481D01*
X170286Y1287814D01*
X166204Y1277958D01*
Y1259824D01*
G01X300433Y1581457D02*
Y1579953D01*
X300933Y1579453D01*
X303469D01*
X305056Y1577866D01*
Y1558296D01*
X303831Y1554254D01*
X303222Y1553343D01*
X288605Y1541348D01*
X271796Y1534386D01*
X263733Y1526323D01*
X259812Y1516856D01*
X253192Y1449656D01*
X233608Y1398888D01*
X230371Y1385968D01*
X227237Y1360565D01*
X213654Y1327770D01*
X180183Y1277679D01*
X177425Y1271022D01*
Y1259824D01*
G01X309094Y1585788D02*
Y1584284D01*
X309594Y1583784D01*
X311939D01*
X313718Y1582005D01*
Y1562624D01*
X311231Y1554426D01*
X292100Y1538725D01*
X273924Y1531196D01*
X267340Y1524612D01*
X264070Y1516715D01*
X257543Y1450483D01*
X237197Y1397738D01*
X234076Y1385279D01*
X230909Y1359601D01*
X216988Y1325991D01*
X183690Y1276158D01*
X181165Y1270063D01*
Y1259824D01*
G01X309094Y1580670D02*
Y1582174D01*
X309594Y1582674D01*
X311479D01*
X312608Y1581545D01*
Y1562789D01*
X310266Y1555071D01*
X299999Y1546645D01*
X299380Y1546706D01*
X297910Y1545499D01*
X297849Y1544880D01*
X296381Y1543675D01*
X295762Y1543736D01*
X294292Y1542530D01*
X294231Y1541910D01*
X291523Y1539688D01*
X273295Y1532137D01*
X266399Y1525241D01*
X262981Y1516988D01*
X256453Y1450742D01*
X236136Y1398074D01*
X232982Y1385483D01*
X229825Y1359887D01*
X222914Y1343202D01*
Y1343200D01*
X216004Y1326517D01*
X182706Y1276684D01*
X180055Y1270284D01*
Y1259824D01*
G01X283110Y1581457D02*
Y1579953D01*
X283610Y1579453D01*
X286146D01*
X287733Y1577866D01*
Y1557309D01*
X286263Y1553760D01*
X284347Y1551844D01*
X267084Y1540310D01*
X257014Y1530240D01*
X251926Y1517957D01*
X245231Y1449919D01*
X226422Y1401162D01*
X222960Y1387341D01*
X219896Y1362501D01*
X207907Y1333559D01*
X174442Y1283474D01*
X169944Y1272617D01*
Y1259824D01*
G01X291771Y1580670D02*
Y1582174D01*
X292271Y1582674D01*
X294156D01*
X295285Y1581545D01*
Y1561863D01*
X292523Y1555194D01*
X289285Y1551956D01*
X268770Y1538248D01*
X259384Y1528862D01*
X255073Y1518455D01*
X248405Y1450782D01*
X228953Y1400359D01*
X225573Y1386865D01*
X222482Y1361819D01*
X209338Y1330081D01*
X183385Y1291240D01*
X183386D01*
X182775Y1291118D01*
X181719Y1289538D01*
X181840Y1288927D01*
X180785Y1287348D01*
X180174Y1287227D01*
X179118Y1285646D01*
X179239Y1285036D01*
X175866Y1279987D01*
X172574Y1272039D01*
Y1259824D01*
G01X283110Y1576339D02*
Y1577843D01*
X283610Y1578343D01*
X285686D01*
X286623Y1577406D01*
Y1557530D01*
X285322Y1554389D01*
X283639Y1552706D01*
X266376Y1541172D01*
X256073Y1530869D01*
X250837Y1518230D01*
X244141Y1450178D01*
X225361Y1401498D01*
X221866Y1387545D01*
X218812Y1362787D01*
X206923Y1334085D01*
X191528Y1311045D01*
X191529D01*
X190918Y1310923D01*
X189862Y1309343D01*
X189983Y1308732D01*
X188928Y1307153D01*
X188318Y1307031D01*
X187261Y1305450D01*
X187382Y1304840D01*
Y1304839D01*
X173458Y1284000D01*
X168834Y1272838D01*
Y1259824D01*
G01X291771Y1585788D02*
Y1584284D01*
X292271Y1583784D01*
X294616D01*
X296395Y1582005D01*
Y1561642D01*
X293464Y1554565D01*
X289993Y1551094D01*
X269478Y1537386D01*
X260325Y1528233D01*
X256162Y1518182D01*
X249495Y1450523D01*
X230014Y1400023D01*
X226667Y1386661D01*
X223566Y1361533D01*
X210322Y1329555D01*
X180163Y1284420D01*
X180162Y1284419D01*
X176850Y1279461D01*
X173684Y1271818D01*
Y1259824D01*
G01X300433Y1576339D02*
Y1577843D01*
X300933Y1578343D01*
X303009D01*
X303946Y1577406D01*
Y1558461D01*
X302816Y1554734D01*
X302390Y1554097D01*
X288028Y1542311D01*
X284036Y1540658D01*
X283461Y1540896D01*
X281705Y1540169D01*
X281467Y1539593D01*
X279712Y1538867D01*
X279137Y1539105D01*
X277381Y1538378D01*
X277143Y1537802D01*
X277142D01*
X271167Y1535327D01*
X262792Y1526952D01*
X258723Y1517129D01*
X252102Y1449915D01*
X232547Y1399224D01*
X229277Y1386172D01*
X226153Y1360851D01*
X212670Y1328296D01*
X179199Y1278205D01*
X176315Y1271243D01*
Y1259824D01*
G01X343740Y1585788D02*
Y1584284D01*
X344240Y1583784D01*
X346585D01*
X348363Y1582006D01*
Y1560955D01*
X343569Y1551987D01*
X310275Y1529741D01*
X282049Y1518049D01*
X280878Y1516878D01*
X278927Y1512166D01*
X274478Y1421626D01*
Y1347640D01*
X272596Y1343096D01*
X198215Y1268714D01*
X196125Y1263668D01*
Y1259824D01*
G01X343740Y1580670D02*
Y1582174D01*
X344240Y1582674D01*
X346125D01*
X347253Y1581546D01*
Y1561234D01*
X342720Y1552756D01*
X338371Y1549850D01*
X337761Y1549972D01*
X336180Y1548915D01*
X336059Y1548305D01*
X334480Y1547250D01*
X333869Y1547371D01*
X332289Y1546315D01*
X332167Y1545704D01*
X309749Y1530725D01*
X281420Y1518990D01*
X279937Y1517507D01*
X277827Y1512413D01*
X273368Y1421654D01*
Y1347861D01*
X271655Y1343725D01*
X197274Y1269343D01*
X195015Y1263889D01*
Y1259824D01*
G01X335078Y1581457D02*
Y1579953D01*
X335578Y1579453D01*
X338114D01*
X339701Y1577866D01*
Y1557309D01*
X338231Y1553760D01*
X337386Y1552915D01*
X306387Y1532201D01*
X279921Y1521239D01*
X277526Y1518844D01*
X275258Y1513369D01*
X268225Y1441947D01*
X262238Y1411850D01*
Y1346604D01*
X258943Y1341672D01*
X231444Y1308165D01*
X195265Y1271987D01*
X192385Y1265037D01*
Y1259824D01*
G01X335078Y1576339D02*
Y1577843D01*
X335578Y1578343D01*
X337654D01*
X338591Y1577406D01*
Y1557530D01*
X337290Y1554389D01*
X336678Y1553777D01*
X333086Y1551377D01*
X332476Y1551499D01*
X330896Y1550442D01*
X330774Y1549832D01*
X329195Y1548777D01*
X328584Y1548898D01*
X327004Y1547842D01*
X326882Y1547231D01*
X326881D01*
X305861Y1533185D01*
X279292Y1522180D01*
X276585Y1519473D01*
X274169Y1513642D01*
X267125Y1442110D01*
X261128Y1411960D01*
Y1346941D01*
X258050Y1342334D01*
X230620Y1308912D01*
X194324Y1272616D01*
X191275Y1265258D01*
Y1259824D01*
G01X326417Y1585788D02*
Y1584284D01*
X326917Y1583784D01*
X329262D01*
X331040Y1582006D01*
Y1562624D01*
X329551Y1557714D01*
X325008Y1550917D01*
X309005Y1539647D01*
X297874Y1532973D01*
X278183Y1524819D01*
X274043Y1520679D01*
X271622Y1514834D01*
X264820Y1445790D01*
X249998Y1410002D01*
Y1344372D01*
X243899Y1335244D01*
X216880Y1302320D01*
X191853Y1274709D01*
X188645Y1266969D01*
Y1259824D01*
G01X326417Y1580670D02*
Y1582174D01*
X326917Y1582674D01*
X328802D01*
X329930Y1581546D01*
Y1562789D01*
X328536Y1558194D01*
X324200Y1551706D01*
X321228Y1549613D01*
X320615Y1549720D01*
X319061Y1548625D01*
X318954Y1548012D01*
X317401Y1546918D01*
X316788Y1547025D01*
X315234Y1545930D01*
X315127Y1545317D01*
X308399Y1540578D01*
X297373Y1533968D01*
X277554Y1525760D01*
X273102Y1521308D01*
X270533Y1515107D01*
X263731Y1446063D01*
X248888Y1410223D01*
Y1344709D01*
X243006Y1335906D01*
X216039Y1303045D01*
X190901Y1275312D01*
X187535Y1267190D01*
Y1259824D01*
G01X317756Y1581457D02*
Y1579953D01*
X318256Y1579453D01*
X320792D01*
X322379Y1577866D01*
Y1558293D01*
X321155Y1554258D01*
X320543Y1553342D01*
X317126Y1550538D01*
X305630Y1542442D01*
X293841Y1535374D01*
X276054Y1528008D01*
X270671Y1522625D01*
X267966Y1516094D01*
X261477Y1450225D01*
X240784Y1396580D01*
X237781Y1384590D01*
X234597Y1358784D01*
X234598D01*
X234579Y1358633D01*
X220322Y1324209D01*
X187495Y1275081D01*
X184905Y1268831D01*
Y1259824D01*
G01X317756Y1576339D02*
Y1577843D01*
X318256Y1578343D01*
X320332D01*
X321269Y1577406D01*
Y1558458D01*
X320140Y1554738D01*
X319711Y1554096D01*
X316453Y1551422D01*
X314900Y1550328D01*
X314287Y1550435D01*
X312733Y1549340D01*
X312626Y1548727D01*
X311073Y1547633D01*
X310460Y1547740D01*
X308906Y1546645D01*
X308799Y1546032D01*
X305024Y1543373D01*
X293340Y1536369D01*
X275425Y1528949D01*
X269730Y1523254D01*
X266877Y1516367D01*
X260387Y1450484D01*
X239723Y1396916D01*
X236687Y1384794D01*
X233495Y1358919D01*
X229956Y1350374D01*
Y1350372D01*
X219338Y1324735D01*
X186511Y1275607D01*
X183795Y1269052D01*
Y1259824D01*
G01X330512Y1122503D02*
X335734D01*
X340441Y1119774D01*
X371963Y1089219D01*
X380411Y1074239D01*
X380858Y1061194D01*
X347219Y946021D01*
X340440Y914163D01*
X343018Y663001D01*
X341196Y590658D01*
X339622Y579529D01*
X339623D01*
X338016Y568174D01*
X325287Y551590D01*
X323957Y547870D01*
X315147Y542030D01*
X290137Y500170D01*
X286678Y496797D01*
X273889Y491482D01*
X264889Y489742D01*
X257850D01*
X256705Y488597D01*
G01X330512Y1129984D02*
X338583D01*
X338850Y1129821D01*
Y1129820D01*
X344388Y1126420D01*
X378261Y1093732D01*
X387979Y1076270D01*
X388577Y1060150D01*
X353992Y941705D01*
X348298Y913768D01*
X350908Y663520D01*
X348906Y590143D01*
X347889Y576190D01*
X338332Y532374D01*
X336267Y529160D01*
X327337Y524190D01*
X325647Y522500D01*
X317177Y517830D01*
X295667Y492890D01*
X286837Y484160D01*
X266204Y475569D01*
X257850D01*
X256705Y474424D01*
G01X330512Y1128874D02*
X338269D01*
X343704Y1125537D01*
X377371Y1093048D01*
X386879Y1075963D01*
X387461Y1060289D01*
X352913Y941972D01*
X347186Y913874D01*
X349797Y663529D01*
X347797Y590199D01*
X346787Y576350D01*
X337290Y532806D01*
X335483Y529995D01*
X326662Y525085D01*
X324973Y523396D01*
X316466Y518707D01*
X304422Y504741D01*
X303928Y504705D01*
X302654Y503227D01*
X302690Y502733D01*
X301417Y501257D01*
X300923Y501221D01*
X299649Y499743D01*
X299685Y499249D01*
X298412Y497773D01*
X297919Y497737D01*
X296644Y496259D01*
X296680Y495766D01*
X294855Y493649D01*
X286210Y485102D01*
X283710Y484061D01*
X283121Y484304D01*
X281320Y483554D01*
X281078Y482965D01*
X279278Y482216D01*
X278689Y482459D01*
X276888Y481709D01*
X276646Y481120D01*
X274846Y480371D01*
X274257Y480613D01*
X272456Y479863D01*
X272214Y479274D01*
X270414Y478525D01*
X269825Y478767D01*
X268024Y478018D01*
X267782Y477428D01*
Y477429D01*
X265982Y476679D01*
X257850D01*
X256705Y477824D01*
G01X330512Y1121393D02*
X335435D01*
X339766Y1118882D01*
X371074Y1088533D01*
X379310Y1073930D01*
X379742Y1061334D01*
X346141Y946293D01*
X339328Y914274D01*
X341907Y663009D01*
X340087Y590750D01*
X336957Y568619D01*
X324300Y552128D01*
X323035Y548592D01*
X314323Y542816D01*
X301509Y521370D01*
X300892Y521215D01*
X299891Y519540D01*
X300047Y518922D01*
X299047Y517249D01*
X298430Y517094D01*
X297429Y515419D01*
X297585Y514801D01*
X296585Y513128D01*
X296586D01*
X295969Y512973D01*
X294967Y511298D01*
X295123Y510681D01*
X292365Y506064D01*
X291748Y505908D01*
X290746Y504233D01*
X290902Y503616D01*
X289258Y500864D01*
X286058Y497743D01*
X278629Y494656D01*
X278041Y494899D01*
X276240Y494151D01*
X275997Y493562D01*
Y493561D01*
X273567Y492551D01*
X270565Y491971D01*
X270038Y492327D01*
X268123Y491957D01*
X267766Y491429D01*
X264782Y490852D01*
X257850D01*
X256705Y491997D01*
G01X330384Y1115023D02*
X333273D01*
X336906Y1112634D01*
X366030Y1084322D01*
X372949Y1072077D01*
X373165Y1063911D01*
X343102Y961149D01*
X332791Y918553D01*
X328721Y876381D01*
X320011Y632688D01*
X314565Y595900D01*
X314566D01*
X309123Y559139D01*
X306698Y547842D01*
X305572Y545216D01*
X302892Y541139D01*
Y541138D01*
X302780Y540968D01*
X292177Y533310D01*
X265067Y519703D01*
X257850D01*
X256705Y518558D01*
G01X330384Y1113913D02*
X332940D01*
X336207Y1111764D01*
X365142Y1083637D01*
X371846Y1071771D01*
X372050Y1064056D01*
X342029Y961436D01*
X331693Y918738D01*
X327612Y876454D01*
X318903Y632789D01*
X313467Y596063D01*
X313466Y596062D01*
Y596060D01*
X308030Y559337D01*
X305635Y548180D01*
X304590Y545744D01*
X301964Y541749D01*
X297154Y538275D01*
X296526Y538376D01*
X294944Y537233D01*
X294843Y536605D01*
X291599Y534262D01*
X287971Y532441D01*
X287367Y532642D01*
X285623Y531766D01*
X285422Y531162D01*
X283680Y530288D01*
X283075Y530488D01*
X281332Y529612D01*
X281131Y529008D01*
X279389Y528134D01*
X278785Y528335D01*
X277041Y527459D01*
X276840Y526855D01*
X275098Y525981D01*
X274494Y526181D01*
X272751Y525305D01*
X272550Y524701D01*
X270808Y523827D01*
X270204Y524027D01*
X268460Y523151D01*
X268260Y522547D01*
X268259Y522548D01*
X264803Y520813D01*
X257850D01*
X256705Y521958D01*
G01X330512Y1107543D02*
X331450D01*
X332277Y1106721D01*
X333355Y1104205D01*
X333703Y1087828D01*
X328680Y1060722D01*
X326119Y1042649D01*
X312125Y631796D01*
Y631713D01*
X312101Y631689D01*
X295298Y557909D01*
X295297Y557907D01*
Y557908D01*
X294571Y556672D01*
X291196Y553297D01*
X290108Y550671D01*
Y549072D01*
X288463Y546271D01*
X283333Y541070D01*
X265644Y533876D01*
X257850D01*
X256705Y532731D01*
G01Y536131D02*
X257850Y534986D01*
X265426D01*
X268292Y536152D01*
X268540Y536739D01*
X270347Y537474D01*
X270933Y537226D01*
X272739Y537960D01*
X272986Y538548D01*
X274793Y539282D01*
X275380Y539035D01*
X277186Y539769D01*
X277433Y540356D01*
X279241Y541091D01*
X279827Y540844D01*
X282703Y542013D01*
X287575Y546953D01*
X288998Y549374D01*
Y550892D01*
X290255Y553926D01*
X293686Y557357D01*
X294253Y558323D01*
X295723Y564778D01*
X295384Y565317D01*
X295817Y567219D01*
X296357Y567558D01*
X296789Y569459D01*
X296451Y569998D01*
X296884Y571900D01*
X297423Y572239D01*
X297855Y574140D01*
X297517Y574679D01*
X297950Y576581D01*
X298489Y576920D01*
X311018Y631936D01*
X311019Y631940D01*
X325011Y1042746D01*
X327584Y1060901D01*
X332590Y1087918D01*
X332249Y1103966D01*
X331341Y1106085D01*
X330992Y1106433D01*
X330512D01*
G01X256705Y571997D02*
X257850Y570852D01*
X264439D01*
X267392Y572088D01*
X269314Y574037D01*
X269311Y574532D01*
X270681Y575921D01*
X271176Y575924D01*
X272545Y577312D01*
X272542Y577807D01*
X273912Y579196D01*
X274407Y579199D01*
X276270Y581088D01*
X283786Y592667D01*
X286760Y600930D01*
X297579Y611958D01*
X302900Y631909D01*
X317000Y1031411D01*
Y1056142D01*
X314700Y1067707D01*
Y1069976D01*
G01X256705Y568597D02*
X257850Y569742D01*
X264662D01*
X268026Y571149D01*
X277140Y580389D01*
X284787Y592170D01*
X287723Y600325D01*
X298577Y611389D01*
X303641Y630378D01*
Y630377D01*
X304005Y631744D01*
X318110Y1031391D01*
Y1056252D01*
X315810Y1067817D01*
Y1069976D01*
G01X256705Y586171D02*
X257850Y585026D01*
X266084D01*
X268805Y587747D01*
Y588242D01*
X270185Y589622D01*
X270680D01*
X272058Y591000D01*
Y591495D01*
X273438Y592875D01*
X273933D01*
X275768Y594710D01*
X281983Y609623D01*
X290358Y622222D01*
X295077Y633507D01*
X295247Y634283D01*
Y634284D01*
X295246D01*
X295248Y634294D01*
X295332Y634673D01*
X295333Y634674D01*
X295417Y635057D01*
X309217Y1025666D01*
X309354Y1055627D01*
X307220Y1066486D01*
Y1069976D01*
G01X256705Y582771D02*
X257850Y583916D01*
X266544D01*
X276708Y594080D01*
X282967Y609097D01*
X291342Y621695D01*
X296140Y633171D01*
X296332Y634046D01*
X296334Y634056D01*
X296417Y634434D01*
X296418Y634439D01*
X296523Y634918D01*
X310327Y1025644D01*
X310465Y1055733D01*
X308330Y1066595D01*
Y1069976D01*
G01X256705Y600344D02*
X257850Y599199D01*
X266528D01*
X270160Y602831D01*
X273550Y610967D01*
X277660Y617051D01*
X277566Y617537D01*
X278658Y619154D01*
X279144Y619248D01*
X280235Y620863D01*
X280141Y621349D01*
X281234Y622966D01*
X281719Y623060D01*
X283525Y625734D01*
X287486Y635262D01*
X301479Y1026186D01*
X301773Y1054505D01*
X299740Y1065012D01*
Y1069976D01*
G01X256705Y596944D02*
X257850Y598089D01*
X266988D01*
X271100Y602201D01*
X274533Y610437D01*
X284508Y625205D01*
X284551Y625308D01*
X284550D01*
X288589Y635021D01*
X302589Y1026160D01*
X302885Y1054606D01*
X300850Y1065119D01*
Y1069976D01*
G01X256705Y611117D02*
X257850Y612262D01*
X261193D01*
X263635Y614703D01*
X267367Y641184D01*
Y641183D01*
X294564Y1028630D01*
X295233Y1054205D01*
X293370Y1063904D01*
Y1069976D01*
G01X256705Y614517D02*
X257526Y613696D01*
X258309Y613372D01*
X260733D01*
X262587Y615226D01*
X263073Y618678D01*
X262690Y619187D01*
X262963Y621119D01*
X263472Y621501D01*
X263744Y623431D01*
X263361Y623940D01*
X263633Y625872D01*
X264142Y626255D01*
X266262Y641300D01*
X293454Y1028683D01*
X294120Y1054114D01*
X292260Y1063798D01*
Y1069976D01*
G01X291771Y1462953D02*
Y1464457D01*
X292271Y1464957D01*
X294373D01*
X295285Y1464045D01*
Y1454373D01*
X295911Y1448006D01*
X296010Y1445983D01*
X295592Y1445522D01*
X295685Y1443623D01*
X296147Y1443205D01*
X296240Y1441308D01*
X295753Y1440770D01*
X295838Y1439017D01*
X296376Y1438530D01*
X297848Y1408545D01*
Y1347505D01*
X264951Y1277957D01*
X262338Y1266331D01*
Y1259824D01*
G01X283110Y1458622D02*
Y1460127D01*
X283610Y1460627D01*
X285579D01*
X286649Y1459557D01*
Y1446428D01*
X286555Y1444531D01*
X286556D01*
X286094Y1444113D01*
X286001Y1442214D01*
X286419Y1441753D01*
X286326Y1439856D01*
X285864Y1439438D01*
X285771Y1437539D01*
X286189Y1437078D01*
X286096Y1435181D01*
X285634Y1434763D01*
X285541Y1432864D01*
X285959Y1432403D01*
X285608Y1425226D01*
Y1346207D01*
X280105Y1328066D01*
X262107Y1284616D01*
X258598Y1266977D01*
Y1260112D01*
G01X283110Y1463741D02*
Y1462237D01*
X283610Y1461737D01*
X286039D01*
X287759Y1460017D01*
Y1446400D01*
X286718Y1425198D01*
Y1346042D01*
X281152Y1327691D01*
X263175Y1284292D01*
X259708Y1266867D01*
Y1260112D01*
G01X330412Y1133724D02*
X340586D01*
X345411Y1130680D01*
X381263Y1096062D01*
X391687Y1077658D01*
X392419Y1059547D01*
X358138Y941806D01*
X352125Y912895D01*
X354748Y663481D01*
X352966Y589875D01*
X351401Y573164D01*
X339276Y519203D01*
X336177Y515130D01*
X292097Y482260D01*
X286097Y476280D01*
X267256Y468482D01*
X265150D01*
X264005Y467337D01*
G01Y470737D02*
X265150Y469592D01*
X267034D01*
X268836Y470338D01*
Y470337D01*
X269080Y470926D01*
X270883Y471672D01*
X271471Y471428D01*
X273271Y472173D01*
X273272D01*
X273516Y472762D01*
X275319Y473508D01*
X275907Y473264D01*
X277707Y474009D01*
X277708D01*
X277952Y474598D01*
X279755Y475344D01*
X280343Y475100D01*
X285469Y477222D01*
X291369Y483103D01*
X299047Y488828D01*
X299138Y489458D01*
X300702Y490624D01*
X301332Y490532D01*
X302895Y491697D01*
X302986Y492327D01*
X304551Y493494D01*
X305180Y493402D01*
X306743Y494567D01*
X306834Y495197D01*
X308399Y496364D01*
X309028Y496272D01*
X335388Y515927D01*
X338246Y519683D01*
X350302Y573338D01*
X351857Y589940D01*
X353637Y663489D01*
X351013Y913004D01*
X357060Y942075D01*
X391302Y1059683D01*
X390588Y1077344D01*
X380376Y1095375D01*
X344722Y1129802D01*
X340265Y1132614D01*
X330412D01*
G01X264005Y484910D02*
X265150Y483765D01*
X267394D01*
X269194Y484513D01*
X269437Y485102D01*
X271239Y485851D01*
X271827Y485608D01*
X273627Y486356D01*
X273870Y486945D01*
X275672Y487694D01*
X276260Y487451D01*
X278060Y488199D01*
X278303Y488788D01*
X280105Y489536D01*
X280693Y489294D01*
X285546Y491310D01*
X292853Y498666D01*
X298474Y507089D01*
X298349Y507713D01*
X299433Y509336D01*
X300057Y509460D01*
X300056D01*
X301138Y511081D01*
X301013Y511706D01*
X302097Y513329D01*
X302721Y513453D01*
X303803Y515074D01*
X303678Y515699D01*
X304762Y517322D01*
X305386Y517446D01*
X312715Y528428D01*
X329584Y545275D01*
X340407Y565520D01*
X343957Y590490D01*
X345907Y663218D01*
X343125Y914047D01*
X349647Y944691D01*
X383667Y1061058D01*
X383025Y1075091D01*
X374067Y1090881D01*
X341630Y1122312D01*
X336180Y1125133D01*
X330412D01*
G01X264005Y481510D02*
X265150Y482655D01*
X267616D01*
X286177Y490370D01*
X293717Y497960D01*
X313577Y527720D01*
X330486Y544606D01*
X341479Y565169D01*
X345065Y590397D01*
X347018Y663209D01*
X344237Y913936D01*
X350724Y944419D01*
X384785Y1060924D01*
X384122Y1075407D01*
X374955Y1091568D01*
X342285Y1123223D01*
X336690Y1126119D01*
X336566Y1126243D01*
X330412D01*
G01Y1117653D02*
X334447D01*
X338393Y1114884D01*
X368077Y1086190D01*
X375575Y1072815D01*
X375953Y1062070D01*
X342806Y948661D01*
X335387Y914414D01*
X337757Y662730D01*
X336317Y596660D01*
X335127Y593920D01*
X326857Y589790D01*
X322507Y584890D01*
X317617Y583720D01*
X315797Y581807D01*
X311249Y551446D01*
X308341Y544078D01*
X305291Y539579D01*
X297512Y532626D01*
X296876Y532661D01*
X295422Y531361D01*
X295386Y530725D01*
X290547Y526400D01*
X288721Y525436D01*
X288113Y525623D01*
X286387Y524711D01*
X286200Y524103D01*
X284476Y523193D01*
X283868Y523380D01*
X282142Y522468D01*
X281955Y521860D01*
X280231Y520950D01*
X279622Y521137D01*
X277897Y520226D01*
X277710Y519617D01*
X275986Y518707D01*
X275377Y518894D01*
X273652Y517983D01*
X273465Y517374D01*
X271741Y516464D01*
X271133Y516652D01*
X269408Y515740D01*
X269221Y515132D01*
X266560Y513726D01*
X265150D01*
X264005Y514871D01*
G01X330412Y1118763D02*
X334799D01*
X339102Y1115743D01*
X368966Y1086875D01*
X376675Y1073123D01*
X377069Y1061930D01*
X343883Y948387D01*
X336499Y914300D01*
X338868Y662723D01*
X337423Y596418D01*
X335985Y593107D01*
X327545Y588892D01*
X323106Y583891D01*
X322765Y583809D01*
Y583810D01*
X318194Y582716D01*
X316843Y581296D01*
X312328Y551156D01*
X309329Y543557D01*
X306134Y538842D01*
X298252Y531798D01*
Y531797D01*
X291186Y525482D01*
X266836Y512616D01*
X265150D01*
X264005Y511471D01*
G01X330412Y1111283D02*
X332032D01*
X334670Y1109519D01*
X336612Y1107175D01*
X337579Y1104893D01*
X337926Y1090902D01*
Y1089349D01*
X333491Y1066040D01*
X329896Y1042115D01*
X315895Y630881D01*
X302700Y554757D01*
Y550350D01*
X302095Y546859D01*
X300440Y544891D01*
X266719Y526789D01*
X265150D01*
X264005Y525644D01*
G01X330412Y1110173D02*
X331695D01*
X333918Y1108686D01*
X335653Y1106592D01*
X336474Y1104654D01*
X336816Y1090888D01*
Y1089454D01*
X332396Y1066226D01*
X328788Y1042217D01*
X314788Y630995D01*
X301590Y554853D01*
Y550446D01*
X301052Y547344D01*
X299727Y545769D01*
X294867Y543160D01*
X294866D01*
X294256Y543343D01*
X292537Y542420D01*
X292354Y541811D01*
X290636Y540889D01*
X290026Y541072D01*
X288307Y540149D01*
X288124Y539540D01*
X286406Y538618D01*
X285796Y538802D01*
X284077Y537879D01*
X283894Y537270D01*
X280997Y535715D01*
X280387Y535898D01*
X278668Y534975D01*
X278485Y534366D01*
X276767Y533444D01*
X276157Y533627D01*
X274438Y532704D01*
X274255Y532095D01*
X272537Y531173D01*
X271928Y531357D01*
X270209Y530433D01*
X270025Y529824D01*
X266439Y527899D01*
X265150D01*
X264005Y529044D01*
G01X324300Y1075611D02*
Y1060257D01*
X322382Y1044125D01*
X308161Y632323D01*
X307772Y629856D01*
X301826Y609051D01*
X296362Y601698D01*
X290606Y596191D01*
X288452Y590139D01*
X274317Y568127D01*
X266127Y562655D01*
X265150D01*
X264005Y561510D01*
G01X323190Y1075611D02*
Y1060323D01*
X321274Y1044210D01*
X307054Y632450D01*
X306686Y630096D01*
X300814Y609551D01*
X295526Y602436D01*
X289648Y596812D01*
X287448Y590632D01*
X286025Y588414D01*
X285541Y588309D01*
X284487Y586667D01*
X284592Y586183D01*
X283539Y584543D01*
X282917Y584408D01*
X281863Y582766D01*
X281998Y582144D01*
X280945Y580504D01*
X280323Y580369D01*
X279269Y578727D01*
X279404Y578105D01*
X278351Y576465D01*
X277729Y576330D01*
X276675Y574688D01*
X276810Y574066D01*
X273507Y568922D01*
X270845Y567143D01*
X270221Y567268D01*
X268599Y566183D01*
X268475Y565559D01*
X265790Y563765D01*
X265150D01*
X264005Y564910D01*
G01Y575684D02*
X265150Y576829D01*
X267503D01*
X274089Y583415D01*
X280560Y593039D01*
X284202Y601975D01*
X290836Y610893D01*
X294606Y613974D01*
X295921Y616028D01*
X300308Y633904D01*
X314142Y1025568D01*
X314282Y1055838D01*
X312070Y1067091D01*
Y1069976D01*
G01X264005Y579084D02*
X265150Y577939D01*
X267043D01*
X268421Y579317D01*
Y579812D01*
X269801Y581192D01*
X270296D01*
X273228Y584124D01*
X274316Y585742D01*
X274220Y586227D01*
X275309Y587847D01*
X275795Y587942D01*
X279575Y593564D01*
X283226Y602525D01*
X290027Y611666D01*
X293766Y614722D01*
X294886Y616472D01*
X297044Y625265D01*
Y625266D01*
X299202Y634058D01*
X313032Y1025590D01*
X313171Y1055732D01*
X310960Y1066982D01*
Y1069976D01*
G01X264005Y589857D02*
X265150Y591002D01*
X267474D01*
X273421Y596845D01*
X276942Y605218D01*
X276944Y605219D01*
X279006Y610125D01*
X287922Y623372D01*
X287965Y623474D01*
X287964D01*
X292529Y634450D01*
X306428Y1026646D01*
X306675Y1055359D01*
X304590Y1066087D01*
Y1069976D01*
G01X264005Y593257D02*
X265150Y592112D01*
X267019D01*
X272484Y597481D01*
X273286Y599389D01*
X273099Y599848D01*
X273856Y601646D01*
X274314Y601833D01*
X275069Y603630D01*
X274882Y604088D01*
X275639Y605887D01*
X276098Y606074D01*
X278024Y610655D01*
X286939Y623900D01*
X291426Y634691D01*
X305318Y1026670D01*
X305564Y1055257D01*
X303480Y1065980D01*
Y1069976D01*
G01X264005Y604030D02*
X265145Y605170D01*
X266849D01*
X268811Y607132D01*
X269746Y609188D01*
X270798Y624536D01*
X270800Y624538D01*
Y631444D01*
X271254Y638049D01*
X272892Y648313D01*
X298211Y1017019D01*
X299059Y1054375D01*
X297110Y1064792D01*
Y1069976D01*
G01X264005Y607430D02*
X264677Y606758D01*
X265831Y606280D01*
X266389D01*
X267884Y607775D01*
X268652Y609464D01*
X268785Y611408D01*
X268367Y611888D01*
X268500Y613834D01*
X268980Y614252D01*
X269113Y616197D01*
X268695Y616677D01*
X268828Y618623D01*
X269309Y619041D01*
X269687Y624574D01*
X269690Y624576D01*
Y631483D01*
X270150Y638175D01*
X271788Y648439D01*
X297101Y1017070D01*
X297946Y1054284D01*
X296000Y1064689D01*
Y1069976D01*
G01X291771Y1468071D02*
Y1466567D01*
X292271Y1466067D01*
X294833D01*
X296395Y1464505D01*
Y1454428D01*
X297019Y1448088D01*
X298958Y1408573D01*
Y1347255D01*
X266008Y1277593D01*
X263448Y1266207D01*
Y1259824D01*
G01X300433Y1458622D02*
Y1460127D01*
X300933Y1460627D01*
X302902D01*
X303972Y1459557D01*
Y1451140D01*
X304259Y1449200D01*
X303889Y1448700D01*
X304168Y1446820D01*
X304668Y1446449D01*
X304946Y1444570D01*
X304576Y1444070D01*
X304854Y1442190D01*
X305355Y1441819D01*
X305354D01*
X305633Y1439940D01*
X305263Y1439440D01*
X305541Y1437560D01*
X306042Y1437189D01*
X306041D01*
X310088Y1409911D01*
Y1346812D01*
X309362Y1344188D01*
X299862Y1328340D01*
X299863D01*
X269310Y1277367D01*
X266078Y1265683D01*
Y1259824D01*
G01X300433Y1463741D02*
Y1462237D01*
X300933Y1461737D01*
X303362D01*
X305082Y1460017D01*
Y1451222D01*
X311198Y1409993D01*
Y1346661D01*
X310392Y1343747D01*
X270340Y1276926D01*
X267188Y1265532D01*
Y1259824D01*
G01X309094Y1468071D02*
Y1466567D01*
X309594Y1466067D01*
X312156D01*
X313718Y1464505D01*
Y1456315D01*
X314226Y1452896D01*
X316609Y1443350D01*
X323438Y1408768D01*
Y1347548D01*
X322124Y1343320D01*
X275302Y1275223D01*
X270929Y1264664D01*
Y1259824D01*
G01X309094Y1462953D02*
Y1464457D01*
X309594Y1464957D01*
X311696D01*
X312608Y1464045D01*
Y1456233D01*
X313135Y1452679D01*
X315525Y1443108D01*
X315893Y1441244D01*
X315585Y1440787D01*
X315973Y1438824D01*
X316432Y1438516D01*
X316800Y1436652D01*
X316517Y1436232D01*
X316917Y1434207D01*
X317339Y1433924D01*
X317706Y1432061D01*
X317401Y1431607D01*
X317790Y1429637D01*
X318245Y1429332D01*
X322328Y1408659D01*
Y1347717D01*
X321113Y1343811D01*
X274321Y1275756D01*
X269819Y1264885D01*
Y1259824D01*
G01X317756Y1458622D02*
Y1460127D01*
X318256Y1460627D01*
X320225D01*
X321295Y1459557D01*
Y1456105D01*
X322820Y1451077D01*
X322527Y1450528D01*
X323078Y1448709D01*
X323628Y1448416D01*
X323627D01*
X324179Y1446598D01*
X323886Y1446050D01*
X324437Y1444230D01*
X324987Y1443937D01*
X324985D01*
X325537Y1442119D01*
X325538D01*
X325245Y1441571D01*
X325796Y1439751D01*
X326346Y1439458D01*
X326345D01*
X333484Y1415925D01*
X334568Y1408618D01*
Y1346531D01*
X331719Y1339652D01*
X328447Y1335667D01*
X328448D01*
X277700Y1273833D01*
X273559Y1263831D01*
Y1259824D01*
G01X317756Y1463741D02*
Y1462237D01*
X318256Y1461737D01*
X320685D01*
X322405Y1460017D01*
Y1456270D01*
X327407Y1439782D01*
X327408Y1439779D01*
X334570Y1416169D01*
X335678Y1408700D01*
Y1346310D01*
X332682Y1339075D01*
X278663Y1273256D01*
X274669Y1263610D01*
Y1259824D01*
G01X326417Y1462953D02*
Y1464457D01*
X326917Y1464957D01*
X329019D01*
X329930Y1464046D01*
Y1456161D01*
X330426Y1453665D01*
X331446Y1450814D01*
X331246Y1450391D01*
X331959Y1448396D01*
X332383Y1448196D01*
X333023Y1446408D01*
X332760Y1445852D01*
X333404Y1444052D01*
X333960Y1443789D01*
X333959D01*
X334599Y1442001D01*
X334600D01*
X334392Y1441561D01*
X335097Y1439590D01*
X335537Y1439382D01*
X344348Y1414757D01*
X346808Y1408819D01*
Y1346609D01*
X341085Y1338044D01*
X280938Y1271682D01*
X277299Y1262897D01*
Y1259824D01*
G01X326417Y1468071D02*
Y1466567D01*
X326917Y1466067D01*
X329479D01*
X331040Y1464506D01*
Y1456271D01*
X331499Y1453962D01*
X345384Y1415157D01*
X347918Y1409040D01*
Y1346272D01*
X341963Y1337359D01*
X281890Y1271079D01*
X278409Y1262676D01*
Y1259824D01*
G01X343740Y1468071D02*
Y1466567D01*
X344240Y1466067D01*
X346802D01*
X348364Y1464505D01*
Y1457824D01*
X349959Y1452565D01*
X363490Y1423957D01*
X370671Y1413210D01*
X372398Y1409040D01*
Y1347277D01*
X370219Y1343201D01*
X331497Y1309797D01*
X288494Y1266794D01*
X285889Y1260506D01*
Y1259812D01*
G01X335078Y1458622D02*
Y1460127D01*
X335578Y1460627D01*
X337547D01*
X338617Y1459557D01*
Y1455723D01*
X340556Y1451623D01*
X340346Y1451037D01*
X341160Y1449319D01*
X341746Y1449109D01*
X341745D01*
X342557Y1447392D01*
X342558D01*
X342348Y1446806D01*
X343161Y1445087D01*
X343747Y1444878D01*
X344559Y1443161D01*
X344349Y1442575D01*
X345162Y1440856D01*
X345748Y1440647D01*
X347012Y1437974D01*
X359048Y1408819D01*
Y1345751D01*
X358035Y1343305D01*
X284268Y1269538D01*
X281039Y1261742D01*
Y1259824D01*
G01X335078Y1463741D02*
Y1462237D01*
X335578Y1461737D01*
X338007D01*
X339727Y1460017D01*
Y1455973D01*
X348028Y1438424D01*
X360158Y1409040D01*
Y1345530D01*
X358976Y1342676D01*
X285209Y1268909D01*
X282149Y1261521D01*
Y1259824D01*
G01X343740Y1462953D02*
Y1464457D01*
X344240Y1464957D01*
X346342D01*
X347254Y1464045D01*
Y1457659D01*
X348920Y1452164D01*
X349732Y1450447D01*
X349552Y1449945D01*
X350420Y1448112D01*
X350921Y1447933D01*
X351734Y1446216D01*
X351559Y1445729D01*
X352437Y1443876D01*
X352923Y1443702D01*
X353735Y1441985D01*
X353544Y1441452D01*
X354392Y1439661D01*
X354924Y1439471D01*
X362521Y1423408D01*
X369687Y1412684D01*
X371288Y1408819D01*
Y1347556D01*
X369337Y1343907D01*
X330741Y1310611D01*
X287553Y1267423D01*
X284779Y1260727D01*
Y1259812D01*
G01X454385Y1305245D02*
X455530Y1304100D01*
X456415D01*
X456930Y1304615D01*
Y1308611D01*
X454957Y1313374D01*
X453614Y1314717D01*
X452992D01*
X451647Y1316061D01*
Y1316684D01*
X442819Y1325511D01*
X420712Y1337328D01*
X399741Y1341499D01*
X379490Y1361750D01*
Y1403415D01*
X379050Y1403855D01*
Y1405755D01*
X379490Y1406195D01*
Y1408095D01*
X379050Y1408535D01*
Y1410435D01*
X379490Y1410875D01*
Y1412775D01*
X379050Y1413215D01*
Y1415115D01*
X379490Y1415555D01*
Y1417455D01*
X377220Y1420759D01*
X376609Y1420873D01*
X375532Y1422440D01*
X375645Y1423051D01*
X374570Y1424617D01*
X373959Y1424731D01*
X372882Y1426298D01*
X372995Y1426909D01*
X371920Y1428475D01*
X371309Y1428588D01*
X370232Y1430156D01*
X370345Y1430767D01*
X369270Y1432333D01*
X368659Y1432446D01*
X367582Y1434014D01*
X367695Y1434625D01*
X366620Y1436191D01*
X366008Y1436304D01*
X364932Y1437872D01*
X365045Y1438483D01*
X363970Y1440049D01*
X363358Y1440162D01*
X362282Y1441730D01*
X362395Y1442341D01*
X355849Y1451871D01*
Y1505181D01*
X354355Y1506675D01*
X352871D01*
X352401Y1506205D01*
Y1504685D01*
G01X454385Y1301845D02*
X455530Y1302990D01*
X456875D01*
X458040Y1304155D01*
Y1308832D01*
X455898Y1314003D01*
X443488Y1326413D01*
X421090Y1338385D01*
X400288Y1342522D01*
X380600Y1362210D01*
Y1417800D01*
X356959Y1452216D01*
Y1505641D01*
X354815Y1507785D01*
X352901D01*
X352401Y1508285D01*
Y1509804D01*
G01X408159Y1349072D02*
X407010Y1347923D01*
Y1347060D01*
X407770Y1346300D01*
X410352D01*
X411971Y1347919D01*
Y1352603D01*
X407684Y1356890D01*
X405784D01*
X405344Y1356450D01*
X403444D01*
X403004Y1356890D01*
X401104D01*
X400664Y1356450D01*
X398764D01*
X398324Y1356890D01*
X396424D01*
X395984Y1356450D01*
X394084D01*
X393644Y1356890D01*
X391640D01*
X390297Y1358233D01*
X389675D01*
X388330Y1359578D01*
Y1360200D01*
X384990Y1363540D01*
Y1389457D01*
X384550Y1389897D01*
Y1391797D01*
X384990Y1392237D01*
Y1394137D01*
X384550Y1394577D01*
Y1396477D01*
X384990Y1396917D01*
Y1398817D01*
X384550Y1399257D01*
Y1401157D01*
X384990Y1401597D01*
Y1403497D01*
X384550Y1403937D01*
Y1405837D01*
X384990Y1406277D01*
Y1408177D01*
X384550Y1408617D01*
Y1410517D01*
X384990Y1410957D01*
Y1412857D01*
X384550Y1413297D01*
Y1415197D01*
X384990Y1415637D01*
Y1417537D01*
X373817Y1434256D01*
X372954Y1436340D01*
X372378Y1436578D01*
X371651Y1438334D01*
X371890Y1438909D01*
X371163Y1440664D01*
X370588Y1440902D01*
X369860Y1442658D01*
X370099Y1443233D01*
X369372Y1444988D01*
X368797Y1445226D01*
X368069Y1446982D01*
X368308Y1447557D01*
X367581Y1449312D01*
X367006Y1449550D01*
X366278Y1451306D01*
X366517Y1451881D01*
X365790Y1453636D01*
Y1508539D01*
X363294Y1511035D01*
X361643D01*
X361063Y1510455D01*
Y1509016D01*
G01X404759Y1349072D02*
X405900Y1347931D01*
Y1346600D01*
X407310Y1345190D01*
X410812D01*
X413081Y1347459D01*
Y1353063D01*
X408144Y1358000D01*
X392100D01*
X386100Y1364000D01*
Y1417874D01*
X374801Y1434782D01*
X366900Y1453857D01*
Y1508999D01*
X363754Y1512145D01*
X361613D01*
X361063Y1512695D01*
Y1514134D01*
G01X652988Y1260830D02*
X652309D01*
X648440Y1264005D01*
X608452Y1287680D01*
X579438Y1306091D01*
X567778Y1309478D01*
X487590Y1343987D01*
X485497Y1346829D01*
Y1410319D01*
X483814Y1416285D01*
X462400Y1451218D01*
X460510Y1457918D01*
Y1475584D01*
X459003Y1477091D01*
X456839D01*
X456339Y1477591D01*
Y1479095D01*
G01X652988Y1259720D02*
X651911D01*
X647801Y1263093D01*
X607871Y1286733D01*
X578976Y1305068D01*
X567402Y1308431D01*
X486875Y1343086D01*
X484387Y1346464D01*
Y1410165D01*
X482787Y1415836D01*
X468620Y1438946D01*
X468154Y1439058D01*
X467018Y1440911D01*
X467130Y1441377D01*
X466112Y1443039D01*
X465493Y1443187D01*
X464473Y1444851D01*
X464621Y1445470D01*
X461373Y1450769D01*
X459400Y1457764D01*
Y1475124D01*
X458543Y1475981D01*
X456839D01*
X456339Y1475481D01*
Y1473977D01*
G01Y1560985D02*
Y1562488D01*
X456840Y1562989D01*
X458543D01*
X459400Y1562132D01*
Y1560326D01*
X460290Y1558648D01*
X460139Y1558156D01*
X461102Y1556342D01*
X461594Y1556191D01*
X463984Y1551684D01*
X465685Y1550839D01*
X465883Y1550249D01*
X467585Y1549402D01*
X468175Y1549600D01*
X503799Y1531894D01*
X518642Y1526101D01*
X534135Y1523013D01*
X535781Y1521853D01*
X536656Y1520456D01*
X560519Y1456678D01*
X564941Y1440757D01*
X585665Y1386094D01*
X616388Y1324741D01*
X626485Y1313457D01*
X677688Y1283194D01*
X682162Y1278720D01*
X685764Y1270034D01*
Y1259495D01*
G01X456339Y1566103D02*
Y1564599D01*
X456839Y1564099D01*
X459003D01*
X460510Y1562592D01*
Y1560603D01*
X464798Y1552520D01*
X504249Y1532910D01*
X518955Y1527171D01*
X534583Y1524057D01*
X536604Y1522632D01*
X537657Y1520951D01*
X561559Y1457066D01*
X561570Y1457039D01*
X561589Y1456975D01*
X563791Y1449047D01*
Y1449046D01*
X565997Y1441103D01*
X586684Y1386541D01*
X617314Y1325371D01*
X627198Y1314325D01*
X678374Y1284078D01*
X683103Y1279349D01*
X686874Y1270256D01*
Y1259495D01*
G01X660693Y1259375D02*
Y1260706D01*
X659325Y1262074D01*
X610449Y1290963D01*
X580286Y1310102D01*
X500442Y1343633D01*
X499099Y1344976D01*
X497737Y1346828D01*
Y1409153D01*
X496441Y1413372D01*
X471483Y1450130D01*
X469171Y1455725D01*
Y1479915D01*
X467664Y1481422D01*
X465500D01*
X465000Y1481922D01*
Y1483426D01*
G01X659583Y1259375D02*
Y1260246D01*
X658639Y1261190D01*
X609869Y1290016D01*
X579770Y1309114D01*
X499811Y1342694D01*
X498254Y1344250D01*
X496627Y1346463D01*
Y1408986D01*
X495428Y1412886D01*
X475758Y1441856D01*
X475394Y1441926D01*
X474126Y1443792D01*
X474196Y1444157D01*
X473129Y1445728D01*
X472857Y1445780D01*
X471515Y1447756D01*
X471567Y1448029D01*
X470500Y1449600D01*
X468061Y1455504D01*
Y1479455D01*
X467204Y1480312D01*
X465500D01*
X465000Y1479812D01*
Y1478308D01*
G01X473662Y1479095D02*
Y1477591D01*
X474162Y1477091D01*
X476326D01*
X477833Y1475584D01*
Y1455748D01*
X479972Y1451254D01*
X509664Y1410515D01*
X509977Y1409557D01*
Y1346850D01*
X512131Y1343887D01*
X577056Y1316620D01*
X612311Y1294256D01*
X660116Y1266000D01*
X661837Y1264983D01*
X664433Y1262387D01*
Y1259712D01*
G01X663323D02*
Y1261927D01*
X661151Y1264099D01*
X659551Y1265044D01*
X611731Y1293309D01*
X576540Y1315632D01*
X511415Y1342983D01*
X508867Y1346489D01*
Y1409380D01*
X508663Y1410002D01*
X490112Y1435455D01*
X489697Y1435520D01*
X488367Y1437344D01*
X488432Y1437759D01*
X487284Y1439334D01*
X486804Y1439410D01*
X485570Y1441102D01*
X485646Y1441582D01*
X484527Y1443117D01*
X483912Y1443214D01*
X482792Y1444750D01*
X482889Y1445365D01*
X481770Y1446900D01*
X481155Y1446997D01*
X480035Y1448533D01*
X480132Y1449148D01*
X479013Y1450683D01*
X476723Y1455497D01*
Y1475124D01*
X475866Y1475981D01*
X474162D01*
X473662Y1475481D01*
Y1473977D01*
G01X465000Y1565315D02*
Y1566819D01*
X465501Y1567320D01*
X467204D01*
X468061Y1566463D01*
Y1564190D01*
X467700Y1563829D01*
Y1561771D01*
X468061Y1561410D01*
Y1559084D01*
X468608Y1557806D01*
X468417Y1557328D01*
X469225Y1555441D01*
X469704Y1555249D01*
Y1555247D01*
X470875Y1552512D01*
X505827Y1535140D01*
X519702Y1529725D01*
X535655Y1526546D01*
X538783Y1524342D01*
X540461Y1521520D01*
X552745Y1488710D01*
X552747D01*
X565028Y1455900D01*
X569450Y1439978D01*
X589622Y1386750D01*
X619575Y1326936D01*
X629115Y1316271D01*
X679894Y1286306D01*
X685642Y1280558D01*
X689504Y1271253D01*
Y1259495D01*
G01X465000Y1570434D02*
Y1568930D01*
X465500Y1568430D01*
X467664D01*
X469171Y1566923D01*
Y1559312D01*
X470724Y1555687D01*
Y1555685D01*
X471735Y1553325D01*
X506277Y1536156D01*
X520015Y1530795D01*
X536102Y1527589D01*
X539616Y1525113D01*
X541477Y1521985D01*
X553786Y1489101D01*
X553787Y1489098D01*
X566085Y1456244D01*
X570506Y1440324D01*
X590641Y1387197D01*
X620501Y1327566D01*
X629828Y1317140D01*
X680580Y1287191D01*
X686583Y1281187D01*
X690614Y1271475D01*
Y1259495D01*
G01X473662Y1560985D02*
Y1562488D01*
X474163Y1562989D01*
X475866D01*
X476723Y1562132D01*
Y1558480D01*
X477924Y1557008D01*
X477870Y1556473D01*
X479147Y1554907D01*
X479682Y1554853D01*
X480733Y1553564D01*
X482271Y1552336D01*
X482326Y1551844D01*
X483851Y1550626D01*
X484343Y1550681D01*
X486405Y1549035D01*
X506784Y1538903D01*
X521286Y1533244D01*
X537174Y1530078D01*
X541677Y1526903D01*
X544201Y1522662D01*
X556479Y1489860D01*
X556480D01*
X568757Y1457059D01*
X573179Y1441137D01*
X593356Y1387900D01*
X622834Y1329032D01*
X631723Y1319099D01*
X682618Y1289149D01*
X684979Y1287030D01*
X688707Y1283302D01*
X692404Y1274392D01*
X693244Y1271678D01*
Y1259495D01*
G01X473662Y1566103D02*
Y1564599D01*
X474162Y1564099D01*
X476326D01*
X477833Y1562592D01*
Y1558876D01*
X480542Y1555556D01*
Y1555555D01*
X481519Y1554358D01*
X487005Y1549978D01*
Y1549977D01*
X507234Y1539919D01*
X521599Y1534314D01*
X537621Y1531121D01*
X542510Y1527674D01*
X545209Y1523141D01*
X569814Y1457403D01*
X574235Y1441483D01*
X594375Y1388347D01*
X623760Y1329662D01*
X632435Y1319968D01*
X683277Y1290050D01*
X685743Y1287836D01*
X689648Y1283931D01*
X693450Y1274770D01*
X694354Y1271846D01*
Y1259495D01*
G01X482323Y1478308D02*
Y1479812D01*
X482823Y1480312D01*
X484527D01*
X485384Y1479455D01*
Y1455790D01*
X487719Y1449516D01*
X490603Y1446176D01*
X490557Y1445556D01*
X491800Y1444117D01*
X492421Y1444071D01*
X519875Y1412279D01*
X521107Y1408968D01*
Y1346437D01*
X522737Y1344248D01*
X523812Y1343173D01*
X572147Y1322873D01*
X613696Y1296517D01*
X662549Y1267642D01*
X667063Y1262445D01*
Y1259512D01*
G01X482323Y1483426D02*
Y1481922D01*
X482823Y1481422D01*
X484987D01*
X486494Y1479915D01*
Y1455990D01*
X488690Y1450090D01*
X520846Y1412853D01*
X522217Y1409168D01*
Y1346805D01*
X523586Y1344969D01*
X524443Y1344112D01*
X572663Y1323861D01*
X614276Y1297464D01*
X663269Y1268506D01*
X668173Y1262860D01*
Y1259512D01*
G01X482323Y1570434D02*
Y1568930D01*
X482823Y1568430D01*
X484987D01*
X486494Y1566923D01*
Y1559477D01*
X488537Y1554571D01*
X490551Y1552418D01*
X508815Y1543339D01*
X522662Y1537937D01*
X539135Y1534655D01*
X545547Y1530136D01*
X548647Y1524929D01*
X573255Y1459188D01*
X577676Y1443268D01*
X597815Y1390131D01*
X626746Y1332356D01*
X635584Y1322480D01*
X685906Y1292993D01*
X693327Y1285572D01*
X697163Y1276325D01*
X698094Y1273156D01*
Y1259495D01*
G01X696984D02*
Y1272996D01*
X696114Y1275954D01*
X692386Y1284943D01*
X685222Y1292107D01*
X634872Y1321609D01*
X625820Y1331726D01*
X596796Y1389684D01*
X576620Y1442922D01*
X572198Y1458844D01*
X547642Y1524447D01*
X544714Y1529365D01*
X538688Y1533612D01*
X522349Y1536867D01*
X508365Y1542323D01*
X489877Y1551513D01*
X487589Y1553959D01*
X486883Y1555654D01*
X486342Y1555877D01*
X485592Y1557681D01*
X485814Y1558221D01*
X485384Y1559254D01*
Y1561510D01*
X485100Y1561794D01*
Y1564006D01*
X485384Y1564290D01*
Y1566463D01*
X484527Y1567320D01*
X482824D01*
X482323Y1566819D01*
Y1565315D01*
G01X670800Y1259587D02*
Y1264094D01*
X664978Y1270799D01*
X615758Y1299888D01*
X574961Y1325767D01*
X537714Y1341511D01*
X533347Y1345878D01*
Y1409203D01*
X530942Y1415068D01*
X507770Y1438567D01*
X507147Y1438572D01*
X505812Y1439925D01*
X505817Y1440548D01*
X504483Y1441900D01*
X503861Y1441904D01*
X502526Y1443258D01*
X502531Y1443881D01*
X501197Y1445233D01*
X500575Y1445238D01*
X499240Y1446592D01*
X499245Y1447214D01*
X496300Y1450200D01*
X494046Y1453953D01*
Y1475124D01*
X493189Y1475981D01*
X491485D01*
X490985Y1475481D01*
Y1473977D01*
G01X671910Y1259587D02*
Y1264509D01*
X665698Y1271663D01*
X616338Y1300835D01*
X575478Y1326754D01*
X538346Y1342449D01*
X534457Y1346338D01*
Y1409422D01*
X531886Y1415692D01*
X497184Y1450886D01*
X495156Y1454261D01*
Y1475584D01*
X493649Y1477091D01*
X491485D01*
X490985Y1477591D01*
Y1479095D01*
G01X674543Y1259512D02*
Y1265087D01*
X670406Y1271276D01*
X668162Y1273398D01*
X619054Y1302424D01*
X578151Y1328502D01*
X547400Y1341500D01*
X545587Y1343313D01*
Y1409141D01*
X544103Y1412724D01*
X537427Y1419400D01*
X509383Y1445921D01*
X508761Y1445903D01*
X507379Y1447210D01*
X507362Y1447832D01*
X503800Y1451200D01*
X502707Y1456083D01*
Y1479455D01*
X501850Y1480312D01*
X500146D01*
X499646Y1479812D01*
Y1478308D01*
G01X675653Y1259512D02*
Y1265424D01*
X671260Y1271997D01*
X668835Y1274291D01*
X619635Y1303370D01*
X578670Y1329489D01*
X548032Y1342438D01*
X546697Y1343773D01*
Y1409362D01*
X545044Y1413353D01*
X538201Y1420196D01*
X504810Y1451774D01*
X503817Y1456206D01*
Y1479915D01*
X502310Y1481422D01*
X500146D01*
X499646Y1481922D01*
Y1483426D01*
G01Y1565315D02*
Y1566819D01*
X500147Y1567320D01*
X501850D01*
X502707Y1566463D01*
Y1564190D01*
X502400Y1563883D01*
Y1561717D01*
X502707Y1561410D01*
Y1559231D01*
X502942Y1558433D01*
X502944Y1558427D01*
X502662Y1557908D01*
X503211Y1556042D01*
X503732Y1555760D01*
X504047Y1554694D01*
X506291Y1552668D01*
X512727Y1548717D01*
X524577Y1544094D01*
X541717Y1540679D01*
X550526Y1534471D01*
X554890Y1527143D01*
X579778Y1460073D01*
X584158Y1444425D01*
X603934Y1392234D01*
X632091Y1336007D01*
X639453Y1327772D01*
X690256Y1297973D01*
X694318Y1293913D01*
X694481Y1293750D01*
Y1293748D01*
X699667Y1288562D01*
X702309Y1282606D01*
X704465Y1275509D01*
Y1259495D01*
G01X490985Y1560985D02*
Y1562488D01*
X491486Y1562989D01*
X493189D01*
X494046Y1562132D01*
Y1559555D01*
X495362Y1558185D01*
X495349Y1557573D01*
X496677Y1556192D01*
X497289Y1556180D01*
X498605Y1554810D01*
X498595Y1554337D01*
X500059Y1552814D01*
X500532Y1552805D01*
X500531D01*
X503237Y1549989D01*
X510430Y1545576D01*
X516974Y1543022D01*
X516975D01*
X523517Y1540469D01*
X540202Y1537146D01*
X547602Y1531930D01*
X551059Y1526124D01*
X575776Y1460014D01*
X580535Y1443205D01*
X600244Y1391201D01*
X628958Y1333860D01*
X637042Y1324827D01*
X688157Y1294744D01*
X696324Y1286575D01*
X699063Y1279968D01*
X700724Y1274321D01*
Y1259495D01*
G01X499646Y1570434D02*
Y1568930D01*
X500146Y1568430D01*
X502310D01*
X503817Y1566923D01*
Y1559393D01*
X505024Y1555309D01*
X506960Y1553561D01*
X513223Y1549715D01*
X524890Y1545164D01*
X542164Y1541722D01*
X551359Y1535242D01*
X555896Y1527624D01*
X580835Y1460416D01*
X585214Y1444772D01*
X604953Y1392681D01*
X633018Y1336637D01*
X640165Y1328642D01*
X690940Y1298859D01*
X695591Y1294210D01*
Y1294208D01*
X700598Y1289201D01*
X703352Y1282994D01*
X705575Y1275674D01*
Y1259495D01*
G01X490985Y1566103D02*
Y1564599D01*
X491485Y1564099D01*
X493649D01*
X495156Y1562592D01*
Y1560002D01*
X503939Y1550861D01*
X510926Y1546574D01*
X517378Y1544056D01*
X517379D01*
X523830Y1541539D01*
X540649Y1538189D01*
X548435Y1532701D01*
X552064Y1526606D01*
X576832Y1460360D01*
X581590Y1443554D01*
X601263Y1391648D01*
X629884Y1334490D01*
X637754Y1325696D01*
X688842Y1295629D01*
X697265Y1287204D01*
X700112Y1280338D01*
X701834Y1274481D01*
Y1259495D01*
G01X679394Y1259712D02*
Y1266595D01*
X672961Y1276222D01*
X622209Y1306217D01*
X606331Y1323967D01*
X569163Y1389093D01*
X566894Y1390410D01*
X562587D01*
X558937Y1394060D01*
Y1409330D01*
X557070Y1413501D01*
X513587Y1452354D01*
X512478Y1454255D01*
Y1475584D01*
X510971Y1477091D01*
X508807D01*
X508307Y1477591D01*
Y1479095D01*
G01X678284Y1259712D02*
Y1266258D01*
X672178Y1275394D01*
X621496Y1305349D01*
X605424Y1323314D01*
X568347Y1388283D01*
X566595Y1389300D01*
X562127D01*
X557827Y1393600D01*
Y1409092D01*
X556153Y1412831D01*
X526455Y1439366D01*
X525834Y1439331D01*
X524416Y1440598D01*
X524381Y1441220D01*
X522965Y1442485D01*
X522344Y1442450D01*
X520926Y1443717D01*
X520891Y1444339D01*
X519475Y1445604D01*
X518854Y1445569D01*
X517436Y1446836D01*
X517401Y1447457D01*
X512716Y1451643D01*
X511368Y1453954D01*
Y1475124D01*
X510511Y1475981D01*
X508807D01*
X508307Y1475481D01*
Y1473977D01*
G01X683134Y1259495D02*
Y1267774D01*
X675319Y1279461D01*
X674841Y1279939D01*
X623843Y1310034D01*
X612842Y1322329D01*
X581063Y1385788D01*
X571780Y1410721D01*
X527224Y1447942D01*
X523137Y1451555D01*
X521140Y1456659D01*
Y1479915D01*
X519633Y1481422D01*
X517469D01*
X516969Y1481922D01*
Y1483426D01*
G01X682024Y1259495D02*
Y1267437D01*
X674457Y1278753D01*
X674156Y1279054D01*
X623130Y1309165D01*
X611916Y1321699D01*
X580043Y1385344D01*
X570842Y1410058D01*
X530092Y1444099D01*
X529472Y1444044D01*
X528013Y1445263D01*
X527958Y1445882D01*
X526500Y1447100D01*
X522200Y1450900D01*
X520030Y1456449D01*
Y1479455D01*
X519173Y1480312D01*
X517469D01*
X516969Y1479812D01*
Y1478308D01*
G01Y1570434D02*
Y1568930D01*
X517469Y1568430D01*
X519633D01*
X521140Y1566923D01*
Y1556131D01*
X523078Y1554193D01*
X524677Y1553338D01*
X529200Y1552436D01*
X530515D01*
X534554Y1551631D01*
X534555Y1551632D01*
X543801Y1549790D01*
X557216Y1540342D01*
X562424Y1531661D01*
X588508Y1461368D01*
X592998Y1445715D01*
X611338Y1397325D01*
X639501Y1341085D01*
X643974Y1336078D01*
X699324Y1302582D01*
X707216Y1293382D01*
X710583Y1285255D01*
X713055Y1277111D01*
Y1259612D01*
G01X516969Y1565315D02*
Y1566819D01*
X517470Y1567320D01*
X519173D01*
X520030Y1566463D01*
Y1555671D01*
X522409Y1553292D01*
X524298Y1552281D01*
X529090Y1551326D01*
X530405D01*
X534338Y1550542D01*
X534545Y1550230D01*
X536753Y1549790D01*
X537065Y1549999D01*
X538928Y1549628D01*
X539244Y1549153D01*
X541181Y1548768D01*
X541655Y1549085D01*
X543354Y1548747D01*
X556384Y1539569D01*
X561419Y1531178D01*
X587452Y1461021D01*
X591943Y1445364D01*
X610319Y1396878D01*
X638574Y1340455D01*
X643257Y1335214D01*
X698597Y1301724D01*
X706257Y1292793D01*
X709536Y1284880D01*
X711945Y1276946D01*
Y1259612D01*
G01X508307Y1566103D02*
Y1564599D01*
X508807Y1564099D01*
X510971D01*
X512478Y1562592D01*
Y1559093D01*
X520754Y1550817D01*
X525440Y1548987D01*
X543485Y1545393D01*
X554104Y1537913D01*
Y1537914D01*
X554293Y1537780D01*
X559060Y1529906D01*
X584821Y1460490D01*
X589331Y1444775D01*
X608504Y1394189D01*
X636269Y1338743D01*
X640945Y1333512D01*
X696547Y1299867D01*
X704071Y1291089D01*
X706981Y1284070D01*
X709315Y1276384D01*
Y1259495D01*
G01X508307Y1560985D02*
Y1562488D01*
X508808Y1562989D01*
X510511D01*
X511368Y1562132D01*
Y1558633D01*
X512711Y1557290D01*
Y1556790D01*
X514178Y1555323D01*
X514678D01*
X516021Y1553980D01*
Y1553358D01*
X517365Y1552013D01*
X517987D01*
X520133Y1549867D01*
X525127Y1547917D01*
X543038Y1544350D01*
X553464Y1537006D01*
X558056Y1529421D01*
X583765Y1460143D01*
X588276Y1444424D01*
X607485Y1393742D01*
X635342Y1338113D01*
X640228Y1332648D01*
X695820Y1299009D01*
X703113Y1290501D01*
X705934Y1283695D01*
X708205Y1276219D01*
Y1259495D01*
G01X670066Y390995D02*
X668921Y392140D01*
X661386D01*
X633886Y405889D01*
X610758Y424258D01*
X601139Y430639D01*
X598558Y432970D01*
X592107Y435594D01*
X590243Y437502D01*
X579217Y471034D01*
X572827Y497475D01*
X567379Y590306D01*
X570035Y628237D01*
X574978Y653821D01*
X689504Y1063406D01*
Y1068999D01*
G01X670066Y394395D02*
X668921Y393250D01*
X661649D01*
X657076Y395536D01*
X656875Y396140D01*
X655130Y397013D01*
X654526Y396812D01*
X652782Y397683D01*
X652581Y398287D01*
X650836Y399160D01*
X650232Y398959D01*
X648488Y399830D01*
X648287Y400434D01*
X646542Y401307D01*
X645938Y401106D01*
X644194Y401977D01*
X643993Y402581D01*
X642248Y403454D01*
X641644Y403253D01*
X639900Y404124D01*
X639699Y404728D01*
X637954Y405601D01*
X637350Y405400D01*
X634486Y406831D01*
X631649Y409084D01*
X631576Y409717D01*
X630048Y410930D01*
X629416Y410858D01*
X627890Y412070D01*
X627817Y412703D01*
X626289Y413916D01*
X625657Y413844D01*
X624130Y415056D01*
X624058Y415688D01*
X622530Y416902D01*
X621898Y416830D01*
X611411Y425157D01*
X601822Y431518D01*
X599157Y433925D01*
X592740Y436535D01*
X591218Y438094D01*
X580286Y471339D01*
X573930Y497639D01*
X568492Y590300D01*
X571138Y628092D01*
X576060Y653566D01*
X690614Y1063253D01*
Y1068999D01*
G01X662766Y398082D02*
Y398083D01*
X661622Y399227D01*
X659796D01*
X633158Y414426D01*
X588324Y461192D01*
X582929Y471867D01*
X577012Y498317D01*
X571399Y591264D01*
X573643Y625484D01*
X578347Y651241D01*
X693244Y1062754D01*
Y1069176D01*
G01X670066Y405168D02*
X668921Y406313D01*
X661539D01*
X633194Y420858D01*
X590307Y465777D01*
X586392Y473934D01*
X581913Y498436D01*
X575598Y591895D01*
X577802Y625162D01*
X582237Y650804D01*
X696984Y1062098D01*
Y1069000D01*
G01X670066Y408568D02*
X668921Y407423D01*
X661808D01*
X657597Y409584D01*
Y409583D01*
X657403Y410189D01*
X655667Y411081D01*
X655061Y410886D01*
X653327Y411776D01*
X653132Y412382D01*
X651396Y413273D01*
X650790Y413078D01*
X649056Y413968D01*
X648861Y414574D01*
X647125Y415465D01*
X646519Y415270D01*
X644785Y416160D01*
X644590Y416765D01*
X642854Y417657D01*
X642248Y417462D01*
X640513Y418352D01*
X640319Y418957D01*
X638582Y419848D01*
X637977Y419653D01*
X633868Y421761D01*
X632026Y423690D01*
X632041Y424327D01*
X630693Y425738D01*
X630057Y425753D01*
X628711Y427163D01*
X628726Y427799D01*
X627378Y429210D01*
X626742Y429225D01*
X625396Y430635D01*
X625411Y431271D01*
X624063Y432682D01*
X623427Y432697D01*
X591232Y466417D01*
X587458Y474280D01*
X583017Y498574D01*
X576711Y591896D01*
X578906Y625030D01*
X583322Y650559D01*
X698094Y1061946D01*
Y1069000D01*
G01X694354Y1069176D02*
Y1062601D01*
X579430Y650992D01*
X574747Y625347D01*
X572512Y591261D01*
X578115Y498473D01*
X583983Y472245D01*
X589240Y461841D01*
X621308Y428391D01*
X621944Y428378D01*
X623294Y426969D01*
X623281Y426333D01*
X624630Y424926D01*
X625266Y424913D01*
X626616Y423504D01*
X626603Y422868D01*
X627952Y421461D01*
X628589Y421448D01*
X629939Y420039D01*
X629926Y419403D01*
X633849Y415311D01*
X636866Y413589D01*
X637480Y413757D01*
X639174Y412790D01*
X639342Y412176D01*
X643413Y409853D01*
X644027Y410021D01*
X645722Y409054D01*
X645890Y408440D01*
X647583Y407474D01*
X648196Y407642D01*
X649891Y406675D01*
X650059Y406061D01*
X651752Y405095D01*
X652365Y405263D01*
X654060Y404296D01*
X654228Y403682D01*
X655921Y402716D01*
X656535Y402884D01*
X658230Y401917D01*
X658398Y401303D01*
X660091Y400337D01*
X661622D01*
X662766Y401481D01*
Y401482D01*
G01X700724Y1069177D02*
Y1061136D01*
X586024Y650325D01*
X581688Y625071D01*
X581166Y616890D01*
X581165Y616889D01*
X581166D01*
X579609Y592455D01*
X585921Y497447D01*
X588597Y483320D01*
X591533Y479749D01*
X599548Y475434D01*
X604711Y469148D01*
X617158Y443630D01*
X634388Y426947D01*
X659462Y413400D01*
X661621D01*
X662766Y412255D01*
G01X701834Y1069177D02*
Y1060983D01*
X587109Y650081D01*
X582792Y624941D01*
X580722Y592456D01*
X587025Y497588D01*
X589635Y483806D01*
X592252Y480623D01*
X600267Y476308D01*
X605652Y469752D01*
X618071Y444292D01*
X622511Y439993D01*
X623147Y440004D01*
X624549Y438646D01*
X624559Y438010D01*
X625960Y436654D01*
X626596Y436665D01*
X627998Y435307D01*
X628008Y434671D01*
X629409Y433315D01*
X630045Y433325D01*
X631447Y431967D01*
X631457Y431331D01*
X635051Y427852D01*
X638627Y425920D01*
X639236Y426102D01*
X640953Y425174D01*
X641135Y424564D01*
X642850Y423638D01*
X643460Y423820D01*
X645177Y422892D01*
X645359Y422282D01*
X647074Y421356D01*
X647683Y421538D01*
X649400Y420610D01*
X649582Y420000D01*
X651297Y419074D01*
X651906Y419256D01*
X653623Y418328D01*
X653805Y417718D01*
X655520Y416792D01*
X656129Y416974D01*
X657846Y416046D01*
X658028Y415437D01*
X659743Y414510D01*
X661621D01*
X662766Y415655D01*
G01X670066Y419341D02*
X668921Y420486D01*
X660195D01*
X631547Y435738D01*
X621193Y445743D01*
X617895Y451562D01*
X611014Y481096D01*
X608399Y484085D01*
X601440Y486769D01*
X589910Y509734D01*
X583452Y592559D01*
X585503Y625001D01*
X589540Y648527D01*
X704465Y1060437D01*
Y1069000D01*
G01X670066Y422741D02*
X668921Y421596D01*
X660473D01*
X658752Y422512D01*
X658566Y423121D01*
X656844Y424038D01*
X656236Y423852D01*
X654515Y424768D01*
X654329Y425377D01*
X652607Y426294D01*
X651999Y426108D01*
X650278Y427024D01*
X650092Y427633D01*
X648370Y428550D01*
X647761Y428364D01*
X646040Y429280D01*
X645854Y429889D01*
X644132Y430806D01*
X643524Y430620D01*
X641803Y431536D01*
X641617Y432144D01*
X639895Y433062D01*
X639286Y432876D01*
X637565Y433792D01*
X637379Y434401D01*
X635657Y435318D01*
X635048Y435132D01*
X632206Y436645D01*
X630804Y438000D01*
X630793Y438636D01*
X629390Y439992D01*
X628754Y439981D01*
X627352Y441336D01*
X627341Y441972D01*
X625938Y443328D01*
X625302Y443317D01*
X622080Y446430D01*
X618940Y451970D01*
X612033Y481619D01*
X609055Y485023D01*
X602240Y487651D01*
X591000Y510037D01*
X584565Y592567D01*
X586608Y624872D01*
X590625Y648283D01*
X705575Y1060285D01*
Y1069000D01*
G01X662766Y426428D02*
X661621Y427573D01*
X660033D01*
X624618Y447664D01*
X624197Y448073D01*
X621438Y452977D01*
X613122Y489303D01*
X599886Y520124D01*
Y536942D01*
X595223Y549858D01*
X587368Y593180D01*
X589288Y624190D01*
X593449Y648314D01*
X708205Y1059776D01*
Y1069176D01*
G01X662766Y429828D02*
X661621Y428683D01*
X660327D01*
X658240Y429867D01*
X658071Y430480D01*
X656373Y431443D01*
X655760Y431274D01*
X654064Y432236D01*
X653895Y432849D01*
X652198Y433812D01*
X651585Y433643D01*
X649048Y435082D01*
X648879Y435695D01*
X647182Y436658D01*
X646569Y436489D01*
X644873Y437451D01*
X644704Y438064D01*
X643007Y439027D01*
X642393Y438858D01*
X625290Y448560D01*
X625086Y448758D01*
X622485Y453382D01*
X614182Y489649D01*
X610244Y498819D01*
X610480Y499410D01*
X609711Y501203D01*
X609119Y501439D01*
X608350Y503230D01*
X608586Y503821D01*
X607817Y505614D01*
X607225Y505850D01*
X606456Y507641D01*
X606692Y508232D01*
X605922Y510025D01*
X605330Y510261D01*
X604561Y512052D01*
X604797Y512643D01*
X604028Y514436D01*
X603436Y514672D01*
X600996Y520353D01*
Y537137D01*
X596299Y550147D01*
X588485Y593246D01*
X590393Y624061D01*
X594534Y648070D01*
X709315Y1059624D01*
Y1069176D01*
G01X670066Y433515D02*
X668921Y434660D01*
X660974D01*
X644428Y441396D01*
X632239Y449519D01*
X631588Y449790D01*
X629810D01*
X627352Y450923D01*
X626050Y452451D01*
X624808Y455114D01*
X610665Y539070D01*
X603037Y553504D01*
X595607Y570047D01*
X591245Y594584D01*
X593051Y623640D01*
X597342Y647567D01*
X711945Y1058368D01*
Y1069000D01*
G01X670066Y436915D02*
X668921Y435770D01*
X665992D01*
X665542Y436220D01*
X663592D01*
X663142Y435770D01*
X661192D01*
X659387Y436505D01*
X659139Y437092D01*
X657332Y437828D01*
X656746Y437581D01*
X654940Y438316D01*
X654693Y438903D01*
X652886Y439639D01*
X652300Y439392D01*
X650494Y440127D01*
X650247Y440714D01*
X648440Y441449D01*
X647854Y441202D01*
X644951Y442383D01*
X640755Y445179D01*
X640630Y445803D01*
X639006Y446885D01*
X638382Y446760D01*
X636760Y447841D01*
X636635Y448465D01*
X635011Y449547D01*
X634387Y449422D01*
X632765Y450503D01*
X631810Y450900D01*
X630055D01*
X628039Y451830D01*
X626993Y453057D01*
X625878Y455447D01*
X622980Y472653D01*
X623349Y473172D01*
X623025Y475096D01*
X622505Y475465D01*
X622182Y477387D01*
X622551Y477906D01*
X622227Y479830D01*
X621708Y480199D01*
X611730Y539431D01*
X604036Y553992D01*
X596677Y570377D01*
X592362Y594648D01*
X594155Y623507D01*
X598426Y647319D01*
X713055Y1058216D01*
Y1069000D01*
G01X715685Y1069177D02*
Y1057515D01*
X600907Y646036D01*
X597022Y623365D01*
X595193Y595311D01*
X599629Y571121D01*
X606665Y555079D01*
X614499Y540921D01*
X620259Y505391D01*
X626747Y476186D01*
X634052Y460481D01*
X636641Y456762D01*
X639046Y451593D01*
X642197Y448587D01*
X658923Y441747D01*
X661621D01*
X662766Y440602D01*
G01X670066Y469381D02*
X668921Y470526D01*
X662036D01*
X653985Y473033D01*
X631876Y494002D01*
X625489Y503906D01*
X624101Y507516D01*
X618516Y541787D01*
X611806Y553631D01*
X603729Y571525D01*
X599083Y596701D01*
X600799Y622860D01*
X604751Y645427D01*
X719425Y1056771D01*
Y1069000D01*
G01X716795Y1069177D02*
Y1057363D01*
X601992Y645792D01*
X598126Y623235D01*
X596310Y595376D01*
X600698Y571449D01*
X607661Y555572D01*
X615564Y541289D01*
X621350Y505600D01*
X623545Y495719D01*
X624082Y495378D01*
X624505Y493473D01*
X624164Y492936D01*
X624586Y491033D01*
X625123Y490692D01*
X625546Y488787D01*
X625205Y488250D01*
X625627Y486347D01*
X626164Y486006D01*
X626587Y484101D01*
X626246Y483564D01*
X626668Y481661D01*
X627206Y481320D01*
X627629Y479415D01*
X627287Y478878D01*
X627805Y476545D01*
X628629Y474772D01*
X629227Y474554D01*
X630050Y472784D01*
X629832Y472187D01*
X630654Y470419D01*
X631252Y470201D01*
X632075Y468432D01*
X631857Y467834D01*
X635019Y461037D01*
X637608Y457318D01*
X639965Y452252D01*
X642812Y449536D01*
X650256Y446492D01*
X650842Y446738D01*
X652648Y446000D01*
X652895Y445413D01*
X654699Y444675D01*
X655286Y444921D01*
X657091Y444183D01*
X657338Y443595D01*
X659142Y442857D01*
X661621D01*
X662766Y444002D01*
G01X670066Y472781D02*
X668921Y471636D01*
X662205D01*
X654562Y474016D01*
X649228Y479075D01*
X649211Y479711D01*
X647795Y481054D01*
X647159Y481038D01*
X645745Y482379D01*
X645728Y483016D01*
X644312Y484358D01*
X643676Y484342D01*
X642262Y485683D01*
X642245Y486320D01*
X640829Y487662D01*
X640193Y487645D01*
X638779Y488986D01*
X638762Y489623D01*
X637346Y490965D01*
X636710Y490949D01*
X632737Y494716D01*
X631681Y496354D01*
X631815Y496976D01*
X630757Y498616D01*
X630135Y498751D01*
X626485Y504412D01*
X625179Y507808D01*
X619580Y542161D01*
X618342Y544347D01*
X618511Y544960D01*
X617549Y546658D01*
X616936Y546828D01*
X615975Y548524D01*
X616145Y549137D01*
X615183Y550835D01*
X614570Y551005D01*
X612797Y554134D01*
X611683Y556602D01*
X611908Y557198D01*
X611106Y558976D01*
X610510Y559201D01*
X604797Y571859D01*
X600200Y596766D01*
X601903Y622728D01*
X605836Y645181D01*
X720535Y1056619D01*
Y1069000D01*
G01X746716Y1260312D02*
Y1262503D01*
X745406Y1266053D01*
X725159Y1289753D01*
X724188Y1291066D01*
X724126Y1291189D01*
X723996Y1291297D01*
X723994Y1291299D01*
X711876Y1301184D01*
X646397Y1341460D01*
X644474Y1343672D01*
X644414Y1343708D01*
X643995Y1344191D01*
X616253Y1399485D01*
X598330Y1446774D01*
Y1516428D01*
X604693Y1531796D01*
X613111Y1540214D01*
X632947Y1553468D01*
X633738Y1554946D01*
Y1593300D01*
X632231Y1594807D01*
X630067D01*
X629567Y1595307D01*
Y1596811D01*
G01X745606Y1260312D02*
Y1262304D01*
X744433Y1265483D01*
X724289Y1289061D01*
X723239Y1290481D01*
Y1290480D01*
X723238Y1290482D01*
X711231Y1300276D01*
X645670Y1340603D01*
X643756Y1342806D01*
X643693Y1342843D01*
X643065Y1343569D01*
X615235Y1399038D01*
X597220Y1446570D01*
Y1516649D01*
X603752Y1532425D01*
X612403Y1541076D01*
X618187Y1544941D01*
X618188D01*
X618284Y1545426D01*
X619907Y1546511D01*
X620391Y1546414D01*
X622012Y1547497D01*
X622013D01*
X622109Y1547982D01*
X623732Y1549067D01*
X624217Y1548970D01*
X625838Y1550053D01*
X625934Y1550539D01*
X627557Y1551623D01*
X628042Y1551526D01*
X632099Y1554237D01*
X632628Y1555225D01*
Y1592840D01*
X631771Y1593697D01*
X630067D01*
X629567Y1593197D01*
Y1591693D01*
G01X638228Y1596024D02*
Y1597528D01*
X638728Y1598028D01*
X640432D01*
X641289Y1597171D01*
Y1557359D01*
X639946Y1556016D01*
X639324D01*
X637980Y1554671D01*
Y1554049D01*
X636497Y1552565D01*
X614551Y1537906D01*
X606940Y1530295D01*
X600980Y1515901D01*
Y1447399D01*
X618782Y1400429D01*
X646265Y1345652D01*
X648131Y1343505D01*
X714497Y1302684D01*
X725854Y1293200D01*
X728757Y1290635D01*
X747149Y1269437D01*
X749347Y1263551D01*
Y1260312D01*
G01X638228Y1601142D02*
Y1599638D01*
X638728Y1599138D01*
X640892D01*
X642399Y1597631D01*
Y1556899D01*
X637205Y1551703D01*
X615259Y1537044D01*
X607881Y1529666D01*
X602090Y1515680D01*
Y1447603D01*
X619800Y1400876D01*
X647195Y1346275D01*
X648858Y1344362D01*
X715147Y1303588D01*
X726578Y1294043D01*
X729548Y1291419D01*
X748119Y1270013D01*
X750457Y1263752D01*
Y1260312D01*
G01X723164Y1069976D02*
Y1055410D01*
X612225Y639472D01*
X608518Y619118D01*
X606116Y579966D01*
X606115D01*
X606105Y579791D01*
X607824Y573178D01*
X616831Y561559D01*
X622132Y543036D01*
X628317Y507433D01*
X629059Y505743D01*
X637308Y495401D01*
X653887Y480353D01*
X660757Y477613D01*
X661621D01*
X662766Y476468D01*
G01X724274Y1069976D02*
Y1055264D01*
X613310Y639229D01*
X609622Y618984D01*
X607224Y579899D01*
X608841Y573678D01*
X617840Y562071D01*
X618588Y559455D01*
X619146Y559146D01*
X619682Y557270D01*
X619373Y556714D01*
X623216Y543285D01*
X629388Y507756D01*
X630018Y506322D01*
X632133Y503670D01*
X632766Y503599D01*
X633983Y502073D01*
X633912Y501441D01*
X635127Y499917D01*
X635760Y499846D01*
X636977Y498320D01*
X636905Y497688D01*
X638121Y496164D01*
X640265Y494218D01*
X640901Y494248D01*
X642346Y492937D01*
X642377Y492301D01*
X643820Y490991D01*
X644456Y491021D01*
X645901Y489710D01*
X645932Y489074D01*
X647375Y487764D01*
X648011Y487794D01*
X649456Y486483D01*
X649487Y485847D01*
X650930Y484537D01*
X651566Y484567D01*
X653011Y483256D01*
X653042Y482620D01*
X654485Y481310D01*
X656296Y480588D01*
X656880Y480839D01*
X658693Y480117D01*
X658944Y479531D01*
X660971Y478723D01*
X661621D01*
X662766Y479868D01*
G01Y490641D02*
X661621Y491786D01*
X659877D01*
X657753Y493910D01*
X655871Y498454D01*
Y504855D01*
X654106Y509079D01*
X654105Y509081D01*
X651993Y514137D01*
X646933Y521623D01*
X644852Y526043D01*
X644851Y526045D01*
X641843Y532434D01*
X635606Y552957D01*
X635607D01*
X635009Y554923D01*
X626383Y562765D01*
X622522Y566576D01*
X614827Y576902D01*
X613764Y580951D01*
X613775Y581130D01*
X613776D01*
X616174Y618273D01*
X619225Y635490D01*
X730644Y1054274D01*
Y1069976D01*
G01X726905D02*
Y1054845D01*
X615714Y637579D01*
X612502Y619759D01*
X609945Y580339D01*
X611240Y575398D01*
X621096Y562168D01*
X625113Y548303D01*
X631689Y510215D01*
X632359Y508737D01*
X640919Y497905D01*
X643699Y495431D01*
X661099Y484699D01*
X668921D01*
X670066Y483554D01*
G01X731754Y1069976D02*
Y1054128D01*
X620310Y635250D01*
X617278Y618140D01*
X614884Y581059D01*
X615847Y577393D01*
X623362Y567307D01*
X627147Y563571D01*
X635984Y555538D01*
X636536Y553720D01*
X637098Y553420D01*
X637665Y551554D01*
X637365Y550992D01*
X637932Y549127D01*
X637930D01*
X638493Y548828D01*
X639060Y546961D01*
X638760Y546399D01*
X639327Y544534D01*
X639326D01*
X639889Y544234D01*
X640455Y542368D01*
X640156Y541806D01*
X640722Y539941D01*
X641285Y539641D01*
X641852Y537774D01*
X641552Y537213D01*
X642882Y532834D01*
X643811Y530860D01*
X644410Y530645D01*
X645241Y528880D01*
X645026Y528281D01*
X645856Y526517D01*
X646455Y526302D01*
X647287Y524536D01*
X647072Y523938D01*
X647902Y522174D01*
X650287Y518645D01*
X650912Y518524D01*
X652005Y516907D01*
X651884Y516282D01*
X652975Y514667D01*
X655130Y509508D01*
X655720Y509266D01*
X656472Y507465D01*
X656230Y506877D01*
X656981Y505078D01*
Y498675D01*
X658694Y494539D01*
X660337Y492896D01*
X661621D01*
X662766Y494041D01*
G01X728015Y1069976D02*
Y1054699D01*
X616799Y637337D01*
X613606Y619624D01*
X611065Y580447D01*
X612260Y575889D01*
X622107Y562670D01*
X626197Y548553D01*
X630951Y521018D01*
X631472Y520651D01*
X631804Y518728D01*
X631437Y518208D01*
X631768Y516287D01*
X631767D01*
X632288Y515920D01*
X632620Y513997D01*
X632253Y513477D01*
X632759Y510544D01*
X633314Y509319D01*
X634523Y507790D01*
X635155Y507716D01*
X636365Y506185D01*
X636291Y505553D01*
X637500Y504024D01*
X638132Y503950D01*
X639342Y502419D01*
X639268Y501787D01*
Y501786D01*
X641730Y498670D01*
X644365Y496326D01*
X647577Y494345D01*
X648196Y494491D01*
X649857Y493467D01*
X650004Y492847D01*
X651663Y491824D01*
X652282Y491971D01*
X653943Y490946D01*
X654090Y490327D01*
X655749Y489304D01*
X656368Y489451D01*
X658029Y488426D01*
X658175Y487807D01*
X661414Y485809D01*
X663364D01*
X663814Y486259D01*
X665764D01*
X666214Y485809D01*
X668921D01*
X670066Y486954D01*
G01X735495Y1069976D02*
Y1053564D01*
X623983Y634420D01*
X621017Y617686D01*
X618677Y581436D01*
X619339Y579054D01*
X623069Y574018D01*
X623698Y573924D01*
X624860Y572356D01*
X624766Y571727D01*
X625926Y570160D01*
X630204Y565879D01*
X631825Y564796D01*
X632449Y564920D01*
X634071Y563836D01*
X634195Y563212D01*
X635816Y562129D01*
X636440Y562253D01*
X638062Y561169D01*
X638186Y560545D01*
X641517Y558319D01*
X645179Y554658D01*
X646049Y552553D01*
Y537412D01*
X647559Y533766D01*
X648148Y533523D01*
X648894Y531720D01*
X648650Y531132D01*
X649396Y529331D01*
X649985Y529088D01*
X650731Y527285D01*
X650487Y526697D01*
X651233Y524896D01*
X652633Y523191D01*
X653266Y523128D01*
X654505Y521620D01*
X654442Y520987D01*
X655679Y519480D01*
X656312Y519418D01*
X657550Y517910D01*
X657488Y517277D01*
X658725Y515770D01*
X663988D01*
X664438Y516220D01*
X666388D01*
X666838Y515770D01*
X668921D01*
X670066Y516915D01*
G01X734385Y1069976D02*
Y1053710D01*
X622898Y634660D01*
X619913Y617819D01*
X617557Y581320D01*
X618324Y578558D01*
X625083Y569433D01*
X629496Y565017D01*
X640809Y557457D01*
X644237Y554029D01*
X644939Y552332D01*
Y537191D01*
X646709Y532915D01*
X646710Y532914D01*
X650270Y524319D01*
X658200Y514660D01*
X668921D01*
X670066Y513515D01*
G01X646890Y1591693D02*
Y1593197D01*
X647390Y1593697D01*
X649094D01*
X649951Y1592840D01*
Y1555153D01*
X649284Y1554152D01*
X646975Y1552644D01*
X646366Y1552771D01*
X644775Y1551731D01*
X644647Y1551122D01*
X643057Y1550083D01*
X642625Y1550174D01*
X640819Y1548994D01*
X640729Y1548562D01*
X639139Y1547523D01*
X638651Y1547626D01*
X636913Y1546490D01*
X636811Y1546002D01*
X632870Y1543427D01*
X616952Y1534988D01*
X610128Y1528164D01*
X604740Y1515151D01*
Y1452116D01*
X607440Y1443578D01*
X616130Y1434895D01*
X645101Y1413976D01*
X645793Y1413284D01*
Y1368407D01*
X648000Y1366200D01*
X655329D01*
X658033Y1363496D01*
Y1345672D01*
X662618Y1340504D01*
X710855Y1311463D01*
X738388Y1287150D01*
X750652Y1271338D01*
X753087Y1264230D01*
Y1260312D01*
G01X672874Y1596024D02*
Y1597528D01*
X673374Y1598028D01*
X675078D01*
X675935Y1597171D01*
Y1557017D01*
X674592Y1555674D01*
X673970D01*
X672625Y1554329D01*
Y1553707D01*
X671217Y1552299D01*
X650409Y1538402D01*
X648643Y1537362D01*
X636306Y1530997D01*
X623557Y1525637D01*
X619699Y1521779D01*
X616190Y1513314D01*
Y1454356D01*
X618499Y1448477D01*
X623440Y1443540D01*
X637804Y1433178D01*
X671206Y1418491D01*
X676303Y1416094D01*
Y1416095D01*
X681399Y1413699D01*
X682513Y1412585D01*
Y1392787D01*
X685300Y1390000D01*
X692753D01*
X694753Y1388000D01*
Y1345218D01*
X729090Y1313620D01*
X748124Y1294388D01*
X754798Y1286682D01*
X760544Y1278456D01*
X764307Y1266500D01*
Y1260312D01*
G01X664213Y1591693D02*
Y1593197D01*
X664713Y1593697D01*
X666417D01*
X667274Y1592840D01*
Y1555096D01*
X666652Y1553778D01*
X664946Y1552638D01*
X664336Y1552760D01*
X662755Y1551703D01*
X662633Y1551093D01*
X661054Y1550038D01*
X660630Y1550122D01*
X658826Y1548916D01*
X658741Y1548493D01*
X657162Y1547438D01*
X656616Y1547546D01*
X654958Y1546438D01*
X654849Y1545892D01*
X651866Y1543899D01*
X631896Y1533225D01*
X621421Y1528820D01*
X616510Y1523909D01*
X612331Y1513824D01*
X612261Y1454203D01*
X614825Y1446832D01*
X621020Y1440642D01*
X635794Y1429981D01*
X635793Y1429980D01*
X635889Y1429911D01*
X665747Y1416781D01*
X670273Y1412256D01*
Y1381057D01*
X673840Y1377490D01*
X681240D01*
X682513Y1376217D01*
Y1344623D01*
X702500Y1328300D01*
X721025Y1315930D01*
X726460Y1310929D01*
X745363Y1291832D01*
X748817Y1287843D01*
X748819Y1287841D01*
X751115Y1285190D01*
X757158Y1276538D01*
X760567Y1265704D01*
Y1260312D01*
G01X664213Y1596811D02*
Y1595307D01*
X664713Y1594807D01*
X666877D01*
X668384Y1593300D01*
Y1554847D01*
X667525Y1553026D01*
X652438Y1542945D01*
X632374Y1532221D01*
X622052Y1527881D01*
X617451Y1523280D01*
X613441Y1513603D01*
X613372Y1454390D01*
X615790Y1447437D01*
X621742Y1441490D01*
X636444Y1430881D01*
X666385Y1417714D01*
X671383Y1412716D01*
Y1381517D01*
X674300Y1378600D01*
X681700D01*
X683623Y1376677D01*
Y1345150D01*
X703161Y1329194D01*
X721714Y1316806D01*
X727231Y1311728D01*
X746178Y1292587D01*
X749630Y1288600D01*
X749632Y1288598D01*
X751992Y1285873D01*
X758166Y1277034D01*
X761677Y1265875D01*
Y1260312D01*
G01X655551Y1601142D02*
Y1599638D01*
X656051Y1599138D01*
X658215D01*
X659722Y1597631D01*
Y1556178D01*
X652786Y1549242D01*
X647351Y1545609D01*
X619828Y1530975D01*
X614260Y1525408D01*
X609610Y1514182D01*
Y1453771D01*
X612176Y1445732D01*
X619297Y1438616D01*
X634564Y1427597D01*
X653731Y1419169D01*
X659143Y1413757D01*
Y1370200D01*
X662243Y1367100D01*
X669800D01*
X671383Y1365517D01*
Y1346094D01*
X672687Y1344611D01*
X714798Y1316569D01*
X746892Y1285737D01*
X754944Y1274513D01*
X757935Y1265213D01*
X757937Y1265211D01*
Y1260312D01*
G01X672874Y1601142D02*
Y1599638D01*
X673374Y1599138D01*
X675538D01*
X677045Y1597631D01*
Y1556557D01*
X671925Y1551436D01*
X650999Y1537461D01*
X649180Y1536390D01*
X636777Y1529990D01*
X624188Y1524698D01*
X620640Y1521150D01*
X617300Y1513093D01*
Y1454567D01*
X619448Y1449099D01*
X624162Y1444388D01*
X638359Y1434148D01*
X671666Y1419502D01*
X682047Y1414621D01*
X683623Y1413045D01*
Y1393247D01*
X685760Y1391110D01*
X693213D01*
X695863Y1388460D01*
Y1345706D01*
X729861Y1314419D01*
X748939Y1295143D01*
X755675Y1287365D01*
X761552Y1278952D01*
X765417Y1266671D01*
Y1260312D01*
G01X655551Y1596024D02*
Y1597528D01*
X656051Y1598028D01*
X657755D01*
X658612Y1597171D01*
Y1556638D01*
X656670Y1554696D01*
X656048D01*
X654704Y1553352D01*
Y1552730D01*
X652078Y1550104D01*
X646780Y1546564D01*
X619160Y1531877D01*
X613319Y1526037D01*
X608500Y1514403D01*
Y1453598D01*
X611200Y1445137D01*
X618575Y1437768D01*
X634009Y1426627D01*
X653093Y1418236D01*
X658033Y1413297D01*
Y1369740D01*
X661783Y1365990D01*
X669340D01*
X670273Y1365057D01*
Y1345675D01*
X671809Y1343928D01*
X671900Y1343800D01*
X693083Y1329694D01*
X693084D01*
X714100Y1315700D01*
X746049Y1285007D01*
X753940Y1274007D01*
X756825Y1265038D01*
X756827Y1265032D01*
Y1260312D01*
G01X646890Y1596811D02*
Y1595307D01*
X647390Y1594807D01*
X649554D01*
X651061Y1593300D01*
Y1554817D01*
X650082Y1553347D01*
X633435Y1542470D01*
X617619Y1534085D01*
X611069Y1527535D01*
X605850Y1514930D01*
Y1452288D01*
X608417Y1444171D01*
X616852Y1435743D01*
X645823Y1414824D01*
X646903Y1413744D01*
Y1368867D01*
X648460Y1367310D01*
X655789D01*
X659143Y1363956D01*
Y1346094D01*
X663336Y1341368D01*
X711514Y1312362D01*
X739149Y1287959D01*
X739224Y1287884D01*
X751643Y1271873D01*
X754197Y1264415D01*
Y1260312D01*
G01X681535Y1591693D02*
Y1593197D01*
X682035Y1593697D01*
X683739D01*
X684596Y1592840D01*
Y1554815D01*
X683299Y1553700D01*
X680457Y1551799D01*
X679948Y1551900D01*
X678246Y1550761D01*
X678145Y1550253D01*
X676566Y1549197D01*
X675955Y1549318D01*
X674375Y1548261D01*
X674254Y1547651D01*
X672675Y1546595D01*
X672065Y1546716D01*
X670485Y1545659D01*
X670363Y1545048D01*
X667000Y1542799D01*
X640703Y1528745D01*
X625662Y1522424D01*
X622885Y1519645D01*
X619950Y1512561D01*
Y1455070D01*
X621713Y1450586D01*
X625633Y1446666D01*
X639941Y1436351D01*
X674057Y1421348D01*
X689163Y1416668D01*
X705048Y1413452D01*
X706993Y1411507D01*
Y1345810D01*
X712501Y1335730D01*
X750885Y1296945D01*
X758114Y1288599D01*
X764025Y1280275D01*
X768047Y1267661D01*
Y1260312D01*
G01X738125Y1069976D02*
Y1053143D01*
X626537Y633482D01*
X623662Y617248D01*
X621352Y581735D01*
X623293Y578169D01*
X624164Y577105D01*
X625847Y575693D01*
X634594Y572889D01*
X636283Y571200D01*
X637884Y568805D01*
X645375Y562015D01*
X648699Y553989D01*
Y539122D01*
X653322Y527956D01*
X658900Y522674D01*
X659318Y522256D01*
X660546Y521747D01*
X661621D01*
X662766Y520602D01*
G01X741865Y1069000D02*
Y1068497D01*
X741863Y1068495D01*
Y1068493D01*
X741865Y1068491D01*
Y1052247D01*
X630285Y632944D01*
X627466Y617118D01*
X625193Y582851D01*
X626431Y580274D01*
X628014Y579086D01*
X628755Y578715D01*
X630180Y578300D01*
X632064D01*
X636367Y576518D01*
X639101Y573784D01*
X640361Y571901D01*
X646053Y567233D01*
X649620Y563666D01*
X652910Y555723D01*
Y539645D01*
X653016Y539539D01*
X657050Y531010D01*
X657792Y530304D01*
X661344Y528833D01*
X668921D01*
X670066Y527688D01*
G01X739235Y1069976D02*
Y1052997D01*
X627622Y633242D01*
X624766Y617115D01*
X622481Y581984D01*
X624219Y578792D01*
X624957Y577889D01*
X626394Y576684D01*
X630618Y575330D01*
X631184Y575621D01*
X633042Y575026D01*
X633333Y574459D01*
X635189Y573864D01*
X637145Y571908D01*
X638731Y569536D01*
X642749Y565895D01*
X643384Y565926D01*
X644830Y564616D01*
X644862Y563980D01*
X646306Y562671D01*
X647157Y560616D01*
X647745Y560373D01*
X648491Y558570D01*
X648247Y557982D01*
X649809Y554210D01*
Y552260D01*
X650259Y551810D01*
Y549860D01*
X649809Y549410D01*
Y547460D01*
X650259Y547010D01*
Y545060D01*
X649809Y544610D01*
Y539343D01*
X650555Y537542D01*
X651144Y537298D01*
X651890Y535496D01*
X651646Y534908D01*
X652392Y533107D01*
X652980Y532863D01*
X653726Y531061D01*
X653483Y530473D01*
X654258Y528600D01*
X656042Y526910D01*
X656678Y526928D01*
X658095Y525586D01*
X658112Y524949D01*
X659674Y523470D01*
X659947Y523197D01*
X660767Y522857D01*
X661621D01*
X662766Y524002D01*
G01X742975Y1069000D02*
Y1052101D01*
X631370Y632704D01*
X628570Y616984D01*
X628084Y609634D01*
X628360Y609319D01*
X628224Y607266D01*
X627907Y606989D01*
X627779Y605044D01*
X628105Y604672D01*
X627976Y602725D01*
X627603Y602399D01*
X627474Y600454D01*
X627854Y600020D01*
X627719Y597989D01*
X627285Y597609D01*
X627156Y595664D01*
X627575Y595185D01*
X627446Y593238D01*
X626966Y592819D01*
X626967D01*
X626320Y583069D01*
X627315Y581000D01*
X628601Y580034D01*
X629162Y579753D01*
X630339Y579410D01*
X632285D01*
X636996Y577459D01*
X639963Y574492D01*
X641193Y572656D01*
X646799Y568057D01*
X650561Y564295D01*
X651674Y561608D01*
Y561607D01*
X652263Y561363D01*
X653009Y559561D01*
X652766Y558973D01*
X654020Y555944D01*
Y553994D01*
X654470Y553544D01*
Y551594D01*
X654020Y551144D01*
Y549194D01*
X654470Y548744D01*
Y546794D01*
X654020Y546344D01*
Y540013D01*
X655912Y536013D01*
Y536012D01*
X656511Y535797D01*
X657346Y534033D01*
X657132Y533434D01*
X657965Y531672D01*
X658408Y531251D01*
X661565Y529943D01*
X663515D01*
X663965Y530393D01*
X665915D01*
X666365Y529943D01*
X668888D01*
X668912Y529934D01*
X670066Y531088D01*
G01X662766Y534775D02*
Y534776D01*
X661622Y535920D01*
X660138D01*
X657923Y538135D01*
X657422Y539345D01*
Y556049D01*
X652622Y567778D01*
X643165Y577086D01*
X640581Y578144D01*
X639350Y579356D01*
X637523Y583461D01*
X637522Y583468D01*
X634104Y625390D01*
X634436Y632948D01*
X745357Y1049597D01*
X745606Y1051495D01*
Y1069177D01*
G01X662766Y538175D02*
Y538174D01*
X661622Y537030D01*
X660598D01*
X658864Y538764D01*
X658532Y539566D01*
Y541975D01*
X658982Y542425D01*
Y544375D01*
X658532Y544825D01*
Y549075D01*
X658982Y549525D01*
Y551475D01*
X658532Y551925D01*
Y556268D01*
X657786Y558092D01*
X658032Y558679D01*
X657294Y560485D01*
X656706Y560731D01*
X655968Y562535D01*
X656214Y563122D01*
X655476Y564928D01*
X654888Y565174D01*
X653564Y568410D01*
X652175Y569777D01*
X652169Y570414D01*
X650779Y571782D01*
X650142Y571777D01*
X648753Y573144D01*
X648747Y573781D01*
X647357Y575149D01*
X646721Y575145D01*
X643788Y578031D01*
X641204Y579089D01*
X640279Y580000D01*
X638614Y583746D01*
X637602Y596171D01*
X638096Y596753D01*
X637980Y598179D01*
X637397Y598673D01*
X637281Y600098D01*
X637775Y600680D01*
X637659Y602106D01*
X637076Y602601D01*
X635216Y625411D01*
X635540Y632779D01*
X746449Y1049381D01*
X746707Y1051351D01*
X746716Y1051360D01*
Y1069177D01*
G01X681535Y1596811D02*
Y1595307D01*
X682035Y1594807D01*
X684199D01*
X685706Y1593300D01*
Y1554305D01*
X683972Y1552814D01*
X667572Y1541846D01*
X641181Y1527741D01*
X626293Y1521485D01*
X623826Y1519016D01*
X621060Y1512340D01*
Y1455281D01*
X622662Y1451208D01*
X626355Y1447514D01*
X640495Y1437320D01*
X674446Y1422390D01*
X689438Y1417746D01*
Y1417745D01*
X705596Y1414474D01*
X708103Y1411967D01*
Y1346094D01*
X713400Y1336400D01*
X751700Y1297700D01*
X758989Y1289286D01*
X765030Y1280777D01*
X769157Y1267834D01*
Y1260312D01*
G01X690197Y1596024D02*
Y1597528D01*
X690697Y1598028D01*
X692401D01*
X693258Y1597171D01*
Y1558058D01*
X691915Y1556715D01*
X691293D01*
X689948Y1555370D01*
Y1554748D01*
X685250Y1550050D01*
X669800Y1539700D01*
X642492Y1525416D01*
X627803Y1519244D01*
X626166Y1517607D01*
X623710Y1511811D01*
Y1457398D01*
X625919Y1451780D01*
X628084Y1449615D01*
X642886Y1439235D01*
X675567Y1424866D01*
X689976Y1420401D01*
X714954Y1415346D01*
X719233Y1411067D01*
Y1345834D01*
X723504Y1337195D01*
X760038Y1292556D01*
X767587Y1281922D01*
X771787Y1268751D01*
Y1260312D01*
G01X690197Y1601142D02*
Y1599638D01*
X690697Y1599138D01*
X692861D01*
X694368Y1597631D01*
Y1557598D01*
X685958Y1549188D01*
X670368Y1538744D01*
X642965Y1524410D01*
X628434Y1518305D01*
X627104Y1516975D01*
X624820Y1511585D01*
Y1457609D01*
X626868Y1452402D01*
X628801Y1450469D01*
X643434Y1440208D01*
X675956Y1425908D01*
X690251Y1421479D01*
Y1421478D01*
X715502Y1416368D01*
X720343Y1411527D01*
Y1346094D01*
X724444Y1337801D01*
X760921Y1293230D01*
X768592Y1282424D01*
X772897Y1268924D01*
Y1260312D01*
G01X629567Y1489331D02*
Y1490835D01*
X630067Y1491335D01*
X631771D01*
X632628Y1490478D01*
Y1454614D01*
X635142Y1451072D01*
X636589Y1449625D01*
X650743Y1439897D01*
X677790Y1428175D01*
X690579Y1424211D01*
X727447Y1416753D01*
X731473Y1412727D01*
Y1346845D01*
X732657Y1342046D01*
X735160Y1338853D01*
X735084Y1338222D01*
X736288Y1336686D01*
X736920Y1336610D01*
X738123Y1335076D01*
X738046Y1334444D01*
X739251Y1332909D01*
X739882Y1332832D01*
X741085Y1331298D01*
X741008Y1330666D01*
X742213Y1329131D01*
X742845Y1329054D01*
X750688Y1319053D01*
X753603Y1314290D01*
X753454Y1313671D01*
X754473Y1312007D01*
X755091Y1311858D01*
X756108Y1310195D01*
X755959Y1309576D01*
X756978Y1307912D01*
X757597Y1307763D01*
X758614Y1306100D01*
X758465Y1305481D01*
X759484Y1303817D01*
X760103Y1303668D01*
X774467Y1280195D01*
X779268Y1263154D01*
Y1256712D01*
G01X629567Y1494449D02*
Y1492945D01*
X630067Y1492445D01*
X632231D01*
X633738Y1490938D01*
Y1454968D01*
X635993Y1451791D01*
X637302Y1450482D01*
X651283Y1440873D01*
X678176Y1429218D01*
X690854Y1425288D01*
X727995Y1417775D01*
X732583Y1413187D01*
Y1346980D01*
X733678Y1342543D01*
X751602Y1319688D01*
X775494Y1280644D01*
X780378Y1263308D01*
Y1256712D01*
G01X784215Y1224115D02*
X788921Y1228821D01*
Y1247800D01*
X784986Y1258049D01*
X779244Y1280690D01*
X768767Y1299976D01*
X768768D01*
X768158Y1300156D01*
X767226Y1301871D01*
X767406Y1302481D01*
X766476Y1304194D01*
X765934Y1304354D01*
X765002Y1306069D01*
X765162Y1306611D01*
X764232Y1308324D01*
X764233D01*
X763691Y1308484D01*
X762759Y1310199D01*
X762919Y1310741D01*
X761989Y1312454D01*
X761447Y1312615D01*
X760515Y1314329D01*
X760675Y1314872D01*
X760674D01*
X749111Y1336160D01*
X748500Y1336340D01*
X747569Y1338055D01*
X747749Y1338665D01*
X743713Y1346096D01*
Y1410390D01*
X742486Y1412455D01*
X742462Y1412461D01*
X738809Y1416140D01*
X731777Y1419844D01*
X690351Y1428224D01*
X679063Y1431723D01*
X659741Y1440098D01*
X644500Y1450633D01*
X643399Y1451734D01*
X641289Y1455248D01*
Y1494809D01*
X640432Y1495666D01*
X638728D01*
X638228Y1495166D01*
Y1493662D01*
G01X785000Y1223330D02*
X790031Y1228361D01*
Y1248006D01*
X786046Y1258386D01*
X780286Y1281098D01*
X744823Y1346379D01*
Y1410699D01*
X743441Y1413022D01*
Y1413023D01*
X743446Y1413046D01*
X739477Y1417043D01*
X732154Y1420901D01*
X690626Y1429301D01*
X679449Y1432766D01*
X660283Y1441074D01*
X645214Y1451489D01*
X644281Y1452423D01*
X642399Y1455556D01*
Y1495269D01*
X640892Y1496776D01*
X638728D01*
X638228Y1497276D01*
Y1498780D01*
G01X786412Y1219747D02*
X788163D01*
X789641Y1221225D01*
X792864Y1226363D01*
Y1248100D01*
X789154Y1256995D01*
X784257Y1281876D01*
X781961Y1287470D01*
X781372Y1287716D01*
X780632Y1289520D01*
X780877Y1290108D01*
X780137Y1291911D01*
X779549Y1292157D01*
X778808Y1293961D01*
X779053Y1294549D01*
X778313Y1296352D01*
X777725Y1296597D01*
X776984Y1298402D01*
X777229Y1298989D01*
X776261Y1301348D01*
X765737Y1322323D01*
X765738D01*
X765134Y1322524D01*
X764259Y1324268D01*
X764459Y1324872D01*
X764458D01*
X763584Y1326614D01*
X763585D01*
X762981Y1326815D01*
X762106Y1328559D01*
X762306Y1329163D01*
X762305D01*
X761431Y1330905D01*
X761432D01*
X760828Y1331106D01*
X759953Y1332850D01*
X760153Y1333454D01*
X760152D01*
X759278Y1335196D01*
X759279D01*
X758675Y1335396D01*
X757799Y1337140D01*
X758000Y1337744D01*
X755953Y1341824D01*
Y1386814D01*
X754136Y1395943D01*
X746895Y1413426D01*
X740758Y1419605D01*
X733554Y1423403D01*
X690897Y1432029D01*
X681421Y1434968D01*
X681368Y1434989D01*
X676218Y1437173D01*
X667289Y1440961D01*
X663436Y1442596D01*
X652173Y1450250D01*
X649951Y1454306D01*
Y1490478D01*
X649094Y1491335D01*
X647390D01*
X646890Y1490835D01*
Y1489331D01*
G01X786412Y1218637D02*
X788623D01*
X790515Y1220529D01*
X793974Y1226043D01*
Y1248323D01*
X790222Y1257319D01*
X785326Y1282197D01*
X777273Y1301809D01*
X757063Y1342087D01*
Y1386924D01*
X755204Y1396267D01*
X747837Y1414053D01*
X741426Y1420508D01*
X733931Y1424460D01*
X691172Y1433106D01*
X681796Y1436014D01*
X681791Y1436016D01*
X676652Y1438196D01*
X667723Y1441984D01*
X663970Y1443576D01*
X653018Y1451018D01*
X651061Y1454591D01*
Y1490938D01*
X649554Y1492445D01*
X647390D01*
X646890Y1492945D01*
Y1494449D01*
G01X655551Y1498780D02*
Y1497276D01*
X656051Y1496776D01*
X658215D01*
X659722Y1495269D01*
Y1455802D01*
X661604Y1452423D01*
X663383Y1450644D01*
X674088Y1443370D01*
X683084Y1439553D01*
X692112Y1436753D01*
X735207Y1428039D01*
X743770Y1423525D01*
X751804Y1415431D01*
X763762Y1399061D01*
X780907Y1369319D01*
X829649Y1279152D01*
X832360Y1265611D01*
Y1259593D01*
X829159Y1251766D01*
X821456Y1243834D01*
X813384Y1238457D01*
X797611Y1222708D01*
X797368Y1222009D01*
X797367Y1222007D01*
X796630Y1219890D01*
X793657Y1216917D01*
X788781Y1214897D01*
X786412D01*
G01X655551Y1493662D02*
Y1495166D01*
X656051Y1495666D01*
X657755D01*
X658612Y1494809D01*
Y1455513D01*
X660709Y1451747D01*
X662672Y1449785D01*
X673554Y1442390D01*
X682703Y1438508D01*
X691837Y1435676D01*
X734830Y1426982D01*
X743102Y1422622D01*
X750956Y1414708D01*
X762830Y1398455D01*
X772361Y1381920D01*
X772196Y1381305D01*
X773171Y1379615D01*
X773785Y1379449D01*
X774758Y1377760D01*
X774593Y1377145D01*
X775568Y1375455D01*
X776183Y1375290D01*
X777156Y1373601D01*
X776991Y1372986D01*
X777966Y1371296D01*
X778580Y1371131D01*
X779937Y1368777D01*
X809539Y1314017D01*
X809357Y1313408D01*
X810286Y1311691D01*
X810895Y1311509D01*
X811822Y1309794D01*
X811640Y1309184D01*
X812568Y1307468D01*
X813178Y1307286D01*
X828593Y1278771D01*
X831250Y1265500D01*
Y1259812D01*
X828212Y1252386D01*
X820741Y1244693D01*
X816710Y1242008D01*
Y1242007D01*
X812677Y1239320D01*
X796646Y1223314D01*
X795665Y1220495D01*
X793028Y1217858D01*
X788560Y1216007D01*
X786412D01*
G01X664213Y1489331D02*
Y1490835D01*
X664713Y1491335D01*
X666417D01*
X667274Y1490478D01*
Y1454377D01*
X669801Y1451059D01*
X671237Y1449623D01*
X677992Y1445030D01*
X687829Y1440857D01*
X691997Y1439566D01*
X735805Y1430721D01*
X746226Y1425227D01*
X752755Y1418652D01*
X769153Y1396201D01*
X771754Y1391688D01*
X771589Y1391074D01*
X772564Y1389383D01*
X773178Y1389218D01*
X774151Y1387529D01*
X773986Y1386914D01*
X774961Y1385224D01*
X775576Y1385059D01*
X776549Y1383370D01*
X776384Y1382755D01*
X777359Y1381065D01*
X777973Y1380900D01*
X777972D01*
X783051Y1372090D01*
X787214Y1364324D01*
X787030Y1363715D01*
X787952Y1361995D01*
X788561Y1361811D01*
X789482Y1360093D01*
X789298Y1359484D01*
X790220Y1357764D01*
X790829Y1357580D01*
X791750Y1355862D01*
X791566Y1355253D01*
X792488Y1353533D01*
X793098Y1353349D01*
X793097D01*
X794018Y1351630D01*
X794019Y1351631D01*
X793835Y1351022D01*
X794757Y1349302D01*
X795366Y1349118D01*
X832112Y1280571D01*
X835010Y1266105D01*
Y1259057D01*
X831359Y1250142D01*
X822561Y1241175D01*
X814823Y1236148D01*
X807426Y1228762D01*
Y1228761D01*
X799931Y1221279D01*
X798916Y1218357D01*
X795127Y1214567D01*
X789585Y1212267D01*
X786512D01*
G01X664213Y1494449D02*
Y1492945D01*
X664713Y1492445D01*
X666877D01*
X668384Y1490938D01*
Y1454752D01*
X670639Y1451791D01*
X671948Y1450482D01*
X678526Y1446010D01*
X688211Y1441901D01*
X692272Y1440643D01*
X736182Y1431778D01*
X746894Y1426130D01*
X753602Y1419375D01*
X770085Y1396807D01*
X784021Y1372630D01*
X833169Y1280951D01*
X836120Y1266216D01*
Y1258838D01*
X832304Y1249520D01*
X823269Y1240310D01*
X815525Y1235280D01*
X800897Y1220673D01*
X799881Y1217752D01*
X795756Y1213626D01*
X789807Y1211157D01*
X786512D01*
G01X672874Y1493662D02*
Y1495166D01*
X673374Y1495666D01*
X675078D01*
X675935Y1494809D01*
Y1454657D01*
X679059Y1450349D01*
X683820Y1446764D01*
X694411Y1442932D01*
X737307Y1434255D01*
X748440Y1428497D01*
X757018Y1419858D01*
X775817Y1397826D01*
X787195Y1378089D01*
X788075Y1376350D01*
X787877Y1375745D01*
X788758Y1374004D01*
X789363Y1373806D01*
X789362D01*
X790242Y1372067D01*
X790243D01*
X790045Y1371462D01*
X790926Y1369721D01*
X791531Y1369523D01*
X791530D01*
X792410Y1367784D01*
X792411D01*
X792213Y1367179D01*
X793094Y1365438D01*
X793699Y1365240D01*
X793698Y1365239D01*
X803227Y1346410D01*
X803228Y1346411D01*
X803030Y1345806D01*
X803911Y1344065D01*
X804516Y1343867D01*
X804514Y1343865D01*
X805395Y1342127D01*
X805396Y1342128D01*
X805198Y1341523D01*
X806079Y1339782D01*
X806684Y1339584D01*
X806682Y1339582D01*
X835711Y1282226D01*
X838770Y1266935D01*
Y1258316D01*
X834693Y1248359D01*
X834398Y1247799D01*
X825200Y1238400D01*
X817208Y1233212D01*
X803213Y1219239D01*
X801986Y1215726D01*
X797657Y1211397D01*
X790848Y1208577D01*
X786812D01*
G01X672874Y1498780D02*
Y1497276D01*
X673374Y1496776D01*
X675538D01*
X677045Y1495269D01*
Y1455018D01*
X679860Y1451136D01*
X684355Y1447752D01*
X694712Y1444004D01*
X737679Y1435313D01*
X749105Y1429403D01*
X757836Y1420611D01*
X776728Y1398469D01*
X788172Y1378617D01*
X836770Y1282592D01*
X839880Y1267045D01*
Y1258097D01*
X835700Y1247889D01*
X835308Y1247140D01*
X825908Y1237535D01*
X817910Y1232344D01*
X804178Y1218632D01*
X802951Y1215120D01*
X798286Y1210456D01*
X791069Y1207467D01*
X786812D01*
G01X681535Y1489331D02*
Y1490835D01*
X682035Y1491335D01*
X683739D01*
X684596Y1490478D01*
Y1453723D01*
X686100Y1450899D01*
X689031Y1448912D01*
X695637Y1446521D01*
X738565Y1437840D01*
X751055Y1431379D01*
X761840Y1420514D01*
X782644Y1396131D01*
X786138Y1390070D01*
X789655Y1383021D01*
X789453Y1382418D01*
X790324Y1380672D01*
X790928Y1380470D01*
X791798Y1378726D01*
X791596Y1378122D01*
X792468Y1376376D01*
X793071Y1376174D01*
X793941Y1374430D01*
X793739Y1373826D01*
X794611Y1372080D01*
X795214Y1371878D01*
X839281Y1283552D01*
X842530Y1267313D01*
Y1257560D01*
X837152Y1244427D01*
X837153D01*
X831336Y1238610D01*
X830699D01*
X829319Y1237230D01*
Y1236593D01*
X827941Y1235215D01*
X827304D01*
X825924Y1233835D01*
Y1233198D01*
X824546Y1231820D01*
X823924D01*
X822580Y1230476D01*
Y1229854D01*
X806221Y1213495D01*
X805585D01*
X804205Y1212115D01*
Y1211479D01*
X801710Y1208984D01*
X791578Y1204787D01*
X786612D01*
G01X681535Y1494449D02*
Y1492945D01*
X682035Y1492445D01*
X684199D01*
X685706Y1490938D01*
Y1454001D01*
X686951Y1451664D01*
X689539Y1449909D01*
X695938Y1447593D01*
X738937Y1438898D01*
X751720Y1432285D01*
X762658Y1421267D01*
X783555Y1396774D01*
X787117Y1390596D01*
X840341Y1283915D01*
X843640Y1267423D01*
Y1257341D01*
X838096Y1243800D01*
X802339Y1208043D01*
X791799Y1203677D01*
X786612D01*
G01X690197Y1498780D02*
Y1497276D01*
X690697Y1496776D01*
X692861D01*
X694368Y1495269D01*
Y1454002D01*
X697191Y1451179D01*
X740987Y1442321D01*
X754213Y1435481D01*
X777818Y1411590D01*
X789798Y1396363D01*
X843823Y1285687D01*
X847400Y1267800D01*
Y1256600D01*
X840420Y1239550D01*
X806404Y1205534D01*
X792900Y1199940D01*
X792896Y1199936D01*
X786412D01*
G01X690197Y1493662D02*
Y1495166D01*
X690697Y1495666D01*
X692401D01*
X693258Y1494809D01*
Y1453542D01*
X696643Y1450157D01*
X740615Y1441263D01*
X753546Y1434575D01*
X776984Y1410854D01*
X788852Y1395770D01*
X794227Y1384758D01*
X794020Y1384156D01*
X794876Y1382403D01*
X795478Y1382196D01*
X796333Y1380444D01*
X796126Y1379842D01*
X796982Y1378089D01*
X797584Y1377882D01*
X798439Y1376130D01*
X798232Y1375528D01*
X799088Y1373775D01*
X799690Y1373568D01*
X799689D01*
X842762Y1285329D01*
X846290Y1267690D01*
Y1256819D01*
X839477Y1240177D01*
X831253Y1231953D01*
X830616D01*
X829236Y1230573D01*
Y1229936D01*
X827858Y1228558D01*
X827222D01*
X825842Y1227178D01*
Y1226542D01*
X805775Y1206475D01*
X792669Y1201046D01*
X786412D01*
G01X713791Y474424D02*
X714936Y475569D01*
X723291D01*
X743924Y484160D01*
X752754Y492890D01*
X774264Y517830D01*
X782734Y522500D01*
X784424Y524190D01*
X793354Y529160D01*
X795419Y532374D01*
X804976Y576190D01*
X805993Y590143D01*
X807995Y663520D01*
X805385Y913768D01*
X811079Y941705D01*
X845664Y1060150D01*
X845066Y1076270D01*
X835348Y1093732D01*
X801475Y1126420D01*
X795670Y1129984D01*
X787599D01*
G01X713791Y488597D02*
X714936Y489742D01*
X721976D01*
X730976Y491482D01*
X743765Y496797D01*
X747224Y500170D01*
X772234Y542030D01*
X781044Y547870D01*
X782374Y551590D01*
X795103Y568174D01*
X798283Y590658D01*
X800105Y663001D01*
X797527Y914163D01*
X804306Y946021D01*
X837945Y1061194D01*
X837498Y1074239D01*
X829050Y1089219D01*
X797528Y1119774D01*
X792821Y1122503D01*
X787599D01*
G01X713791Y477824D02*
X714936Y476679D01*
X723069D01*
X724869Y477429D01*
Y477428D01*
X725111Y478018D01*
X726912Y478767D01*
X727501Y478525D01*
X729301Y479274D01*
X729543Y479863D01*
X731344Y480613D01*
X731933Y480371D01*
X733733Y481120D01*
X733975Y481709D01*
X735776Y482459D01*
X736365Y482216D01*
X738165Y482965D01*
X738407Y483554D01*
X740208Y484304D01*
X740797Y484061D01*
X743297Y485102D01*
X751942Y493649D01*
X753767Y495766D01*
X753731Y496259D01*
X755006Y497737D01*
X755499Y497773D01*
X756772Y499249D01*
X756736Y499743D01*
X758010Y501221D01*
X758504Y501257D01*
X759777Y502733D01*
X759741Y503227D01*
X761015Y504705D01*
X761509Y504741D01*
X773553Y518707D01*
X782060Y523396D01*
X783749Y525085D01*
X792570Y529995D01*
X794377Y532806D01*
X803874Y576350D01*
X804884Y590199D01*
X806884Y663529D01*
X804273Y913874D01*
X810000Y941972D01*
X844548Y1060289D01*
X843966Y1075963D01*
X834458Y1093048D01*
X800791Y1125537D01*
X795356Y1128874D01*
X787599D01*
G01X713791Y491997D02*
X714936Y490852D01*
X721869D01*
X724853Y491429D01*
X725210Y491957D01*
X727125Y492327D01*
X727652Y491971D01*
X730654Y492551D01*
X733084Y493561D01*
Y493562D01*
X733327Y494151D01*
X735128Y494899D01*
X735716Y494656D01*
X743145Y497743D01*
X746345Y500864D01*
X747989Y503616D01*
X747833Y504233D01*
X748835Y505908D01*
X749452Y506064D01*
X752210Y510681D01*
X752054Y511298D01*
X753056Y512973D01*
X753673Y513128D01*
X753672D01*
X754672Y514801D01*
X754516Y515419D01*
X755517Y517094D01*
X756134Y517249D01*
X757134Y518922D01*
X756978Y519540D01*
X757979Y521215D01*
X758596Y521370D01*
X771410Y542816D01*
X780122Y548592D01*
X781387Y552128D01*
X794044Y568619D01*
X797174Y590750D01*
X798994Y663009D01*
X796415Y914274D01*
X803228Y946293D01*
X836829Y1061334D01*
X836397Y1073930D01*
X828161Y1088533D01*
X796853Y1118882D01*
X792522Y1121393D01*
X787599D01*
G01X713791Y518558D02*
X714936Y519703D01*
X722154D01*
X749264Y533310D01*
X759867Y540968D01*
X762659Y545216D01*
X763785Y547842D01*
X766210Y559139D01*
X777098Y632688D01*
X785808Y876381D01*
X789878Y918553D01*
X800189Y961149D01*
X830252Y1063911D01*
X830036Y1072077D01*
X823117Y1084322D01*
X793993Y1112634D01*
X790360Y1115023D01*
X787471D01*
G01X713791Y521958D02*
X714936Y520813D01*
X721890D01*
X725346Y522548D01*
X725347Y522547D01*
X725547Y523151D01*
X727291Y524027D01*
X727895Y523827D01*
X729637Y524701D01*
X729838Y525305D01*
X731581Y526181D01*
X732185Y525981D01*
X733927Y526855D01*
X734128Y527459D01*
X735872Y528335D01*
X736476Y528134D01*
X738218Y529008D01*
X738419Y529612D01*
X740162Y530488D01*
X740767Y530288D01*
X742509Y531162D01*
X742710Y531766D01*
X744454Y532642D01*
X745058Y532441D01*
X748686Y534262D01*
X751930Y536605D01*
X752031Y537233D01*
X753613Y538376D01*
X754241Y538275D01*
X759051Y541749D01*
X761677Y545744D01*
X762722Y548180D01*
X765117Y559337D01*
X770553Y596060D01*
Y596062D01*
X770554Y596063D01*
X775990Y632789D01*
X784699Y876454D01*
X788780Y918738D01*
X799116Y961436D01*
X829137Y1064056D01*
X828933Y1071771D01*
X822229Y1083637D01*
X793294Y1111764D01*
X790027Y1113913D01*
X787471D01*
G01X713791Y536131D02*
X714936Y534986D01*
X722513D01*
X725379Y536152D01*
X725627Y536739D01*
X727434Y537474D01*
X728020Y537226D01*
X729826Y537960D01*
X730073Y538548D01*
X731880Y539282D01*
X732467Y539035D01*
X734273Y539769D01*
X734520Y540356D01*
X736328Y541091D01*
X736914Y540844D01*
X739790Y542013D01*
X744662Y546953D01*
X746085Y549374D01*
Y550892D01*
X747342Y553926D01*
X750773Y557357D01*
X751340Y558323D01*
X752810Y564778D01*
X752471Y565317D01*
X752904Y567219D01*
X753444Y567558D01*
X753876Y569459D01*
X753538Y569998D01*
X753971Y571900D01*
X754510Y572239D01*
X754942Y574140D01*
X754604Y574679D01*
X755037Y576581D01*
X755576Y576920D01*
X755577Y576924D01*
X768105Y631936D01*
X768106Y631940D01*
X782098Y1042746D01*
X785557Y1067150D01*
X789649Y1089236D01*
X789336Y1103966D01*
X788428Y1106085D01*
X788079Y1106433D01*
X787599D01*
G01X713791Y532731D02*
X714936Y533876D01*
X722731D01*
X740420Y541070D01*
X745550Y546271D01*
X747195Y549072D01*
Y550671D01*
X748283Y553297D01*
X751658Y556672D01*
X752384Y557908D01*
Y557907D01*
X752385Y557909D01*
X769188Y631689D01*
X769212Y631713D01*
Y631796D01*
X783206Y1042649D01*
X786653Y1066971D01*
X790762Y1089146D01*
X790442Y1104205D01*
X789364Y1106721D01*
X788539Y1107543D01*
X787599D01*
G01X713791Y571997D02*
X714936Y570852D01*
X721526D01*
X724479Y572088D01*
X726401Y574037D01*
X726398Y574532D01*
X727768Y575921D01*
X728263Y575924D01*
X729632Y577312D01*
X729629Y577807D01*
X730999Y579196D01*
X731494Y579199D01*
X733357Y581088D01*
X740873Y592667D01*
X743847Y600930D01*
X754666Y611958D01*
X759987Y631909D01*
X774087Y1031411D01*
Y1056142D01*
X771787Y1067707D01*
Y1069000D01*
G01X713791Y568597D02*
X714936Y569742D01*
X721749D01*
X725113Y571149D01*
X734227Y580389D01*
X741874Y592170D01*
X744810Y600325D01*
X755664Y611389D01*
X761092Y631744D01*
X775197Y1031391D01*
Y1056252D01*
X772897Y1067817D01*
Y1069000D01*
G01X713791Y582771D02*
X714936Y583916D01*
X723631D01*
X733795Y594080D01*
X740054Y609097D01*
X748429Y621695D01*
X753227Y633171D01*
X753610Y634918D01*
X767414Y1025644D01*
X767552Y1055733D01*
X765417Y1066595D01*
Y1069000D01*
G01X713791Y586171D02*
X714936Y585026D01*
X723171D01*
X725892Y587747D01*
Y588242D01*
X727272Y589622D01*
X727767D01*
X729145Y591000D01*
Y591495D01*
X730525Y592875D01*
X731020D01*
X732855Y594710D01*
X739070Y609623D01*
X747445Y622222D01*
X752164Y633507D01*
X752334Y634283D01*
Y634284D01*
X752333D01*
X752336Y634299D01*
X752504Y635057D01*
X766304Y1025666D01*
X766441Y1055627D01*
X764307Y1066486D01*
Y1069000D01*
G01X713791Y596944D02*
X714936Y598089D01*
X724075D01*
X728187Y602201D01*
X731620Y610437D01*
X741595Y625205D01*
X745676Y635021D01*
X759676Y1026160D01*
X759972Y1054606D01*
X757937Y1065119D01*
Y1069000D01*
G01X713791Y600344D02*
X714936Y599199D01*
X723615D01*
X727247Y602831D01*
X730637Y610967D01*
X734747Y617051D01*
X734653Y617537D01*
X735745Y619154D01*
X736231Y619248D01*
X737322Y620863D01*
X737228Y621349D01*
X738321Y622966D01*
X738806Y623060D01*
X740612Y625734D01*
X744573Y635262D01*
X758566Y1026186D01*
X758860Y1054505D01*
X756827Y1065012D01*
Y1069000D01*
G01X713791Y611117D02*
X714936Y612262D01*
X718280D01*
X720722Y614703D01*
X724454Y641184D01*
Y641183D01*
X751651Y1028630D01*
X752320Y1054205D01*
X750457Y1063904D01*
Y1069000D01*
G01X749347D02*
Y1063798D01*
X751207Y1054114D01*
X750541Y1028683D01*
X723349Y641300D01*
X721229Y626255D01*
X720866Y625982D01*
X720558Y623794D01*
X720831Y623431D01*
X720559Y621501D01*
X720050Y621119D01*
X719777Y619187D01*
X720160Y618678D01*
X719674Y615226D01*
X717820Y613372D01*
X714936D01*
X713791Y614517D01*
G01X721091Y470737D02*
X722236Y469592D01*
X724121D01*
X725923Y470338D01*
Y470337D01*
X726167Y470926D01*
X727970Y471672D01*
X728558Y471428D01*
X730358Y472173D01*
X730359D01*
X730603Y472762D01*
X732406Y473508D01*
X732994Y473264D01*
X734794Y474009D01*
X734795D01*
X735039Y474598D01*
X736842Y475344D01*
X737430Y475100D01*
X742556Y477222D01*
X748456Y483103D01*
X756134Y488828D01*
X756225Y489458D01*
X757789Y490624D01*
X758419Y490532D01*
X759982Y491697D01*
X760073Y492327D01*
X761638Y493494D01*
X762267Y493402D01*
X763830Y494567D01*
X763921Y495197D01*
X765486Y496364D01*
X766115Y496272D01*
X792475Y515927D01*
X795333Y519683D01*
X807389Y573338D01*
X808944Y589940D01*
X810724Y663489D01*
X808100Y913004D01*
X814147Y942075D01*
X848389Y1059683D01*
X847675Y1077344D01*
X837463Y1095375D01*
X801809Y1129802D01*
X797352Y1132614D01*
X787499D01*
G01X721091Y467337D02*
X722236Y468482D01*
X724343D01*
X743184Y476280D01*
X749184Y482260D01*
X793264Y515130D01*
X796363Y519203D01*
X808488Y573164D01*
X810053Y589875D01*
X811835Y663481D01*
X809212Y912895D01*
X815225Y941806D01*
X849506Y1059547D01*
X848774Y1077658D01*
X838350Y1096062D01*
X802498Y1130680D01*
X797673Y1133724D01*
X787499D01*
G01X721091Y484910D02*
X722236Y483765D01*
X724481D01*
X726281Y484513D01*
X726524Y485102D01*
X728326Y485851D01*
X728914Y485608D01*
X730714Y486356D01*
X730957Y486945D01*
X732759Y487694D01*
X733347Y487451D01*
X735147Y488199D01*
X735390Y488788D01*
X737192Y489536D01*
X737780Y489294D01*
X742633Y491310D01*
X749940Y498666D01*
X755561Y507089D01*
X755436Y507713D01*
X756520Y509336D01*
X757144Y509460D01*
X757143D01*
X758225Y511081D01*
X758100Y511706D01*
X759184Y513329D01*
X759808Y513453D01*
X760890Y515074D01*
X760765Y515699D01*
X761849Y517322D01*
X762473Y517446D01*
X769802Y528428D01*
X786671Y545275D01*
X797494Y565520D01*
X801044Y590490D01*
X802994Y663218D01*
X800212Y914047D01*
X806734Y944691D01*
X840754Y1061058D01*
X840112Y1075091D01*
X831154Y1090881D01*
X798717Y1122312D01*
X793267Y1125133D01*
X787499D01*
G01X721091Y481510D02*
X722236Y482655D01*
X724703D01*
X743264Y490370D01*
X750804Y497960D01*
X770664Y527720D01*
X787573Y544606D01*
X798566Y565169D01*
X802152Y590397D01*
X804105Y663209D01*
X801324Y913936D01*
X807811Y944419D01*
X841872Y1060924D01*
X841209Y1075407D01*
X832042Y1091568D01*
X799372Y1123223D01*
X793777Y1126119D01*
X793653Y1126243D01*
X787499D01*
G01X721091Y514871D02*
X722236Y513726D01*
X723647D01*
X726308Y515132D01*
X726495Y515740D01*
X728220Y516652D01*
X728828Y516464D01*
X730552Y517374D01*
X730739Y517983D01*
X732464Y518894D01*
X733073Y518707D01*
X734797Y519617D01*
X734984Y520226D01*
X736709Y521137D01*
X737318Y520950D01*
X739042Y521860D01*
X739229Y522468D01*
X740955Y523380D01*
X741563Y523193D01*
X743287Y524103D01*
X743474Y524711D01*
X745200Y525623D01*
X745808Y525436D01*
X747634Y526400D01*
X752473Y530725D01*
X752509Y531361D01*
X753963Y532661D01*
X754599Y532626D01*
X762378Y539579D01*
X765428Y544078D01*
X768336Y551446D01*
X772884Y581807D01*
X774704Y583720D01*
X779594Y584890D01*
X783944Y589790D01*
X792214Y593920D01*
X793404Y596660D01*
X794844Y662730D01*
X792474Y914414D01*
X799893Y948661D01*
X833040Y1062070D01*
X832662Y1072815D01*
X825164Y1086190D01*
X795480Y1114884D01*
X791534Y1117653D01*
X787499D01*
G01X721091Y511471D02*
X722236Y512616D01*
X723923D01*
X748273Y525482D01*
X763221Y538842D01*
X766416Y543557D01*
X769415Y551156D01*
X773930Y581296D01*
X775281Y582716D01*
X780193Y583891D01*
X784632Y588892D01*
X793072Y593107D01*
X794510Y596418D01*
X795955Y662723D01*
X793586Y914300D01*
X800970Y948387D01*
X834156Y1061930D01*
X833762Y1073123D01*
X826053Y1086875D01*
X796189Y1115743D01*
X791886Y1118763D01*
X787499D01*
G01X721091Y525644D02*
X722236Y526789D01*
X723806D01*
X757527Y544891D01*
X759182Y546859D01*
X759787Y550350D01*
Y554757D01*
X772982Y630881D01*
X786983Y1042115D01*
X791601Y1072851D01*
X795013Y1090781D01*
Y1090902D01*
X794666Y1104893D01*
X793699Y1107175D01*
X791757Y1109519D01*
X789119Y1111283D01*
X787499D01*
G01X721091Y529044D02*
X722236Y527899D01*
X723526D01*
X727112Y529824D01*
X727296Y530433D01*
X729015Y531357D01*
X729624Y531173D01*
X731342Y532095D01*
X731525Y532704D01*
X733244Y533627D01*
X733854Y533444D01*
X735572Y534366D01*
X735755Y534975D01*
X737474Y535898D01*
X738084Y535715D01*
X740981Y537270D01*
X741164Y537879D01*
X742883Y538802D01*
X743493Y538618D01*
X745211Y539540D01*
X745394Y540149D01*
X747113Y541072D01*
X747723Y540889D01*
X749441Y541811D01*
X749624Y542420D01*
X751343Y543343D01*
X751953Y543160D01*
X751954D01*
X756814Y545769D01*
X758139Y547344D01*
X758677Y550446D01*
Y554853D01*
X771875Y630995D01*
X785875Y1042217D01*
X790506Y1073037D01*
X793903Y1090886D01*
Y1090888D01*
X793561Y1104654D01*
X792740Y1106592D01*
X791005Y1108686D01*
X788782Y1110173D01*
X787499D01*
G01X721091Y561510D02*
X722236Y562655D01*
X723214D01*
X731404Y568127D01*
X745539Y590139D01*
X747693Y596191D01*
X753449Y601698D01*
X758913Y609051D01*
X764859Y629856D01*
X765248Y632323D01*
X779469Y1044125D01*
X782065Y1065960D01*
X782250Y1069036D01*
X782252Y1069038D01*
Y1071163D01*
G01X721091Y564910D02*
X722236Y563765D01*
X722877D01*
X725562Y565559D01*
X725686Y566183D01*
X727308Y567268D01*
X727932Y567143D01*
X730594Y568922D01*
X733897Y574066D01*
X733762Y574688D01*
X734816Y576330D01*
X735438Y576465D01*
X736491Y578105D01*
X736356Y578727D01*
X737410Y580369D01*
X738032Y580504D01*
X739085Y582144D01*
X738950Y582766D01*
X740004Y584408D01*
X740626Y584543D01*
X741679Y586183D01*
X741574Y586667D01*
X742628Y588309D01*
X743112Y588414D01*
X744535Y590632D01*
X746735Y596812D01*
X752613Y602436D01*
X757901Y609551D01*
X763773Y630096D01*
X764140Y632429D01*
X778361Y1044210D01*
X780958Y1066059D01*
X781142Y1069103D01*
Y1071163D01*
G01X721091Y579084D02*
X722236Y577939D01*
X724130D01*
X725508Y579317D01*
Y579812D01*
X726888Y581192D01*
X727383D01*
X730315Y584124D01*
X731403Y585742D01*
X731307Y586227D01*
X732396Y587847D01*
X732882Y587942D01*
X736662Y593564D01*
X740313Y602525D01*
X747114Y611666D01*
X750853Y614722D01*
X751973Y616472D01*
X756289Y634058D01*
X770119Y1025590D01*
X770258Y1055732D01*
X768047Y1066982D01*
Y1069177D01*
G01X721091Y575684D02*
X722236Y576829D01*
X724590D01*
X731176Y583415D01*
X737647Y593039D01*
X741289Y601975D01*
X747923Y610893D01*
X751693Y613974D01*
X753008Y616028D01*
X757395Y633904D01*
X771229Y1025568D01*
X771369Y1055838D01*
X769157Y1067091D01*
Y1069177D01*
G01X721091Y593257D02*
X722236Y592112D01*
X724106D01*
X729571Y597481D01*
X730373Y599389D01*
X730186Y599848D01*
X730943Y601646D01*
X731401Y601833D01*
X732156Y603630D01*
X731969Y604088D01*
X732726Y605887D01*
X733185Y606074D01*
X735111Y610655D01*
X744026Y623900D01*
X748513Y634691D01*
X762405Y1026670D01*
X762651Y1055257D01*
X760567Y1065980D01*
Y1069177D01*
G01X721091Y604030D02*
X722231Y605170D01*
X723936D01*
X725898Y607132D01*
X726833Y609188D01*
X727885Y624536D01*
X727887Y624538D01*
Y631444D01*
X728341Y638049D01*
X729979Y648313D01*
X755298Y1017019D01*
X756146Y1054375D01*
X754197Y1064792D01*
Y1069176D01*
G01X721091Y589857D02*
X722236Y591002D01*
X724561D01*
X730508Y596845D01*
X736093Y610125D01*
X745009Y623372D01*
X749616Y634450D01*
X763515Y1026646D01*
X763762Y1055359D01*
X761677Y1066087D01*
Y1069177D01*
G01X753087Y1069176D02*
Y1064689D01*
X755033Y1054284D01*
X754188Y1017070D01*
X728875Y648439D01*
X727237Y638175D01*
X726777Y631483D01*
Y624576D01*
X726774Y624574D01*
X726396Y619041D01*
X726066Y618754D01*
X725913Y616526D01*
X726200Y616197D01*
X726067Y614252D01*
X725587Y613834D01*
X725454Y611888D01*
X725872Y611408D01*
X725739Y609464D01*
X724971Y607775D01*
X723476Y606280D01*
X722241D01*
X721091Y607430D01*
G01X945982Y886737D02*
X947127Y885592D01*
Y884008D01*
X942440Y872690D01*
X932981Y863231D01*
X931490Y859631D01*
Y853160D01*
X927640Y849310D01*
X922290D01*
X921028Y850572D01*
X920183D01*
X919163Y851592D01*
G01X949382Y886737D02*
X948237Y885592D01*
Y883787D01*
X943381Y872061D01*
X933922Y862602D01*
X932600Y859410D01*
Y852700D01*
X928100Y848200D01*
X921830D01*
X920568Y849462D01*
X920183D01*
X919163Y848442D01*
G01X1131850Y1607048D02*
Y1608552D01*
X1132350Y1609052D01*
X1134044D01*
X1135173Y1607923D01*
Y1555834D01*
X1133314Y1553025D01*
X1127281Y1549438D01*
X1126733Y1549577D01*
X1125055Y1548579D01*
X1124916Y1548031D01*
X1123240Y1547035D01*
X1122692Y1547174D01*
X1121015Y1546177D01*
X1120876Y1545628D01*
X1117072Y1543367D01*
X1105510Y1533097D01*
X1099030Y1519127D01*
X1097872Y1492158D01*
X1095797Y1470836D01*
X1093559Y1466237D01*
X1049821Y1421330D01*
X1010997Y1326316D01*
X990505Y1293220D01*
X982030Y1274083D01*
Y1251015D01*
X1001198Y1208432D01*
X1016409Y1193221D01*
X1036311Y1184976D01*
X1057588D01*
G01X1140511Y1611378D02*
Y1612882D01*
X1141011Y1613382D01*
X1142705D01*
X1143834Y1612253D01*
Y1559115D01*
X1142955Y1556929D01*
X1136413Y1550483D01*
X1119353Y1540156D01*
X1108505Y1530299D01*
X1103159Y1518232D01*
X1101892Y1491977D01*
X1099815Y1469294D01*
X1097221Y1464136D01*
X1053143Y1419253D01*
X1014995Y1324668D01*
X994308Y1291437D01*
X986040Y1272291D01*
Y1252105D01*
X1004062Y1211778D01*
X1018934Y1196906D01*
X1038701Y1188716D01*
X1054300D01*
G01X1131850Y1612166D02*
Y1610662D01*
X1132350Y1610162D01*
X1134504D01*
X1136283Y1608383D01*
Y1555500D01*
X1134100Y1552200D01*
X1117731Y1542466D01*
X1106420Y1532420D01*
X1100130Y1518860D01*
X1098980Y1492080D01*
X1096883Y1470530D01*
X1094480Y1465590D01*
X1050767Y1420710D01*
X1031380Y1373262D01*
X1031379D01*
Y1373261D01*
X1011990Y1325810D01*
X991490Y1292700D01*
X983140Y1273848D01*
Y1251254D01*
X1002127Y1209073D01*
X1005329Y1205871D01*
X1005895D01*
X1007275Y1204491D01*
Y1203925D01*
X1008653Y1202547D01*
X1009219D01*
X1010599Y1201167D01*
Y1200601D01*
X1011977Y1199223D01*
X1012543D01*
X1013923Y1197843D01*
Y1197277D01*
X1017038Y1194162D01*
X1022957Y1191711D01*
X1023479Y1191927D01*
X1025282Y1191180D01*
X1025498Y1190657D01*
Y1190658D01*
X1027299Y1189912D01*
X1027822Y1190129D01*
X1029624Y1189381D01*
X1029841Y1188859D01*
X1029842Y1188858D01*
X1036532Y1186086D01*
X1057588D01*
G01X1149173Y1612166D02*
Y1610662D01*
X1149673Y1610162D01*
X1151827D01*
X1153606Y1608383D01*
Y1554000D01*
X1150400Y1550800D01*
X1121992Y1535851D01*
X1112486Y1527034D01*
X1108506Y1517392D01*
X1107080Y1491760D01*
X1104774Y1467622D01*
X1102060Y1461910D01*
X1057700Y1416721D01*
X1019660Y1322820D01*
X998100Y1287660D01*
X991350Y1271485D01*
Y1254182D01*
X1002826Y1228404D01*
X1002825D01*
X1003353Y1228202D01*
X1004147Y1226419D01*
X1003944Y1225891D01*
X1003945D01*
X1004738Y1224110D01*
X1004737D01*
X1005265Y1223907D01*
X1006059Y1222125D01*
X1005856Y1221597D01*
X1006649Y1219816D01*
X1007177Y1219613D01*
X1007971Y1217831D01*
X1007768Y1217303D01*
X1009477Y1213464D01*
X1012574Y1210367D01*
X1013140D01*
X1014520Y1208987D01*
Y1208421D01*
X1015898Y1207043D01*
X1016463D01*
X1017843Y1205663D01*
Y1205098D01*
X1021830Y1201111D01*
X1040042Y1193566D01*
X1054300D01*
G01X1149173Y1607048D02*
Y1608552D01*
X1149673Y1609052D01*
X1151367D01*
X1152496Y1607923D01*
Y1554461D01*
X1149734Y1551705D01*
X1145943Y1549710D01*
X1145335Y1549899D01*
X1143608Y1548990D01*
X1143420Y1548382D01*
X1141695Y1547474D01*
X1141087Y1547663D01*
X1139360Y1546754D01*
X1139172Y1546146D01*
X1121345Y1536765D01*
X1111552Y1527683D01*
X1107408Y1517642D01*
X1105972Y1491844D01*
X1103687Y1467922D01*
X1101137Y1462555D01*
X1056753Y1417342D01*
X1018665Y1323322D01*
X997108Y1288167D01*
X990240Y1271708D01*
Y1253946D01*
X1008546Y1212824D01*
X1021201Y1200170D01*
X1039821Y1192456D01*
X1054300D01*
G01X1140511Y1616496D02*
Y1614992D01*
X1141011Y1614492D01*
X1143165D01*
X1144944Y1612713D01*
Y1558900D01*
X1143900Y1556300D01*
X1137100Y1549600D01*
X1120020Y1539262D01*
X1109425Y1529635D01*
X1104258Y1517972D01*
X1103000Y1491900D01*
X1100902Y1468983D01*
X1098135Y1463482D01*
X1054090Y1418633D01*
X1015989Y1324163D01*
X995295Y1290920D01*
X987150Y1272061D01*
Y1252342D01*
X989550Y1246972D01*
X990078Y1246770D01*
X990875Y1244988D01*
X990673Y1244460D01*
X991468Y1242680D01*
X991996Y1242478D01*
X992793Y1240697D01*
X992591Y1240168D01*
X993386Y1238388D01*
X993914Y1238186D01*
X994711Y1236405D01*
X994509Y1235876D01*
X999099Y1225604D01*
X999627Y1225402D01*
X1000424Y1223620D01*
X1000222Y1223092D01*
X1001017Y1221312D01*
X1001545Y1221110D01*
X1002342Y1219328D01*
X1002140Y1218800D01*
X1002935Y1217020D01*
X1003463Y1216818D01*
X1004260Y1215037D01*
X1004058Y1214509D01*
X1004992Y1212418D01*
X1019563Y1197847D01*
X1038922Y1189826D01*
X1054300D01*
G01Y1196196D02*
X1042413D01*
X1026391Y1202240D01*
X1012672Y1215958D01*
X1003815Y1235852D01*
X1001087Y1241004D01*
X994180Y1256995D01*
Y1270715D01*
X1000633Y1286223D01*
X1022405Y1321881D01*
X1060120Y1415190D01*
X1104797Y1460695D01*
X1107750Y1466678D01*
X1109992Y1491633D01*
X1111508Y1517029D01*
X1114962Y1525616D01*
X1122987Y1533087D01*
X1153132Y1549004D01*
X1161157Y1557059D01*
Y1612253D01*
X1160028Y1613382D01*
X1158334D01*
X1157834Y1612882D01*
Y1611378D01*
G01X1054300Y1197306D02*
X1042616D01*
X1027007Y1203194D01*
X1025423Y1204778D01*
Y1205343D01*
X1024043Y1206723D01*
X1023478D01*
X1022100Y1208101D01*
Y1208667D01*
X1020720Y1210047D01*
X1020154D01*
X1018776Y1211425D01*
Y1211991D01*
X1017396Y1213371D01*
X1016830D01*
X1013603Y1216598D01*
X1012810Y1218379D01*
X1013013Y1218907D01*
X1012219Y1220689D01*
X1011691Y1220892D01*
X1010898Y1222673D01*
X1011101Y1223201D01*
X1010307Y1224983D01*
X1009779Y1225186D01*
X1008986Y1226967D01*
X1009189Y1227495D01*
X1008395Y1229277D01*
X1007867Y1229480D01*
X1004814Y1236338D01*
X1002089Y1241485D01*
X995290Y1257225D01*
Y1270493D01*
X1001626Y1285717D01*
X1023400Y1321380D01*
X1061067Y1414570D01*
X1105714Y1460044D01*
X1108837Y1466372D01*
X1111100Y1491550D01*
X1112606Y1516782D01*
X1115900Y1524972D01*
X1123636Y1532174D01*
X1153800Y1548100D01*
X1162267Y1556600D01*
Y1612713D01*
X1160488Y1614492D01*
X1158334D01*
X1157834Y1614992D01*
Y1616496D01*
G01X1054476Y1199937D02*
X1043962D01*
X1029830Y1205058D01*
X1018130Y1216851D01*
X1004480Y1242637D01*
X997960Y1257728D01*
Y1269809D01*
X1004096Y1284549D01*
X1059556Y1341095D01*
X1061978Y1347947D01*
Y1409276D01*
X1063270Y1412461D01*
X1108081Y1458578D01*
X1111446Y1465227D01*
X1113832Y1491472D01*
X1115232Y1516141D01*
X1118117Y1523114D01*
X1124996Y1529660D01*
X1158055Y1547167D01*
X1158056Y1547166D01*
X1158243Y1547774D01*
X1159967Y1548688D01*
X1160575Y1548501D01*
X1162298Y1549413D01*
X1162485Y1550021D01*
X1164209Y1550935D01*
X1164817Y1550748D01*
X1166540Y1551660D01*
X1168756Y1553079D01*
X1169819Y1555077D01*
Y1607923D01*
X1168690Y1609052D01*
X1166996D01*
X1166496Y1608552D01*
Y1607048D01*
G01X1054476Y1201047D02*
X1044157D01*
X1030443Y1206018D01*
X1027962Y1208518D01*
X1027964Y1209084D01*
X1026590Y1210469D01*
X1026024Y1210471D01*
X1023031Y1213488D01*
X1023033Y1214053D01*
X1021659Y1215438D01*
X1021093Y1215441D01*
X1019034Y1217516D01*
X1017965Y1219537D01*
X1018131Y1220077D01*
X1017218Y1221802D01*
X1016677Y1221968D01*
Y1221969D01*
X1015765Y1223692D01*
X1015932Y1224232D01*
X1015018Y1225956D01*
X1014478Y1226122D01*
X1013566Y1227846D01*
X1013678Y1228209D01*
X1012642Y1230164D01*
X1012279Y1230276D01*
X1012280Y1230277D01*
X1011367Y1232001D01*
X1011485Y1232383D01*
X1010416Y1234402D01*
X1010033Y1234520D01*
X1005482Y1243117D01*
X999070Y1257958D01*
Y1269587D01*
X1005039Y1283924D01*
X1060521Y1340493D01*
X1063088Y1347756D01*
Y1409059D01*
X1064218Y1411842D01*
X1108996Y1457925D01*
X1112533Y1464915D01*
X1114940Y1491390D01*
X1116330Y1515890D01*
X1119053Y1522472D01*
X1125651Y1528750D01*
X1167100Y1550700D01*
X1169600Y1552300D01*
X1170929Y1554800D01*
Y1608383D01*
X1169150Y1610162D01*
X1166996D01*
X1166496Y1610662D01*
Y1612166D01*
G01X1175157Y1611378D02*
Y1612882D01*
X1175657Y1613382D01*
X1177351D01*
X1178480Y1612253D01*
Y1556780D01*
X1176754Y1553572D01*
X1170257Y1549276D01*
X1127255Y1526415D01*
X1121352Y1520832D01*
X1119122Y1515497D01*
X1117695Y1491389D01*
X1115114Y1463320D01*
X1111864Y1456814D01*
X1075186Y1411782D01*
X1074218Y1409059D01*
Y1347947D01*
X1073206Y1344984D01*
X1008064Y1281607D01*
X1005591Y1277989D01*
X1001750Y1268894D01*
Y1259130D01*
X1007413Y1245723D01*
X1024938Y1219913D01*
X1036757Y1207938D01*
X1046951Y1203677D01*
X1054300D01*
G01X1183818Y1607048D02*
Y1608552D01*
X1184318Y1609052D01*
X1186012D01*
X1187141Y1607923D01*
Y1554840D01*
X1185277Y1552852D01*
X1181937Y1550617D01*
X1181312Y1550740D01*
X1179691Y1549655D01*
X1179567Y1549031D01*
X1177947Y1547947D01*
X1177323Y1548071D01*
X1175701Y1546985D01*
X1175578Y1546361D01*
X1173044Y1544665D01*
X1129651Y1523419D01*
X1124456Y1518337D01*
X1122893Y1514527D01*
X1121780Y1490939D01*
X1119199Y1462545D01*
X1115669Y1454848D01*
X1087147Y1411713D01*
X1086458Y1409424D01*
Y1347000D01*
X1084518Y1343763D01*
X1084512Y1343754D01*
X1011172Y1279196D01*
X1009057Y1276238D01*
X1005560Y1267793D01*
Y1260910D01*
X1010979Y1247462D01*
X1043426Y1210251D01*
X1049658Y1207417D01*
X1054300D01*
G01X1183818Y1612166D02*
Y1610662D01*
X1184318Y1610162D01*
X1186472D01*
X1188251Y1608383D01*
Y1554400D01*
X1186000Y1552000D01*
X1173600Y1543700D01*
X1130300Y1522500D01*
X1125397Y1517703D01*
X1123993Y1514283D01*
X1122888Y1490863D01*
X1120288Y1462255D01*
X1116643Y1454307D01*
X1088163Y1411237D01*
X1087568Y1409260D01*
Y1346692D01*
X1085404Y1343059D01*
X1012002Y1278446D01*
X1010035Y1275695D01*
X1006670Y1267572D01*
Y1261126D01*
X1011939Y1248051D01*
X1015298Y1244199D01*
X1015863Y1244160D01*
X1017145Y1242690D01*
X1017107Y1242125D01*
X1018388Y1240656D01*
X1018952Y1240617D01*
X1020235Y1239146D01*
X1020196Y1238582D01*
X1027246Y1230498D01*
X1027810Y1230459D01*
X1029092Y1228989D01*
X1029054Y1228424D01*
X1030335Y1226955D01*
X1030899Y1226916D01*
X1032182Y1225446D01*
X1032143Y1224881D01*
X1033424Y1223412D01*
X1033988Y1223374D01*
X1035271Y1221903D01*
X1035232Y1221339D01*
X1044105Y1211163D01*
X1049899Y1208527D01*
X1054300D01*
G01X1175157Y1616496D02*
Y1614992D01*
X1175657Y1614492D01*
X1177811D01*
X1179590Y1612713D01*
Y1556500D01*
X1177600Y1552799D01*
X1170825Y1548320D01*
X1127909Y1525505D01*
X1122286Y1520186D01*
X1120219Y1515243D01*
X1118804Y1491324D01*
X1116201Y1463010D01*
X1112800Y1456200D01*
X1112797Y1456197D01*
X1112792Y1456195D01*
X1076168Y1411230D01*
X1075328Y1408867D01*
Y1347762D01*
X1074171Y1344374D01*
X1074157Y1344360D01*
X1008918Y1280889D01*
X1006570Y1277454D01*
X1002860Y1268669D01*
Y1259355D01*
X1008393Y1246256D01*
X1011209Y1242109D01*
X1011834Y1241989D01*
X1012931Y1240375D01*
X1012811Y1239750D01*
X1013906Y1238137D01*
X1013905D01*
X1014460Y1238031D01*
X1015557Y1236416D01*
X1015450Y1235861D01*
X1015451Y1235862D01*
X1016547Y1234249D01*
X1016545Y1234248D01*
X1017101Y1234142D01*
X1018197Y1232527D01*
X1018091Y1231972D01*
X1018092Y1231973D01*
X1019187Y1230360D01*
X1019186Y1230359D01*
X1019742Y1230253D01*
X1020838Y1228638D01*
X1020732Y1228084D01*
X1021828Y1226470D01*
X1021827D01*
X1022383Y1226364D01*
X1023479Y1224750D01*
X1023373Y1224194D01*
X1025800Y1220620D01*
X1028520Y1217864D01*
X1029086Y1217861D01*
X1030456Y1216472D01*
X1030453Y1215906D01*
X1037391Y1208877D01*
X1047174Y1204787D01*
X1054300D01*
G01X1192480Y1611378D02*
Y1612882D01*
X1192980Y1613382D01*
X1194674D01*
X1195803Y1612253D01*
Y1559321D01*
X1194358Y1555829D01*
X1188081Y1549552D01*
X1176880Y1541908D01*
X1130930Y1519300D01*
X1127987Y1516358D01*
X1126667Y1513718D01*
X1125493Y1488800D01*
X1122867Y1460761D01*
X1099217Y1411615D01*
X1098698Y1409334D01*
Y1346503D01*
X1097354Y1343279D01*
X1014155Y1276597D01*
Y1276596D01*
X1012207Y1273996D01*
X1009330Y1267045D01*
Y1262288D01*
X1014128Y1250691D01*
X1047240Y1212816D01*
X1051248Y1211157D01*
X1054476D01*
G01X1011187Y-33526D02*
X1012332Y-32381D01*
X1025082D01*
X1027018Y-34317D01*
X1029811Y-50148D01*
X1032069Y-51731D01*
X1036974Y-50864D01*
X1038557Y-48605D01*
X1033454Y-19661D01*
X1034508Y-18157D01*
X1038511Y-17450D01*
X1040015Y-18504D01*
X1045610Y-50231D01*
X1047867Y-51813D01*
X1052771Y-50945D01*
X1054355Y-48685D01*
X1049240Y-19675D01*
X1050294Y-18171D01*
X1054297Y-17464D01*
X1055801Y-18518D01*
X1061466Y-50638D01*
X1063724Y-52221D01*
X1068629Y-51354D01*
X1070212Y-49096D01*
X1065029Y-19700D01*
X1066083Y-18196D01*
X1070086Y-17489D01*
X1071590Y-18543D01*
X1077259Y-50699D01*
X1079520Y-52282D01*
X1084425Y-51415D01*
X1086008Y-49159D01*
X1080809Y-19674D01*
X1081863Y-18170D01*
X1085866Y-17463D01*
X1087370Y-18517D01*
X1093011Y-50512D01*
X1095270Y-52095D01*
X1100175Y-51228D01*
X1101758Y-48970D01*
X1096589Y-19655D01*
X1097643Y-18151D01*
X1101646Y-17444D01*
X1103150Y-18498D01*
X1108780Y-50429D01*
X1111039Y-52012D01*
X1115944Y-51145D01*
X1117527Y-48887D01*
X1112378Y-19686D01*
X1113432Y-18182D01*
X1117435Y-17475D01*
X1118940Y-18530D01*
X1124580Y-50517D01*
X1126839Y-52100D01*
X1131744Y-51233D01*
X1133327Y-48975D01*
X1128167Y-19712D01*
X1129221Y-18208D01*
X1133224Y-17501D01*
X1134729Y-18555D01*
X1140395Y-50692D01*
X1142654Y-52275D01*
X1147559Y-51408D01*
X1149142Y-49150D01*
X1143948Y-19691D01*
X1145002Y-18187D01*
X1149005Y-17480D01*
X1150509Y-18534D01*
X1156161Y-50590D01*
X1158420Y-52173D01*
X1163325Y-51306D01*
X1164908Y-49048D01*
X1159723Y-19637D01*
X1160777Y-18133D01*
X1164780Y-17426D01*
X1166284Y-18480D01*
X1171926Y-50480D01*
X1174185Y-52063D01*
X1179090Y-51196D01*
X1180673Y-48938D01*
X1175510Y-19656D01*
X1176564Y-18152D01*
X1180567Y-17445D01*
X1182071Y-18499D01*
X1187698Y-50415D01*
X1189957Y-51998D01*
X1194862Y-51131D01*
X1196446Y-48872D01*
X1191297Y-19682D01*
X1192351Y-18178D01*
X1196354Y-17471D01*
X1197860Y-18526D01*
X1203493Y-50475D01*
X1205752Y-52058D01*
X1210657Y-51191D01*
X1212240Y-48933D01*
X1207097Y-19765D01*
X1208151Y-18261D01*
X1212153Y-17554D01*
X1213659Y-18610D01*
X1215882Y-31216D01*
X1217690Y-32483D01*
X1229616D01*
X1230761Y-33628D01*
G01X1011187Y-30126D02*
X1012332Y-31271D01*
X1025542D01*
X1028051Y-33779D01*
X1030825Y-49502D01*
X1032329Y-50557D01*
X1036328Y-49850D01*
X1037383Y-48344D01*
X1032280Y-19400D01*
X1033862Y-17143D01*
X1038771Y-16276D01*
X1041029Y-17858D01*
X1046624Y-49585D01*
X1048127Y-50639D01*
X1052125Y-49932D01*
X1053181Y-48425D01*
X1048066Y-19414D01*
X1049648Y-17157D01*
X1054557Y-16290D01*
X1056815Y-17872D01*
X1062480Y-49992D01*
X1063984Y-51047D01*
X1067983Y-50340D01*
X1069038Y-48835D01*
X1063855Y-19439D01*
X1065437Y-17182D01*
X1070346Y-16315D01*
X1072604Y-17897D01*
X1078273Y-50053D01*
X1079780Y-51108D01*
X1083779Y-50401D01*
X1084834Y-48898D01*
X1079635Y-19413D01*
X1081217Y-17156D01*
X1086126Y-16289D01*
X1088384Y-17871D01*
X1094025Y-49866D01*
X1095530Y-50921D01*
X1099529Y-50214D01*
X1100584Y-48709D01*
X1095415Y-19394D01*
X1096997Y-17137D01*
X1101906Y-16270D01*
X1104164Y-17852D01*
X1109794Y-49783D01*
X1111299Y-50838D01*
X1115298Y-50131D01*
X1116353Y-48626D01*
X1111204Y-19425D01*
X1112786Y-17168D01*
X1117696Y-16301D01*
X1119954Y-17884D01*
X1125594Y-49871D01*
X1127099Y-50926D01*
X1131098Y-50219D01*
X1132153Y-48714D01*
X1126993Y-19451D01*
X1128575Y-17194D01*
X1133484Y-16327D01*
X1135743Y-17909D01*
X1141409Y-50046D01*
X1142914Y-51101D01*
X1146913Y-50394D01*
X1147968Y-48889D01*
X1142774Y-19430D01*
X1144356Y-17173D01*
X1149265Y-16306D01*
X1151523Y-17888D01*
X1157175Y-49944D01*
X1158680Y-50999D01*
X1162679Y-50292D01*
X1163734Y-48787D01*
X1158549Y-19376D01*
X1160131Y-17119D01*
X1165040Y-16252D01*
X1167298Y-17834D01*
X1172940Y-49834D01*
X1174445Y-50889D01*
X1178444Y-50182D01*
X1179499Y-48677D01*
X1174336Y-19395D01*
X1175918Y-17138D01*
X1180827Y-16271D01*
X1183085Y-17853D01*
X1188712Y-49769D01*
X1190217Y-50824D01*
X1194216Y-50117D01*
X1195272Y-48611D01*
X1190123Y-19422D01*
X1191705Y-17164D01*
X1196614Y-16297D01*
X1198874Y-17880D01*
X1204507Y-49829D01*
X1206012Y-50884D01*
X1210011Y-50177D01*
X1211066Y-48672D01*
X1205923Y-19504D01*
X1207505Y-17247D01*
X1212414Y-16380D01*
X1214673Y-17964D01*
X1216896Y-30570D01*
X1218041Y-31373D01*
X1229616D01*
X1230761Y-30228D01*
G01X1127153Y390995D02*
X1126008Y392140D01*
X1118472D01*
X1090972Y405889D01*
X1067844Y424258D01*
X1058225Y430639D01*
X1055644Y432970D01*
X1049193Y435594D01*
X1047329Y437502D01*
X1036303Y471034D01*
X1029913Y497475D01*
X1024465Y590306D01*
X1024469Y590377D01*
X1024470D01*
X1027121Y628237D01*
X1032064Y653821D01*
X1146590Y1063406D01*
Y1068999D01*
G01X1127153Y394395D02*
X1126008Y393250D01*
X1118735D01*
X1114162Y395536D01*
X1113961Y396140D01*
X1112216Y397013D01*
X1111612Y396812D01*
X1109868Y397683D01*
X1109667Y398287D01*
X1107922Y399160D01*
X1107318Y398959D01*
X1105574Y399830D01*
X1105373Y400434D01*
X1103628Y401307D01*
X1103024Y401106D01*
X1101280Y401977D01*
X1101079Y402581D01*
X1099334Y403454D01*
X1098730Y403253D01*
X1096986Y404124D01*
X1096785Y404728D01*
X1095040Y405601D01*
X1094436Y405400D01*
X1091572Y406831D01*
X1088735Y409084D01*
X1088662Y409717D01*
X1087134Y410930D01*
X1086502Y410858D01*
X1084976Y412070D01*
X1084903Y412703D01*
X1083375Y413916D01*
X1082743Y413844D01*
X1081216Y415056D01*
X1081144Y415688D01*
X1079616Y416902D01*
X1078984Y416830D01*
X1068497Y425157D01*
X1058908Y431518D01*
X1056243Y433925D01*
X1049826Y436535D01*
X1048304Y438094D01*
X1037372Y471339D01*
X1031016Y497639D01*
X1025578Y590300D01*
X1028224Y628092D01*
X1033146Y653566D01*
X1147700Y1063253D01*
Y1068999D01*
G01X1192480Y1616496D02*
Y1614992D01*
X1192980Y1614492D01*
X1195134D01*
X1196913Y1612713D01*
Y1559100D01*
X1195299Y1555200D01*
X1188793Y1548693D01*
X1177441Y1540946D01*
X1131585Y1518385D01*
X1128900Y1515700D01*
X1127765Y1513431D01*
X1126601Y1488722D01*
X1123954Y1460459D01*
X1100272Y1411247D01*
X1099808Y1409209D01*
Y1346280D01*
X1098270Y1342590D01*
X1014960Y1275818D01*
X1013179Y1273441D01*
Y1273442D01*
X1011811Y1270134D01*
X1011810D01*
X1010440Y1266824D01*
Y1262509D01*
X1015084Y1251284D01*
X1018187Y1247735D01*
X1018751Y1247697D01*
X1020036Y1246228D01*
X1019998Y1245664D01*
X1021281Y1244196D01*
X1021845Y1244158D01*
X1023130Y1242689D01*
X1023092Y1242125D01*
X1024375Y1240657D01*
X1024940Y1240619D01*
X1026224Y1239150D01*
X1026186Y1238585D01*
X1028075Y1236425D01*
Y1236424D01*
X1028639Y1236386D01*
X1029924Y1234917D01*
X1029886Y1234353D01*
X1031169Y1232885D01*
X1031733Y1232847D01*
X1033018Y1231378D01*
X1032980Y1230814D01*
X1034263Y1229346D01*
X1034828Y1229308D01*
X1036112Y1227839D01*
X1036074Y1227275D01*
X1047905Y1213743D01*
X1051469Y1212267D01*
X1054476D01*
G01X1119853Y398082D02*
X1118708Y399227D01*
X1116772D01*
X1116626Y399373D01*
X1090244Y414426D01*
X1045410Y461192D01*
X1040015Y471867D01*
X1034098Y498317D01*
X1028485Y591264D01*
X1030729Y625484D01*
X1035433Y651241D01*
X1150330Y1062754D01*
Y1069176D01*
G01X1119853Y401482D02*
X1118708Y400337D01*
X1117177D01*
X1115484Y401303D01*
X1115316Y401917D01*
X1113621Y402884D01*
X1113007Y402716D01*
X1111314Y403682D01*
X1111146Y404296D01*
X1109451Y405263D01*
X1108838Y405095D01*
X1107145Y406061D01*
X1106977Y406675D01*
X1105282Y407642D01*
X1104669Y407474D01*
X1102976Y408440D01*
X1102808Y409054D01*
X1101113Y410021D01*
X1100499Y409853D01*
X1096428Y412176D01*
X1096260Y412790D01*
X1094566Y413757D01*
X1093952Y413589D01*
X1090935Y415311D01*
X1087012Y419403D01*
X1087025Y420039D01*
X1085675Y421448D01*
X1085038Y421461D01*
X1083689Y422868D01*
X1083702Y423504D01*
X1082352Y424913D01*
X1081716Y424926D01*
X1080367Y426333D01*
X1080380Y426969D01*
X1079030Y428378D01*
X1078394Y428391D01*
X1046326Y461841D01*
X1041069Y472245D01*
X1035201Y498473D01*
X1029598Y591261D01*
X1031833Y625347D01*
X1036516Y650992D01*
X1151440Y1062601D01*
Y1069176D01*
G01X1127153Y408568D02*
X1126008Y407423D01*
X1118894D01*
X1114683Y409584D01*
Y409583D01*
X1114489Y410189D01*
X1112753Y411081D01*
X1112147Y410886D01*
X1110413Y411776D01*
X1110218Y412382D01*
X1108482Y413273D01*
X1107876Y413078D01*
X1106142Y413968D01*
X1105947Y414574D01*
X1104211Y415465D01*
X1103605Y415270D01*
X1101871Y416160D01*
X1101676Y416765D01*
X1099940Y417657D01*
X1099334Y417462D01*
X1097599Y418352D01*
X1097405Y418957D01*
X1095668Y419848D01*
X1095063Y419653D01*
X1090954Y421761D01*
X1089112Y423690D01*
X1089127Y424327D01*
X1087779Y425738D01*
X1087143Y425753D01*
X1085797Y427163D01*
X1085812Y427799D01*
X1084464Y429210D01*
X1083828Y429225D01*
X1082482Y430635D01*
X1082497Y431271D01*
X1081149Y432682D01*
X1080513Y432697D01*
X1048318Y466417D01*
X1044544Y474280D01*
X1040103Y498574D01*
X1033797Y591896D01*
X1035992Y625030D01*
X1040408Y650559D01*
X1155180Y1061946D01*
Y1069000D01*
G01X1127153Y405168D02*
X1126008Y406313D01*
X1118625D01*
X1090280Y420858D01*
X1047393Y465777D01*
X1043478Y473934D01*
X1038999Y498436D01*
X1032684Y591895D01*
X1033786Y608536D01*
X1034888Y625162D01*
X1039323Y650804D01*
X1154070Y1062098D01*
Y1069000D01*
G01X1119853Y412255D02*
X1118708Y413400D01*
X1116548D01*
X1091474Y426947D01*
X1074244Y443630D01*
X1061797Y469148D01*
X1056634Y475434D01*
X1048619Y479749D01*
X1045683Y483320D01*
X1043007Y497447D01*
X1036695Y592455D01*
X1037734Y608768D01*
X1037735D01*
X1038252Y616889D01*
X1038251D01*
X1038252Y616890D01*
X1038774Y625071D01*
X1043110Y650325D01*
X1157810Y1061136D01*
Y1069177D01*
G01X1119853Y415655D02*
X1118708Y414510D01*
X1116829D01*
X1115114Y415436D01*
X1114932Y416046D01*
X1113215Y416974D01*
X1112606Y416792D01*
X1110891Y417718D01*
X1110709Y418328D01*
X1108992Y419256D01*
X1108383Y419074D01*
X1106668Y420000D01*
X1106486Y420610D01*
X1104769Y421538D01*
X1104160Y421356D01*
X1102445Y422282D01*
X1102263Y422892D01*
X1100546Y423820D01*
X1099936Y423638D01*
X1098221Y424564D01*
X1098039Y425174D01*
X1096322Y426102D01*
X1095713Y425920D01*
X1092137Y427852D01*
X1088543Y431331D01*
X1088533Y431967D01*
X1087131Y433325D01*
X1086495Y433315D01*
X1085094Y434671D01*
X1085084Y435307D01*
X1083682Y436665D01*
X1083046Y436654D01*
X1081645Y438010D01*
X1081635Y438646D01*
X1080233Y440004D01*
X1079597Y439993D01*
X1075157Y444292D01*
X1062738Y469752D01*
X1057353Y476308D01*
X1049338Y480623D01*
X1046721Y483806D01*
X1044111Y497588D01*
X1040961Y545023D01*
X1040959Y545024D01*
X1037808Y592456D01*
X1039878Y624941D01*
X1044195Y650081D01*
X1158920Y1060983D01*
Y1069177D01*
G01X1127153Y419341D02*
X1126008Y420486D01*
X1117281D01*
X1088633Y435738D01*
X1078279Y445743D01*
X1074981Y451562D01*
X1068100Y481096D01*
X1065485Y484085D01*
X1058526Y486769D01*
X1058333Y487152D01*
X1058334D01*
X1046996Y509734D01*
X1040538Y592559D01*
X1041564Y608789D01*
X1042589Y625001D01*
X1046626Y648527D01*
X1161551Y1060437D01*
Y1069000D01*
G01X1127153Y422741D02*
X1126008Y421596D01*
X1117559D01*
X1115838Y422512D01*
X1115652Y423121D01*
X1113930Y424038D01*
X1113322Y423852D01*
X1111601Y424768D01*
X1111415Y425377D01*
X1109693Y426294D01*
X1109085Y426108D01*
X1107364Y427024D01*
X1107178Y427633D01*
X1105456Y428550D01*
X1104847Y428364D01*
X1103126Y429280D01*
X1102940Y429889D01*
X1101218Y430806D01*
X1100610Y430620D01*
X1098889Y431536D01*
X1098703Y432144D01*
X1096981Y433062D01*
X1096372Y432876D01*
X1094651Y433792D01*
X1094465Y434401D01*
X1092743Y435318D01*
X1092134Y435132D01*
X1089292Y436645D01*
X1087890Y438000D01*
X1087879Y438636D01*
X1086476Y439992D01*
X1085840Y439981D01*
X1084438Y441336D01*
X1084427Y441972D01*
X1083024Y443328D01*
X1082388Y443317D01*
X1079166Y446430D01*
X1076026Y451970D01*
X1069119Y481619D01*
X1066141Y485023D01*
X1059326Y487651D01*
X1048086Y510037D01*
X1041651Y592567D01*
X1043694Y624872D01*
X1047711Y648283D01*
X1162661Y1060285D01*
Y1069000D01*
G01X1119853Y426428D02*
X1118708Y427573D01*
X1117005D01*
X1116855Y427723D01*
X1081704Y447664D01*
X1081283Y448073D01*
X1078524Y452977D01*
X1070208Y489303D01*
X1056972Y520124D01*
Y536942D01*
X1052309Y549858D01*
X1044454Y593180D01*
X1044462Y593314D01*
X1044463D01*
X1046374Y624190D01*
X1050535Y648314D01*
X1165291Y1059776D01*
Y1069176D01*
G01X1119853Y429828D02*
X1118708Y428683D01*
X1117398D01*
X1117402Y428687D01*
Y428689D01*
X1115326Y429867D01*
X1115157Y430480D01*
X1113459Y431443D01*
X1112846Y431274D01*
X1111150Y432236D01*
X1110981Y432849D01*
X1109284Y433812D01*
X1108671Y433643D01*
X1106134Y435082D01*
X1105965Y435695D01*
X1104268Y436658D01*
X1103655Y436489D01*
X1101959Y437451D01*
X1101790Y438064D01*
X1100093Y439027D01*
X1099479Y438858D01*
X1082376Y448560D01*
X1082172Y448758D01*
X1079571Y453382D01*
X1071268Y489649D01*
X1067330Y498819D01*
X1067566Y499410D01*
X1066797Y501203D01*
X1066205Y501439D01*
X1065436Y503230D01*
X1065672Y503821D01*
X1064903Y505614D01*
X1064311Y505850D01*
X1063542Y507641D01*
X1063778Y508232D01*
X1063008Y510025D01*
X1062416Y510261D01*
X1061647Y512052D01*
X1061883Y512643D01*
X1061114Y514436D01*
X1060522Y514672D01*
X1058082Y520353D01*
Y537137D01*
X1053385Y550147D01*
X1045571Y593246D01*
X1047479Y624061D01*
X1051620Y648070D01*
X1166401Y1059624D01*
Y1069176D01*
G01X1119853Y440602D02*
X1118708Y441747D01*
X1116009D01*
X1099283Y448587D01*
X1096132Y451593D01*
X1093727Y456762D01*
X1091138Y460481D01*
X1083833Y476186D01*
X1077345Y505391D01*
X1071585Y540921D01*
X1063751Y555079D01*
X1056715Y571121D01*
X1054498Y583211D01*
Y583212D01*
X1052279Y595311D01*
X1053196Y609377D01*
X1054108Y623365D01*
X1057993Y646036D01*
X1172771Y1057515D01*
Y1069177D01*
G01X1119853Y444002D02*
X1118708Y442857D01*
X1116228D01*
X1114424Y443595D01*
X1114177Y444183D01*
X1112372Y444921D01*
X1111785Y444675D01*
X1109981Y445413D01*
X1109734Y446000D01*
X1107928Y446738D01*
X1107342Y446492D01*
X1099898Y449536D01*
X1097051Y452252D01*
X1094694Y457318D01*
X1092105Y461037D01*
X1088943Y467834D01*
X1089161Y468432D01*
X1088338Y470201D01*
X1087740Y470419D01*
X1086918Y472187D01*
X1087136Y472784D01*
X1086313Y474554D01*
X1085715Y474772D01*
X1084891Y476545D01*
X1084373Y478878D01*
X1084715Y479415D01*
X1084292Y481320D01*
X1083754Y481661D01*
X1083332Y483564D01*
X1083673Y484101D01*
X1083250Y486006D01*
X1082713Y486347D01*
X1082291Y488250D01*
X1082632Y488787D01*
X1082209Y490692D01*
X1081672Y491033D01*
X1081250Y492936D01*
X1081591Y493473D01*
X1081168Y495378D01*
X1080631Y495719D01*
X1078436Y505600D01*
X1072650Y541289D01*
X1064747Y555572D01*
X1057784Y571449D01*
X1053396Y595376D01*
X1055212Y623235D01*
X1059078Y645792D01*
X1173881Y1057363D01*
Y1069177D01*
G01X1127153Y436915D02*
X1126008Y435770D01*
X1123078D01*
X1122628Y436220D01*
X1120678D01*
X1120228Y435770D01*
X1118278D01*
X1116473Y436505D01*
X1116225Y437092D01*
X1114418Y437828D01*
X1113832Y437581D01*
X1112026Y438316D01*
X1111779Y438903D01*
X1109972Y439639D01*
X1109386Y439392D01*
X1107580Y440127D01*
X1107333Y440714D01*
X1105526Y441449D01*
X1104940Y441202D01*
X1102037Y442383D01*
X1097841Y445179D01*
X1097716Y445803D01*
X1096092Y446885D01*
X1095468Y446760D01*
X1093846Y447841D01*
X1093721Y448465D01*
X1092097Y449547D01*
X1091473Y449422D01*
X1089851Y450503D01*
X1088896Y450900D01*
X1087141D01*
X1085125Y451830D01*
X1084079Y453057D01*
X1082964Y455447D01*
X1080066Y472653D01*
X1080435Y473172D01*
X1080111Y475096D01*
X1079591Y475465D01*
X1079268Y477387D01*
X1079637Y477906D01*
X1079313Y479830D01*
X1078794Y480199D01*
X1068816Y539431D01*
X1061122Y553992D01*
X1053763Y570377D01*
X1049448Y594648D01*
X1051241Y623507D01*
X1055512Y647319D01*
X1170141Y1058216D01*
Y1069000D01*
G01X1127153Y433515D02*
X1126008Y434660D01*
X1118060D01*
X1101514Y441396D01*
X1089325Y449519D01*
X1088674Y449790D01*
X1086896D01*
X1084438Y450923D01*
X1083136Y452451D01*
X1081894Y455114D01*
X1067751Y539070D01*
X1060123Y553504D01*
X1052693Y570047D01*
X1048355Y594454D01*
X1048354D01*
X1048331Y594584D01*
X1050137Y623640D01*
X1054428Y647567D01*
X1169031Y1058368D01*
Y1069000D01*
G01X1127153Y469381D02*
X1126008Y470526D01*
X1119122D01*
X1111071Y473033D01*
X1088962Y494002D01*
X1082575Y503906D01*
X1081187Y507516D01*
X1075602Y541787D01*
X1068892Y553631D01*
X1060815Y571525D01*
X1056169Y596701D01*
X1057885Y622860D01*
X1061837Y645427D01*
X1176511Y1056771D01*
Y1069000D01*
G01X1127153Y472781D02*
X1126008Y471636D01*
X1119291D01*
X1111648Y474016D01*
X1106314Y479075D01*
X1106297Y479711D01*
X1104881Y481054D01*
X1104245Y481038D01*
X1102831Y482379D01*
X1102814Y483016D01*
X1101398Y484358D01*
X1100762Y484342D01*
X1099348Y485683D01*
X1099331Y486320D01*
X1097915Y487662D01*
X1097279Y487645D01*
X1095865Y488986D01*
X1095848Y489623D01*
X1094432Y490965D01*
X1093796Y490949D01*
X1089823Y494716D01*
X1088767Y496354D01*
X1088901Y496976D01*
X1087843Y498616D01*
X1087221Y498751D01*
X1083571Y504412D01*
X1082265Y507808D01*
X1076666Y542161D01*
X1075428Y544347D01*
X1075597Y544960D01*
X1074635Y546658D01*
X1074022Y546828D01*
X1073061Y548524D01*
X1073231Y549137D01*
X1072269Y550835D01*
X1071656Y551005D01*
X1069883Y554134D01*
X1068769Y556602D01*
X1068994Y557198D01*
X1068192Y558976D01*
X1067596Y559201D01*
X1061883Y571859D01*
X1057286Y596766D01*
X1058989Y622728D01*
X1062922Y645181D01*
X1177621Y1056619D01*
Y1069000D01*
G01X1054615Y1214897D02*
X1051233D01*
X1046894Y1219236D01*
X1046295Y1220682D01*
Y1223583D01*
X1046085Y1228476D01*
Y1243849D01*
X1046780Y1246702D01*
Y1246704D01*
X1050590Y1262358D01*
Y1281498D01*
X1057137Y1297039D01*
X1069338Y1310897D01*
X1069356Y1310894D01*
X1069362Y1310899D01*
X1100505Y1335568D01*
X1100562Y1336060D01*
X1102092Y1337272D01*
X1102584Y1337215D01*
X1109467Y1342667D01*
X1110938Y1346639D01*
Y1409881D01*
X1130369Y1443268D01*
X1130225Y1443815D01*
X1131206Y1445501D01*
X1131753Y1445646D01*
X1135173Y1451522D01*
Y1505561D01*
X1134044Y1506690D01*
X1132350D01*
X1131850Y1506190D01*
Y1504685D01*
G01X1054615Y1216007D02*
X1051693D01*
X1047835Y1219865D01*
X1047405Y1220903D01*
Y1223607D01*
X1047195Y1228500D01*
Y1230775D01*
X1047645Y1231225D01*
Y1233175D01*
X1047195Y1233625D01*
Y1236415D01*
X1047700Y1236920D01*
Y1238660D01*
X1047195Y1239165D01*
Y1243715D01*
X1047859Y1246440D01*
X1048403Y1246771D01*
X1048864Y1248667D01*
X1048533Y1249210D01*
X1049555Y1253411D01*
X1050039Y1253706D01*
X1050500Y1255601D01*
X1050206Y1256084D01*
X1051700Y1262224D01*
Y1281273D01*
X1058090Y1296441D01*
X1070052Y1310028D01*
X1110400Y1341990D01*
X1112048Y1346440D01*
Y1409581D01*
X1136283Y1451222D01*
Y1506021D01*
X1134504Y1507800D01*
X1132350D01*
X1131850Y1508300D01*
Y1509804D01*
G01X1056625Y1223375D02*
X1052390Y1227610D01*
Y1251265D01*
X1054570Y1261910D01*
Y1280799D01*
X1060281Y1294351D01*
X1071103Y1306978D01*
X1103888Y1329097D01*
X1103996Y1329652D01*
X1105613Y1330744D01*
X1106169Y1330636D01*
X1121116Y1340720D01*
X1123178Y1345855D01*
Y1409919D01*
X1126121Y1415896D01*
X1125916Y1416499D01*
X1126778Y1418249D01*
X1127381Y1418454D01*
X1127380Y1418455D01*
X1128241Y1420203D01*
X1128242D01*
X1128037Y1420805D01*
X1128899Y1422556D01*
X1129502Y1422761D01*
X1129501Y1422762D01*
X1140028Y1444143D01*
X1140029D01*
X1139824Y1444745D01*
X1140686Y1446496D01*
X1141289Y1446701D01*
X1141288D01*
X1143834Y1451871D01*
Y1509891D01*
X1142705Y1511020D01*
X1141011D01*
X1140511Y1510520D01*
Y1509016D01*
G01X1057410Y1224160D02*
X1053500Y1228070D01*
Y1251152D01*
X1055680Y1261797D01*
Y1280574D01*
X1061237Y1293760D01*
X1071849Y1306141D01*
X1122020Y1339990D01*
X1124288Y1345640D01*
Y1409660D01*
X1144944Y1451612D01*
Y1510351D01*
X1143165Y1512130D01*
X1141011D01*
X1140511Y1512630D01*
Y1514134D01*
G01X1119853Y476468D02*
X1118708Y477613D01*
X1117844D01*
X1110974Y480353D01*
X1094395Y495401D01*
X1086146Y505743D01*
X1085404Y507433D01*
X1079219Y543036D01*
X1073918Y561559D01*
X1064911Y573178D01*
X1063192Y579791D01*
X1063202Y579966D01*
X1063203D01*
X1065605Y619118D01*
X1069312Y639472D01*
X1180251Y1055410D01*
Y1069176D01*
G01X1127153Y486954D02*
X1126008Y485809D01*
X1123301D01*
X1122851Y486259D01*
X1120901D01*
X1120451Y485809D01*
X1118501D01*
X1115262Y487807D01*
X1115116Y488426D01*
X1113455Y489451D01*
X1112836Y489304D01*
X1111177Y490327D01*
X1111030Y490946D01*
X1109369Y491971D01*
X1108750Y491824D01*
X1107091Y492847D01*
X1106944Y493467D01*
X1105283Y494491D01*
X1104664Y494345D01*
X1101452Y496326D01*
X1098817Y498670D01*
X1096355Y501786D01*
Y501787D01*
X1096429Y502419D01*
X1095219Y503950D01*
X1094587Y504024D01*
X1093378Y505553D01*
X1093452Y506185D01*
X1092242Y507716D01*
X1091610Y507790D01*
X1090401Y509319D01*
X1089846Y510544D01*
X1089340Y513477D01*
X1089707Y513997D01*
X1089375Y515920D01*
X1088854Y516287D01*
X1088855D01*
X1088524Y518208D01*
X1088891Y518728D01*
X1088559Y520651D01*
X1088038Y521018D01*
X1083284Y548553D01*
X1079194Y562670D01*
X1069347Y575889D01*
X1068152Y580447D01*
X1070693Y619624D01*
X1073886Y637337D01*
X1185102Y1054699D01*
Y1069000D01*
G01X1119853Y479868D02*
X1118708Y478723D01*
X1118058D01*
X1116031Y479531D01*
X1115780Y480117D01*
X1113967Y480839D01*
X1113383Y480588D01*
X1111572Y481310D01*
X1110129Y482620D01*
X1110098Y483256D01*
X1108653Y484567D01*
X1108017Y484537D01*
X1106574Y485847D01*
X1106543Y486483D01*
X1105098Y487794D01*
X1104462Y487764D01*
X1103019Y489074D01*
X1102988Y489710D01*
X1101543Y491021D01*
X1100907Y490991D01*
X1099464Y492301D01*
X1099433Y492937D01*
X1097988Y494248D01*
X1097352Y494218D01*
X1095208Y496164D01*
X1093992Y497688D01*
X1094064Y498320D01*
X1092847Y499846D01*
X1092214Y499917D01*
X1090999Y501441D01*
X1091070Y502073D01*
X1089853Y503599D01*
X1089220Y503670D01*
X1087105Y506322D01*
X1086475Y507756D01*
X1080303Y543285D01*
X1076460Y556714D01*
X1076769Y557270D01*
X1076233Y559146D01*
X1075675Y559455D01*
X1074927Y562071D01*
X1065928Y573678D01*
X1064311Y579899D01*
X1066709Y618984D01*
X1070397Y639229D01*
X1181361Y1055264D01*
Y1069176D01*
G01X1127153Y483554D02*
X1126008Y484699D01*
X1118186D01*
X1100786Y495431D01*
X1098006Y497905D01*
X1089446Y508737D01*
X1088776Y510215D01*
X1082200Y548303D01*
X1078183Y562168D01*
X1068327Y575398D01*
X1067032Y580339D01*
X1069589Y619759D01*
X1072801Y637579D01*
X1183992Y1054845D01*
Y1069000D01*
G01X1119853Y490641D02*
X1118708Y491786D01*
X1116964D01*
X1114840Y493910D01*
X1112958Y498454D01*
Y504855D01*
X1111193Y509079D01*
X1111192Y509081D01*
X1109080Y514137D01*
X1104020Y521623D01*
X1101939Y526043D01*
X1101938Y526045D01*
X1098930Y532434D01*
X1092693Y552957D01*
X1092694D01*
X1092096Y554923D01*
X1083470Y562765D01*
X1079609Y566576D01*
X1071914Y576902D01*
X1070851Y580951D01*
X1070862Y581130D01*
X1070863D01*
X1073261Y618273D01*
X1076312Y635490D01*
X1187731Y1054274D01*
Y1069177D01*
G01X1119853Y494041D02*
X1118708Y492896D01*
X1117424D01*
X1115781Y494539D01*
X1114068Y498675D01*
Y505078D01*
X1113317Y506877D01*
X1113559Y507465D01*
X1112807Y509266D01*
X1112217Y509508D01*
X1110062Y514667D01*
X1108971Y516282D01*
X1109092Y516907D01*
X1107999Y518524D01*
X1107374Y518645D01*
X1104989Y522174D01*
X1104159Y523938D01*
X1104374Y524536D01*
X1103542Y526302D01*
X1102943Y526517D01*
X1102113Y528281D01*
X1102328Y528880D01*
X1101497Y530645D01*
X1100898Y530860D01*
X1099969Y532834D01*
X1098639Y537213D01*
X1098939Y537774D01*
X1098372Y539641D01*
X1097809Y539941D01*
X1097243Y541806D01*
X1097542Y542368D01*
X1096976Y544234D01*
X1096413Y544534D01*
X1096414D01*
X1095847Y546399D01*
X1096147Y546961D01*
X1095580Y548828D01*
X1095017Y549127D01*
X1095019D01*
X1094452Y550992D01*
X1094752Y551554D01*
X1094185Y553420D01*
X1093623Y553720D01*
X1093071Y555538D01*
X1084234Y563571D01*
X1080449Y567307D01*
X1072934Y577393D01*
X1071971Y581059D01*
X1074365Y618140D01*
X1077397Y635250D01*
X1188841Y1054128D01*
Y1069177D01*
G01X1127153Y513515D02*
X1126008Y514660D01*
X1115287D01*
X1107357Y524319D01*
X1103797Y532914D01*
X1103796Y532915D01*
X1102026Y537191D01*
Y552332D01*
X1101324Y554029D01*
X1097896Y557457D01*
X1086583Y565017D01*
X1082170Y569433D01*
X1075411Y578558D01*
X1074644Y581320D01*
X1077000Y617819D01*
X1079985Y634660D01*
X1191472Y1053710D01*
Y1069000D01*
G01X1071787Y1260012D02*
Y1281322D01*
X1072859Y1284120D01*
X1080253Y1292967D01*
X1091032Y1300270D01*
X1168926Y1342541D01*
X1170971Y1344920D01*
X1172138Y1348142D01*
Y1416101D01*
X1175664Y1435925D01*
X1175300Y1436447D01*
X1175641Y1438367D01*
X1176164Y1438732D01*
X1176505Y1440651D01*
X1176141Y1441173D01*
X1176483Y1443094D01*
X1177006Y1443458D01*
X1177005D01*
X1178480Y1451747D01*
Y1509891D01*
X1177351Y1511020D01*
X1175657D01*
X1175157Y1510520D01*
Y1509016D01*
G01X1065417Y1260012D02*
Y1282968D01*
X1067101Y1287611D01*
X1076455Y1298741D01*
X1081704Y1302261D01*
Y1302260D01*
X1086950Y1305779D01*
X1135414Y1332816D01*
X1135890Y1332681D01*
X1137594Y1333632D01*
X1137730Y1334108D01*
X1139432Y1335058D01*
X1139909Y1334923D01*
X1141612Y1335874D01*
X1141748Y1336350D01*
X1143450Y1337300D01*
X1147310Y1342670D01*
X1148768Y1346480D01*
Y1409700D01*
X1162267Y1451773D01*
Y1510351D01*
X1160488Y1512130D01*
X1158334D01*
X1157834Y1512630D01*
Y1514134D01*
G01X1149173Y1504685D02*
Y1506190D01*
X1149673Y1506690D01*
X1151367D01*
X1152496Y1505561D01*
Y1451500D01*
X1150819Y1447405D01*
X1150820D01*
X1150232Y1447159D01*
X1149493Y1445353D01*
X1149739Y1444766D01*
X1149001Y1442962D01*
X1148413Y1442716D01*
X1147674Y1440910D01*
X1147920Y1440323D01*
X1147919D01*
X1147180Y1438522D01*
X1147182Y1438519D01*
X1146594Y1438273D01*
X1145855Y1436467D01*
X1146101Y1435880D01*
X1146100Y1435881D01*
X1142291Y1426578D01*
X1142293D01*
X1141836Y1426387D01*
X1141096Y1424582D01*
X1141287Y1424125D01*
X1140549Y1422321D01*
X1139961Y1422075D01*
X1139222Y1420269D01*
X1139468Y1419682D01*
X1138730Y1417878D01*
X1138142Y1417632D01*
X1137403Y1415826D01*
X1137649Y1415239D01*
X1135418Y1409790D01*
Y1347440D01*
X1134163Y1343463D01*
X1084475Y1310637D01*
X1073477Y1303105D01*
X1073377Y1302990D01*
Y1302989D01*
X1073367Y1302977D01*
X1073357Y1302966D01*
X1073352Y1302959D01*
X1063261Y1291326D01*
X1060566Y1284717D01*
Y1256512D01*
G01X1166496Y1509804D02*
Y1508300D01*
X1166996Y1507800D01*
X1169150D01*
X1170929Y1506021D01*
Y1451669D01*
X1161008Y1409469D01*
Y1346410D01*
X1159410Y1343270D01*
X1156006Y1339225D01*
X1088913Y1302216D01*
X1078430Y1295060D01*
X1070540Y1285720D01*
X1069157Y1282008D01*
Y1260012D01*
G01X1072897D02*
Y1281116D01*
X1073830Y1283550D01*
X1081005Y1292135D01*
X1091609Y1299320D01*
X1164868Y1339075D01*
X1165343Y1338934D01*
X1167058Y1339865D01*
X1167198Y1340340D01*
X1169635Y1341662D01*
X1171946Y1344350D01*
X1173248Y1347947D01*
Y1416003D01*
X1179590Y1451649D01*
Y1510351D01*
X1177811Y1512130D01*
X1175657D01*
X1175157Y1512630D01*
Y1514134D01*
G01X1061676Y1256512D02*
Y1284499D01*
X1064220Y1290737D01*
X1074191Y1302232D01*
X1074196Y1302238D01*
X1074205Y1302248D01*
X1074213Y1302258D01*
X1074223Y1302269D01*
X1085087Y1309710D01*
X1135104Y1342753D01*
X1136528Y1347269D01*
Y1409571D01*
X1153606Y1451281D01*
Y1506021D01*
X1151827Y1507800D01*
X1149673D01*
X1149173Y1508300D01*
Y1509804D01*
G01X1166496Y1504685D02*
Y1506190D01*
X1166996Y1506690D01*
X1168690D01*
X1169819Y1505561D01*
Y1451798D01*
X1167751Y1443003D01*
X1167752D01*
X1167330Y1442742D01*
X1166884Y1440843D01*
X1167144Y1440422D01*
X1166698Y1438524D01*
X1166276Y1438264D01*
X1165830Y1436364D01*
X1166091Y1435944D01*
X1165645Y1434046D01*
X1165223Y1433786D01*
X1164777Y1431886D01*
X1165038Y1431466D01*
X1159898Y1409598D01*
Y1346677D01*
X1158478Y1343888D01*
X1155289Y1340098D01*
X1088330Y1303163D01*
X1077679Y1295892D01*
X1069567Y1286289D01*
X1068047Y1282209D01*
Y1260012D01*
G01X1157834Y1509016D02*
Y1510520D01*
X1158334Y1511020D01*
X1160028D01*
X1161157Y1509891D01*
Y1451947D01*
X1158348Y1443193D01*
X1158349D01*
X1157782Y1442902D01*
X1157186Y1441044D01*
X1157477Y1440478D01*
X1157476D01*
X1156881Y1438622D01*
X1156882D01*
X1156315Y1438331D01*
X1155719Y1436473D01*
X1156010Y1435907D01*
X1150928Y1420067D01*
X1150929D01*
X1150362Y1419776D01*
X1149766Y1417918D01*
X1150057Y1417352D01*
X1147658Y1409874D01*
Y1346686D01*
X1146324Y1343202D01*
X1142693Y1338149D01*
X1086369Y1306727D01*
X1075706Y1299576D01*
X1066124Y1288175D01*
X1064307Y1283164D01*
Y1260012D01*
G01X1081187Y-72706D02*
X1082332Y-71561D01*
X1097202D01*
X1097745Y-72016D01*
X1100162Y-85726D01*
X1102421Y-87309D01*
X1107326Y-86442D01*
X1108909Y-84184D01*
X1105041Y-62245D01*
X1106095Y-60741D01*
X1110099Y-60034D01*
X1111603Y-61089D01*
X1115962Y-85814D01*
X1118221Y-87397D01*
X1123126Y-86530D01*
X1124709Y-84272D01*
X1120822Y-62225D01*
X1121876Y-60721D01*
X1125879Y-60014D01*
X1127383Y-61068D01*
X1131777Y-85989D01*
X1134036Y-87572D01*
X1138941Y-86705D01*
X1140524Y-84447D01*
X1136606Y-62222D01*
X1137660Y-60718D01*
X1141663Y-60011D01*
X1143167Y-61065D01*
X1147543Y-85887D01*
X1149802Y-87470D01*
X1154707Y-86603D01*
X1156290Y-84344D01*
X1152390Y-62219D01*
X1153444Y-60715D01*
X1157447Y-60008D01*
X1158951Y-61062D01*
X1163317Y-85826D01*
X1165575Y-87409D01*
X1170480Y-86542D01*
X1172063Y-84283D01*
X1168172Y-62210D01*
X1169226Y-60706D01*
X1173229Y-59999D01*
X1174733Y-61053D01*
X1179098Y-85809D01*
X1181356Y-87392D01*
X1186261Y-86525D01*
X1187845Y-84266D01*
X1183957Y-62225D01*
X1185011Y-60721D01*
X1189014Y-60014D01*
X1190520Y-61069D01*
X1194892Y-85869D01*
X1197151Y-87452D01*
X1202056Y-86585D01*
X1203639Y-84327D01*
X1199739Y-62210D01*
X1200793Y-60706D01*
X1204795Y-59999D01*
X1206301Y-61055D01*
X1207926Y-70266D01*
X1209734Y-71533D01*
X1224260D01*
X1225405Y-72678D01*
G01X1081187Y-69306D02*
X1082332Y-70451D01*
X1097606D01*
X1098768Y-71425D01*
X1101176Y-85080D01*
X1102681Y-86135D01*
X1106680Y-85428D01*
X1107735Y-83923D01*
X1103867Y-61984D01*
X1105449Y-59727D01*
X1110360Y-58860D01*
X1112617Y-60443D01*
X1116976Y-85168D01*
X1118481Y-86223D01*
X1122480Y-85516D01*
X1123535Y-84011D01*
X1119648Y-61964D01*
X1121230Y-59707D01*
X1126139Y-58840D01*
X1128397Y-60422D01*
X1132791Y-85343D01*
X1134296Y-86398D01*
X1138295Y-85691D01*
X1139350Y-84186D01*
X1135432Y-61961D01*
X1137014Y-59704D01*
X1141923Y-58837D01*
X1144181Y-60419D01*
X1148557Y-85241D01*
X1150062Y-86296D01*
X1154061Y-85589D01*
X1155116Y-84083D01*
X1151216Y-61958D01*
X1152798Y-59701D01*
X1157707Y-58834D01*
X1159965Y-60416D01*
X1164331Y-85180D01*
X1165835Y-86235D01*
X1169834Y-85528D01*
X1170889Y-84022D01*
X1166998Y-61949D01*
X1168580Y-59692D01*
X1173489Y-58825D01*
X1175747Y-60407D01*
X1180112Y-85163D01*
X1181616Y-86218D01*
X1185615Y-85511D01*
X1186671Y-84005D01*
X1182783Y-61965D01*
X1184365Y-59707D01*
X1189274Y-58840D01*
X1191534Y-60423D01*
X1195906Y-85223D01*
X1197411Y-86278D01*
X1201410Y-85571D01*
X1202465Y-84066D01*
X1198565Y-61949D01*
X1200147Y-59692D01*
X1205056Y-58825D01*
X1207315Y-60409D01*
X1208940Y-69620D01*
X1210085Y-70423D01*
X1224260D01*
X1225405Y-69278D01*
G01X1127153Y516915D02*
X1126008Y515770D01*
X1123925D01*
X1123475Y516220D01*
X1121525D01*
X1121075Y515770D01*
X1115812D01*
X1114575Y517277D01*
X1114637Y517910D01*
X1113399Y519418D01*
X1112766Y519480D01*
X1111529Y520987D01*
X1111592Y521620D01*
X1110353Y523128D01*
X1109720Y523191D01*
X1108320Y524896D01*
X1107574Y526697D01*
X1107818Y527285D01*
X1107072Y529088D01*
X1106483Y529331D01*
X1105737Y531132D01*
X1105981Y531720D01*
X1105235Y533523D01*
X1104646Y533766D01*
X1103136Y537412D01*
Y552553D01*
X1102266Y554658D01*
X1098604Y558319D01*
X1095273Y560545D01*
X1095149Y561169D01*
X1093527Y562253D01*
X1092903Y562129D01*
X1091282Y563212D01*
X1091158Y563836D01*
X1089536Y564920D01*
X1088912Y564796D01*
X1087291Y565879D01*
X1083013Y570160D01*
X1081853Y571727D01*
X1081947Y572356D01*
X1080785Y573924D01*
X1080156Y574018D01*
X1076426Y579054D01*
X1075764Y581436D01*
X1078104Y617686D01*
X1081070Y634420D01*
X1192582Y1053564D01*
Y1069000D01*
G01X1119853Y524002D02*
X1118708Y522857D01*
X1117854D01*
X1117034Y523197D01*
X1116761Y523470D01*
X1115199Y524949D01*
X1115182Y525586D01*
X1113765Y526928D01*
X1113129Y526910D01*
X1111345Y528600D01*
X1110570Y530473D01*
X1110813Y531061D01*
X1110067Y532863D01*
X1109479Y533107D01*
X1108733Y534908D01*
X1108977Y535496D01*
X1108231Y537298D01*
X1107642Y537542D01*
X1106896Y539343D01*
Y544610D01*
X1107346Y545060D01*
Y547010D01*
X1106896Y547460D01*
Y549410D01*
X1107346Y549860D01*
Y551810D01*
X1106896Y552260D01*
Y554210D01*
X1105334Y557982D01*
X1105578Y558570D01*
X1104832Y560373D01*
X1104244Y560616D01*
X1103393Y562671D01*
X1101949Y563980D01*
X1101917Y564616D01*
X1100471Y565926D01*
X1099836Y565895D01*
X1095818Y569536D01*
X1094232Y571908D01*
X1092276Y573864D01*
X1090420Y574459D01*
X1090129Y575026D01*
X1088271Y575621D01*
X1087705Y575330D01*
X1083481Y576684D01*
X1082044Y577889D01*
X1081306Y578792D01*
X1079568Y581984D01*
X1081853Y617115D01*
X1084709Y633242D01*
X1196322Y1052997D01*
Y1069176D01*
G01X1127153Y527688D02*
X1126008Y528833D01*
X1118431D01*
X1114879Y530304D01*
X1114137Y531010D01*
X1110103Y539539D01*
X1109997Y539645D01*
Y555723D01*
X1106707Y563666D01*
X1103140Y567233D01*
X1097448Y571901D01*
X1096188Y573784D01*
X1093454Y576518D01*
X1089151Y578300D01*
X1087267D01*
X1085842Y578715D01*
X1085101Y579086D01*
X1083518Y580274D01*
X1082280Y582851D01*
X1084553Y617118D01*
X1087372Y632944D01*
X1198952Y1052247D01*
Y1068491D01*
X1198950Y1068493D01*
Y1068495D01*
X1198952Y1068497D01*
Y1069000D01*
G01X1127153Y531088D02*
X1125999Y529934D01*
X1125975Y529943D01*
X1123452D01*
X1123002Y530393D01*
X1121052D01*
X1120602Y529943D01*
X1118652D01*
X1115495Y531251D01*
X1115052Y531672D01*
X1114219Y533434D01*
X1114433Y534033D01*
X1113598Y535797D01*
X1112999Y536012D01*
Y536013D01*
X1111107Y540013D01*
Y546344D01*
X1111557Y546794D01*
Y548744D01*
X1111107Y549194D01*
Y551144D01*
X1111557Y551594D01*
Y553544D01*
X1111107Y553994D01*
Y555944D01*
X1109853Y558973D01*
X1110096Y559561D01*
X1109350Y561363D01*
X1108761Y561607D01*
Y561608D01*
X1107648Y564295D01*
X1103886Y568057D01*
X1098280Y572656D01*
X1097050Y574492D01*
X1094083Y577459D01*
X1089372Y579410D01*
X1087426D01*
X1086249Y579753D01*
X1085688Y580034D01*
X1084402Y581000D01*
X1083407Y583069D01*
X1084054Y592819D01*
X1084053D01*
X1084533Y593238D01*
X1084662Y595185D01*
X1084243Y595664D01*
X1084372Y597609D01*
X1084806Y597989D01*
X1084941Y600020D01*
X1084561Y600454D01*
X1084690Y602399D01*
X1085063Y602725D01*
X1085192Y604672D01*
X1084866Y605044D01*
X1084994Y606989D01*
X1085311Y607266D01*
X1085447Y609319D01*
X1085171Y609634D01*
X1085657Y616984D01*
X1088457Y632704D01*
X1200062Y1052101D01*
Y1069000D01*
G01X1119853Y520602D02*
X1118708Y521747D01*
X1117633D01*
X1116405Y522256D01*
X1115987Y522674D01*
X1110409Y527956D01*
X1105786Y539122D01*
Y553989D01*
X1102462Y562015D01*
X1094971Y568805D01*
X1093370Y571200D01*
X1091681Y572889D01*
X1082934Y575693D01*
X1081251Y577105D01*
X1080380Y578169D01*
X1078439Y581735D01*
X1080749Y617248D01*
X1083624Y633482D01*
X1195212Y1053143D01*
Y1069176D01*
G01X1119853Y534775D02*
X1118708Y535920D01*
X1117224D01*
X1115009Y538135D01*
X1114518Y539321D01*
Y556025D01*
X1109708Y567778D01*
X1100251Y577086D01*
X1097667Y578144D01*
X1096436Y579356D01*
X1094609Y583461D01*
X1094608Y583468D01*
X1093063Y602410D01*
X1093061D01*
X1090988Y627849D01*
X1090990Y627918D01*
X1090991D01*
X1091150Y631549D01*
X1202443Y1049597D01*
X1202692Y1051495D01*
Y1069177D01*
G01X1183818Y1504685D02*
Y1506190D01*
X1184318Y1506690D01*
X1186012D01*
X1187141Y1505561D01*
Y1448548D01*
X1186907Y1445804D01*
X1186908D01*
X1186420Y1445394D01*
X1186254Y1443450D01*
X1186664Y1442964D01*
X1186499Y1441022D01*
X1186011Y1440611D01*
X1185846Y1438667D01*
X1186256Y1438181D01*
X1186091Y1436239D01*
X1185603Y1435828D01*
X1185438Y1433884D01*
X1185848Y1433398D01*
X1184928Y1422591D01*
X1184443Y1348364D01*
X1183758Y1346132D01*
X1182574Y1344357D01*
X1090598Y1295170D01*
X1083152Y1290027D01*
X1077282Y1282951D01*
X1075527Y1278840D01*
Y1260012D01*
G01X1192480Y1509016D02*
Y1510520D01*
X1192980Y1511020D01*
X1194576D01*
X1195803Y1509793D01*
Y1453290D01*
X1194293Y1446165D01*
X1194294D01*
X1193819Y1445857D01*
X1193415Y1443948D01*
X1193723Y1443474D01*
X1193319Y1441567D01*
X1192844Y1441258D01*
X1192440Y1439350D01*
X1192749Y1438875D01*
X1190317Y1427392D01*
X1189377Y1419052D01*
X1188249Y1347226D01*
X1187463Y1344676D01*
X1185402Y1341546D01*
X1093202Y1291860D01*
X1086783Y1287802D01*
X1081127Y1281518D01*
X1079267Y1277027D01*
Y1260012D01*
G01X1183818Y1509804D02*
Y1508300D01*
X1184318Y1507800D01*
X1186472D01*
X1188251Y1506021D01*
Y1448500D01*
X1186038Y1422540D01*
X1185861Y1395424D01*
X1186110Y1395173D01*
X1186097Y1393222D01*
X1185844Y1392974D01*
X1185845D01*
X1185552Y1348194D01*
X1184772Y1345651D01*
X1183343Y1343509D01*
X1137110Y1318783D01*
Y1318784D01*
X1091178Y1294220D01*
X1083909Y1289200D01*
X1078240Y1282366D01*
X1076637Y1278612D01*
Y1260012D01*
G01X1192480Y1514134D02*
Y1512630D01*
X1192980Y1512130D01*
X1194908D01*
X1195038Y1512087D01*
X1195068Y1512071D01*
X1195210Y1511956D01*
X1195974Y1511193D01*
Y1511192D01*
X1196913Y1510253D01*
Y1453173D01*
X1191414Y1427214D01*
X1190487Y1418981D01*
X1189775Y1373621D01*
X1190021Y1373367D01*
X1189990Y1371417D01*
X1189735Y1371171D01*
X1189736D01*
X1189357Y1347050D01*
X1188478Y1344197D01*
X1186176Y1340701D01*
X1093763Y1290901D01*
X1087506Y1286945D01*
X1082080Y1280917D01*
X1080377Y1276805D01*
Y1260012D01*
G01X1305079Y1576339D02*
Y1577843D01*
X1305579Y1578343D01*
X1307273D01*
X1308402Y1577214D01*
Y1555450D01*
X1307727Y1553827D01*
X1305622Y1551699D01*
X1302145Y1550241D01*
X1301556Y1550482D01*
X1299757Y1549727D01*
X1299516Y1549137D01*
X1297718Y1548383D01*
X1297129Y1548624D01*
X1295330Y1547870D01*
X1295089Y1547280D01*
X1288880Y1544676D01*
X1278259Y1534034D01*
X1191382Y1339484D01*
X1190555Y1338231D01*
X1096522Y1287553D01*
X1089182Y1282366D01*
X1085690Y1277997D01*
X1083007Y1271509D01*
Y1260012D01*
G01X1322402Y1581457D02*
Y1579953D01*
X1322902Y1579453D01*
X1325056D01*
X1326835Y1577674D01*
Y1555188D01*
X1326069Y1553402D01*
X1324350Y1551710D01*
X1313195Y1544309D01*
X1292202Y1535591D01*
X1286444Y1529824D01*
X1198898Y1333801D01*
X1196605Y1331328D01*
X1100374Y1279339D01*
X1093893Y1274752D01*
X1091598Y1269212D01*
Y1260012D01*
G01X1313740Y1585788D02*
Y1584284D01*
X1314240Y1583784D01*
X1316394D01*
X1318173Y1582005D01*
Y1557532D01*
X1317300Y1555460D01*
X1309256Y1547380D01*
X1304130Y1545263D01*
Y1545262D01*
X1291162Y1539907D01*
X1282423Y1531227D01*
X1194664Y1334772D01*
X1098564Y1283018D01*
X1092763Y1278918D01*
X1089892Y1275324D01*
X1087857Y1270408D01*
Y1260012D01*
G01X1322402Y1576339D02*
Y1577843D01*
X1322902Y1578343D01*
X1324596D01*
X1325725Y1577214D01*
Y1555416D01*
X1325134Y1554041D01*
X1323647Y1552576D01*
X1312670Y1545294D01*
X1309443Y1543954D01*
X1308920Y1544170D01*
X1307118Y1543421D01*
X1306902Y1542898D01*
X1291572Y1536532D01*
X1285513Y1530464D01*
X1200605Y1340346D01*
X1200606D01*
X1200010Y1340119D01*
X1199215Y1338337D01*
X1199442Y1337743D01*
X1197959Y1334421D01*
X1195915Y1332218D01*
X1099787Y1280284D01*
X1092990Y1275473D01*
X1090488Y1269433D01*
Y1260012D01*
G01X1313740Y1580670D02*
Y1582174D01*
X1314240Y1582674D01*
X1315934D01*
X1317063Y1581545D01*
Y1557757D01*
X1316360Y1556091D01*
X1314985Y1554709D01*
X1314419Y1554708D01*
X1313043Y1553325D01*
X1313044Y1552759D01*
X1308626Y1548321D01*
X1306248Y1547339D01*
X1305726Y1547556D01*
X1303923Y1546811D01*
X1303706Y1546288D01*
X1290535Y1540849D01*
X1281494Y1531869D01*
X1193804Y1335571D01*
X1097978Y1283964D01*
X1091994Y1279734D01*
X1088926Y1275894D01*
X1086747Y1270629D01*
Y1260012D01*
G01X1305079Y1581457D02*
Y1579953D01*
X1305579Y1579453D01*
X1307733D01*
X1309512Y1577674D01*
Y1555228D01*
X1308670Y1553200D01*
X1306256Y1550760D01*
X1295519Y1546256D01*
X1295518D01*
X1289512Y1543736D01*
X1279190Y1533394D01*
X1192359Y1338948D01*
X1191329Y1337386D01*
X1097108Y1286607D01*
X1089951Y1281550D01*
X1086656Y1277427D01*
X1084117Y1271288D01*
Y1260012D01*
G01X1119853Y538175D02*
X1118708Y537030D01*
X1117684D01*
X1115950Y538764D01*
X1115628Y539542D01*
Y541975D01*
X1116078Y542425D01*
Y544375D01*
X1115628Y544825D01*
Y549075D01*
X1116078Y549525D01*
Y551475D01*
X1115628Y551925D01*
Y556244D01*
X1114872Y558092D01*
X1115118Y558679D01*
X1114380Y560485D01*
X1113792Y560731D01*
X1113054Y562535D01*
X1113300Y563122D01*
X1112562Y564928D01*
X1111974Y565174D01*
X1110650Y568410D01*
X1109261Y569777D01*
X1109255Y570414D01*
X1107865Y571782D01*
X1107228Y571777D01*
X1105839Y573144D01*
X1105833Y573781D01*
X1104443Y575149D01*
X1103807Y575145D01*
X1100874Y578031D01*
X1098290Y579089D01*
X1097365Y580000D01*
X1095700Y583746D01*
X1094793Y594869D01*
X1095205Y595354D01*
X1095046Y597299D01*
X1094560Y597711D01*
X1094402Y599654D01*
X1094814Y600139D01*
X1094655Y602084D01*
X1094169Y602496D01*
X1092100Y627870D01*
X1092254Y631380D01*
X1203535Y1049381D01*
X1203802Y1051422D01*
Y1069177D01*
G01X1095338Y1259824D02*
Y1268165D01*
X1097062Y1272332D01*
X1100322Y1274635D01*
X1199520Y1328240D01*
X1203553Y1332523D01*
X1241930Y1420303D01*
X1244136Y1423535D01*
X1289640Y1527619D01*
X1294429Y1532381D01*
X1317805Y1542083D01*
X1328410Y1549280D01*
X1334690Y1555500D01*
X1335496Y1557542D01*
Y1582005D01*
X1333717Y1583784D01*
X1331563D01*
X1331063Y1584284D01*
Y1585788D01*
G01X1102818Y1259712D02*
Y1264907D01*
X1104083Y1267962D01*
X1106135Y1269402D01*
X1151238Y1290474D01*
X1151636Y1290330D01*
X1153404Y1291156D01*
X1153549Y1291555D01*
X1258082Y1340395D01*
X1263181Y1345494D01*
Y1411305D01*
X1277073Y1468393D01*
Y1468392D01*
X1292215Y1514037D01*
X1294543Y1519875D01*
X1295613Y1522159D01*
X1296651Y1523629D01*
X1299187Y1526132D01*
X1323141Y1535972D01*
X1336070Y1542710D01*
X1350210Y1552280D01*
X1352819Y1557776D01*
Y1582005D01*
X1351040Y1583784D01*
X1348886D01*
X1348386Y1584284D01*
Y1585788D01*
G01X1331063Y1580670D02*
Y1582174D01*
X1331563Y1582674D01*
X1333257D01*
X1334386Y1581545D01*
Y1557754D01*
X1333743Y1556125D01*
X1327701Y1550142D01*
X1325699Y1548783D01*
X1325143Y1548890D01*
X1323529Y1547793D01*
X1323423Y1547238D01*
X1321810Y1546143D01*
X1321254Y1546250D01*
X1319640Y1545154D01*
X1319534Y1544598D01*
X1317275Y1543065D01*
X1293801Y1533323D01*
X1288707Y1528258D01*
X1243160Y1424075D01*
X1240954Y1420843D01*
X1202613Y1333144D01*
X1198834Y1329132D01*
X1099735Y1275581D01*
X1096159Y1273053D01*
X1094228Y1268386D01*
Y1259824D01*
G01X1357047Y1576339D02*
Y1577843D01*
X1357547Y1578343D01*
X1359241D01*
X1360370Y1577214D01*
Y1555060D01*
X1359659Y1553693D01*
X1358154Y1552421D01*
X1355784Y1550815D01*
X1355298Y1550909D01*
X1353683Y1549814D01*
X1353590Y1549328D01*
X1351976Y1548235D01*
X1351490Y1548328D01*
X1349875Y1547233D01*
X1349781Y1546747D01*
X1345725Y1543999D01*
X1343662Y1542953D01*
X1343124Y1543129D01*
X1341384Y1542247D01*
X1341208Y1541709D01*
X1336353Y1539248D01*
X1322176Y1532583D01*
X1300863Y1523940D01*
X1298902Y1522043D01*
X1297570Y1520064D01*
X1294617Y1512742D01*
X1291289Y1496285D01*
X1290876Y1496012D01*
X1290489Y1494099D01*
X1290763Y1493687D01*
X1290377Y1491776D01*
X1290378D01*
X1289965Y1491502D01*
X1289578Y1489590D01*
X1289852Y1489178D01*
X1288600Y1482984D01*
Y1482979D01*
X1288545Y1482709D01*
X1274333Y1412425D01*
X1274311Y1412403D01*
Y1346370D01*
X1271011Y1343070D01*
X1106667Y1266285D01*
X1105448Y1263942D01*
Y1259712D01*
G01X1339725Y1576339D02*
Y1577843D01*
X1340225Y1578343D01*
X1341919D01*
X1343048Y1577214D01*
Y1556088D01*
X1342425Y1554523D01*
X1341134Y1553134D01*
X1337691Y1550889D01*
X1337276Y1550977D01*
X1335641Y1549911D01*
X1335554Y1549496D01*
X1333921Y1548431D01*
X1333506Y1548519D01*
X1331871Y1547453D01*
X1331784Y1547038D01*
X1330151Y1545973D01*
X1329736Y1546061D01*
X1328101Y1544995D01*
X1328014Y1544580D01*
X1326381Y1543515D01*
X1320919Y1540403D01*
X1296103Y1530160D01*
X1292144Y1526170D01*
X1290328Y1522443D01*
X1286639Y1513679D01*
X1278962Y1492235D01*
X1278961Y1492232D01*
X1278449Y1491990D01*
X1277792Y1490153D01*
X1278034Y1489642D01*
X1277377Y1487807D01*
X1276865Y1487565D01*
X1276208Y1485728D01*
X1276449Y1485216D01*
X1249831Y1410859D01*
Y1346220D01*
X1247443Y1343832D01*
X1232474Y1335058D01*
X1103171Y1273394D01*
X1099529Y1270819D01*
X1097968Y1267036D01*
Y1260012D01*
G01X1106558Y1259712D02*
Y1263670D01*
X1107478Y1265437D01*
X1150498Y1285537D01*
X1151029Y1285344D01*
X1152797Y1286171D01*
X1152990Y1286702D01*
X1154756Y1287527D01*
X1155288Y1287334D01*
X1157056Y1288160D01*
X1157249Y1288692D01*
X1214364Y1315378D01*
X1214365D01*
X1271658Y1342147D01*
X1275421Y1345910D01*
Y1412205D01*
X1289710Y1482867D01*
Y1482872D01*
X1292286Y1495612D01*
Y1495613D01*
X1295685Y1512422D01*
X1298556Y1519541D01*
X1299758Y1521326D01*
X1301480Y1522992D01*
X1322621Y1531565D01*
X1336840Y1538250D01*
X1346290Y1543040D01*
X1358826Y1551534D01*
X1360544Y1552986D01*
X1361480Y1554789D01*
Y1577674D01*
X1359701Y1579453D01*
X1357547D01*
X1357047Y1579953D01*
Y1581457D01*
G01X1099078Y1260012D02*
Y1266815D01*
X1100433Y1270098D01*
X1103735Y1272432D01*
X1146461Y1292808D01*
X1146928Y1292643D01*
X1148689Y1293483D01*
X1148854Y1293950D01*
X1150614Y1294789D01*
X1151080Y1294624D01*
X1152841Y1295464D01*
X1153007Y1295931D01*
X1153008Y1295930D01*
X1232994Y1334076D01*
X1248127Y1342946D01*
X1250941Y1345760D01*
Y1410666D01*
X1278422Y1487431D01*
X1278423Y1487434D01*
X1280007Y1491859D01*
X1280008D01*
X1280009Y1491862D01*
X1287674Y1513276D01*
X1291340Y1521984D01*
X1293062Y1525518D01*
X1296734Y1529219D01*
X1321408Y1539403D01*
X1326930Y1542550D01*
X1326960Y1542566D01*
X1341855Y1552278D01*
X1343380Y1553920D01*
X1344158Y1555875D01*
Y1577674D01*
X1342379Y1579453D01*
X1340225D01*
X1339725Y1579953D01*
Y1581457D01*
G01X1348386Y1580670D02*
Y1582174D01*
X1348886Y1582674D01*
X1350580D01*
X1351709Y1581545D01*
Y1558027D01*
X1349337Y1553030D01*
X1346560Y1551151D01*
X1345983Y1551263D01*
X1344475Y1550242D01*
X1344365Y1549665D01*
X1342751Y1548573D01*
X1342265Y1548666D01*
X1340649Y1547572D01*
X1340555Y1547086D01*
X1335500Y1543666D01*
X1333771Y1542765D01*
X1333367Y1542893D01*
X1331636Y1541990D01*
X1331509Y1541586D01*
X1322673Y1536980D01*
X1298563Y1527076D01*
X1295801Y1524350D01*
X1294649Y1522720D01*
X1293523Y1520317D01*
X1291171Y1514418D01*
X1276005Y1468699D01*
X1262071Y1411439D01*
Y1345954D01*
X1257435Y1341318D01*
X1105577Y1270367D01*
X1103180Y1268686D01*
X1101708Y1265128D01*
Y1259712D01*
G01X1110298Y1259512D02*
Y1260929D01*
X1113268Y1263899D01*
X1159322Y1284928D01*
X1159719Y1284780D01*
X1161494Y1285591D01*
X1161642Y1285988D01*
X1283745Y1341744D01*
X1287661Y1345660D01*
Y1413973D01*
X1299948Y1512883D01*
X1302616Y1518704D01*
X1303591Y1519715D01*
X1325817Y1528694D01*
X1350013Y1540349D01*
X1350050D01*
X1350083Y1540382D01*
X1350084D01*
X1363210Y1549160D01*
X1369130Y1555230D01*
X1370142Y1557561D01*
Y1582005D01*
X1368363Y1583784D01*
X1366209D01*
X1365709Y1584284D01*
Y1585788D01*
G01X1109188Y1259512D02*
Y1261389D01*
X1112625Y1264826D01*
X1283102Y1342671D01*
X1286551Y1346120D01*
Y1414042D01*
X1298867Y1513190D01*
X1301685Y1519339D01*
X1302956Y1520656D01*
X1325368Y1529710D01*
X1349531Y1541349D01*
X1354373Y1544586D01*
X1354484Y1545141D01*
X1356106Y1546226D01*
X1356660Y1546116D01*
X1358281Y1547200D01*
Y1547199D01*
X1358391Y1547754D01*
X1360013Y1548839D01*
X1360568Y1548729D01*
X1362496Y1550018D01*
X1364233Y1551799D01*
X1364226Y1552294D01*
X1365589Y1553691D01*
X1366084Y1553698D01*
X1368192Y1555860D01*
X1369032Y1557792D01*
Y1581545D01*
X1367903Y1582674D01*
X1366209D01*
X1365709Y1582174D01*
Y1580670D01*
G01X1244685Y1129984D02*
X1252756D01*
X1253023Y1129821D01*
Y1129820D01*
X1258561Y1126420D01*
X1292434Y1093732D01*
X1302152Y1076270D01*
X1302750Y1060150D01*
X1268165Y941705D01*
X1262471Y913768D01*
X1265081Y663520D01*
X1263079Y590143D01*
X1262062Y576190D01*
X1252505Y532374D01*
X1250440Y529160D01*
X1241510Y524190D01*
X1239820Y522500D01*
X1231350Y517830D01*
X1209840Y492890D01*
X1201010Y484160D01*
X1180377Y475569D01*
X1172023D01*
X1170878Y474424D01*
G01X1244685Y1128874D02*
X1252442D01*
X1257877Y1125537D01*
X1291544Y1093048D01*
X1301052Y1075963D01*
X1301634Y1060289D01*
X1267086Y941972D01*
X1261359Y913874D01*
X1263970Y663529D01*
X1261970Y590199D01*
X1260960Y576350D01*
X1251463Y532806D01*
X1249656Y529995D01*
X1240835Y525085D01*
X1239146Y523396D01*
X1230639Y518707D01*
X1218595Y504741D01*
X1218101Y504705D01*
X1216827Y503227D01*
X1216863Y502733D01*
X1215590Y501257D01*
X1215096Y501221D01*
X1213822Y499743D01*
X1213858Y499249D01*
X1212585Y497773D01*
X1212092Y497737D01*
X1210817Y496259D01*
X1210853Y495766D01*
X1209028Y493649D01*
X1200383Y485102D01*
X1197883Y484061D01*
X1197294Y484304D01*
X1195493Y483554D01*
X1195251Y482965D01*
X1193451Y482216D01*
X1192862Y482459D01*
X1191061Y481709D01*
X1190819Y481120D01*
X1189019Y480371D01*
X1188430Y480613D01*
X1186629Y479863D01*
X1186387Y479274D01*
X1184587Y478525D01*
X1183998Y478767D01*
X1182197Y478018D01*
X1181955Y477428D01*
Y477429D01*
X1180155Y476679D01*
X1172023D01*
X1170878Y477824D01*
G01X1244685Y1122503D02*
X1249907D01*
X1254614Y1119774D01*
X1286136Y1089219D01*
X1294584Y1074239D01*
X1295031Y1061194D01*
X1261392Y946021D01*
X1254613Y914163D01*
X1257191Y663001D01*
X1255369Y590658D01*
X1253795Y579529D01*
X1253796D01*
X1252189Y568174D01*
X1239460Y551590D01*
X1238130Y547870D01*
X1229320Y542030D01*
X1204310Y500170D01*
X1200851Y496797D01*
X1188062Y491482D01*
X1179062Y489742D01*
X1172023D01*
X1170878Y488597D01*
G01X1244685Y1121393D02*
X1249608D01*
X1253939Y1118882D01*
X1285247Y1088533D01*
X1293483Y1073930D01*
X1293915Y1061334D01*
X1260314Y946293D01*
X1253501Y914274D01*
X1256080Y663009D01*
X1254260Y590750D01*
X1251130Y568619D01*
X1238473Y552128D01*
X1237208Y548592D01*
X1228496Y542816D01*
X1215682Y521370D01*
X1215065Y521215D01*
X1214064Y519540D01*
X1214220Y518922D01*
X1213220Y517249D01*
X1212603Y517094D01*
X1211602Y515419D01*
X1211758Y514801D01*
X1210758Y513128D01*
X1210759D01*
X1210142Y512973D01*
X1209140Y511298D01*
X1209296Y510681D01*
X1206538Y506064D01*
X1205921Y505908D01*
X1204919Y504233D01*
X1205075Y503616D01*
X1203431Y500864D01*
X1200231Y497743D01*
X1192802Y494656D01*
X1192214Y494899D01*
X1190413Y494151D01*
X1190170Y493562D01*
Y493561D01*
X1187740Y492551D01*
X1184738Y491971D01*
X1184211Y492327D01*
X1182296Y491957D01*
X1181939Y491429D01*
X1178955Y490852D01*
X1172023D01*
X1170878Y491997D01*
G01X1244557Y1115023D02*
X1247446D01*
X1251079Y1112634D01*
X1280203Y1084322D01*
X1287122Y1072077D01*
X1287338Y1063911D01*
X1257275Y961149D01*
X1246964Y918553D01*
X1242894Y876381D01*
X1234184Y632688D01*
X1228738Y595900D01*
X1228739D01*
X1223296Y559139D01*
X1220871Y547842D01*
X1219745Y545216D01*
X1217065Y541139D01*
Y541138D01*
X1216953Y540968D01*
X1206350Y533310D01*
X1179240Y519703D01*
X1172023D01*
X1170878Y518558D01*
G01X1244557Y1113913D02*
X1247113D01*
X1250380Y1111764D01*
X1279315Y1083637D01*
X1286019Y1071771D01*
X1286223Y1064056D01*
X1256202Y961436D01*
X1245866Y918738D01*
X1241785Y876454D01*
X1233076Y632789D01*
X1227640Y596063D01*
X1227639Y596062D01*
Y596060D01*
X1222203Y559337D01*
X1219808Y548180D01*
X1218763Y545744D01*
X1216137Y541749D01*
X1211327Y538275D01*
X1210699Y538376D01*
X1209117Y537233D01*
X1209016Y536605D01*
X1205772Y534262D01*
X1202144Y532441D01*
X1201540Y532642D01*
X1199796Y531766D01*
X1199595Y531162D01*
X1197853Y530288D01*
X1197248Y530488D01*
X1195505Y529612D01*
X1195304Y529008D01*
X1193562Y528134D01*
X1192958Y528335D01*
X1191214Y527459D01*
X1191013Y526855D01*
X1189271Y525981D01*
X1188667Y526181D01*
X1186924Y525305D01*
X1186723Y524701D01*
X1184981Y523827D01*
X1184377Y524027D01*
X1182633Y523151D01*
X1182433Y522547D01*
X1182432Y522548D01*
X1178976Y520813D01*
X1172023D01*
X1170878Y521958D01*
G01X1244685Y1107543D02*
X1245623D01*
X1246450Y1106721D01*
X1247528Y1104205D01*
X1247876Y1087828D01*
X1242853Y1060722D01*
X1240292Y1042649D01*
X1226298Y631796D01*
Y631713D01*
X1226274Y631689D01*
X1209471Y557909D01*
X1209470Y557907D01*
Y557908D01*
X1208744Y556672D01*
X1205369Y553297D01*
X1204281Y550671D01*
Y549072D01*
X1202636Y546271D01*
X1197506Y541070D01*
X1179817Y533876D01*
X1172023D01*
X1170878Y532731D01*
G01Y536131D02*
X1172023Y534986D01*
X1179599D01*
X1182465Y536152D01*
X1182713Y536739D01*
X1184520Y537474D01*
X1185106Y537226D01*
X1186912Y537960D01*
X1187159Y538548D01*
X1188966Y539282D01*
X1189553Y539035D01*
X1191359Y539769D01*
X1191606Y540356D01*
X1193414Y541091D01*
X1194000Y540844D01*
X1196876Y542013D01*
X1201748Y546953D01*
X1203171Y549374D01*
Y550892D01*
X1204428Y553926D01*
X1207859Y557357D01*
X1208426Y558323D01*
X1209896Y564778D01*
X1209557Y565317D01*
X1209990Y567219D01*
X1210530Y567558D01*
X1210962Y569459D01*
X1210624Y569998D01*
X1211057Y571900D01*
X1211596Y572239D01*
X1212028Y574140D01*
X1211690Y574679D01*
X1212123Y576581D01*
X1212662Y576920D01*
X1225191Y631936D01*
X1225192Y631940D01*
X1239184Y1042746D01*
X1241757Y1060901D01*
X1246763Y1087918D01*
X1246422Y1103966D01*
X1245514Y1106085D01*
X1245165Y1106433D01*
X1244685D01*
G01X1228873Y1069000D02*
Y1067707D01*
X1231173Y1056142D01*
Y1031411D01*
X1217073Y631909D01*
X1211752Y611958D01*
X1200933Y600930D01*
X1197959Y592667D01*
X1190443Y581088D01*
X1187057Y577656D01*
X1186421Y577651D01*
X1185050Y576262D01*
X1185055Y575626D01*
X1181565Y572088D01*
X1178612Y570852D01*
X1172023D01*
X1170878Y571997D01*
G01Y568597D02*
X1172023Y569742D01*
X1178835D01*
X1182199Y571149D01*
Y571150D01*
X1191313Y580389D01*
X1198960Y592170D01*
X1201896Y600325D01*
X1212750Y611389D01*
X1217814Y630378D01*
Y630377D01*
X1218178Y631744D01*
X1232283Y1031391D01*
Y1056252D01*
X1229983Y1067817D01*
Y1069000D01*
G01X1170878Y586171D02*
X1172023Y585026D01*
X1180257D01*
X1182978Y587747D01*
Y588242D01*
X1184358Y589622D01*
X1184853D01*
X1186231Y591000D01*
Y591495D01*
X1187611Y592875D01*
X1188106D01*
X1189941Y594710D01*
X1196156Y609623D01*
X1204531Y622222D01*
X1209250Y633507D01*
X1209420Y634283D01*
Y634284D01*
X1209419D01*
X1209421Y634294D01*
X1209505Y634673D01*
X1209506Y634674D01*
X1209590Y635057D01*
X1223390Y1025666D01*
X1223527Y1055627D01*
X1221393Y1066486D01*
Y1069000D01*
G01X1170878Y582771D02*
X1172023Y583916D01*
X1180717D01*
X1190881Y594080D01*
X1197140Y609097D01*
X1205515Y621695D01*
X1210313Y633171D01*
X1210505Y634046D01*
X1210507Y634056D01*
X1210590Y634434D01*
X1210591Y634439D01*
X1210696Y634918D01*
X1224500Y1025644D01*
X1224638Y1055733D01*
X1222503Y1066595D01*
Y1069000D01*
G01X1170878Y596944D02*
X1172023Y598089D01*
X1181161D01*
X1185273Y602201D01*
X1188706Y610437D01*
X1198681Y625205D01*
X1198724Y625308D01*
X1198723D01*
X1202762Y635021D01*
X1216762Y1026160D01*
X1217058Y1054606D01*
X1215023Y1065119D01*
Y1069000D01*
G01X1170878Y600344D02*
X1172023Y599199D01*
X1180701D01*
X1184333Y602831D01*
X1187723Y610967D01*
X1191833Y617051D01*
X1191739Y617537D01*
X1192831Y619154D01*
X1193317Y619248D01*
X1194408Y620863D01*
X1194314Y621349D01*
X1195407Y622966D01*
X1195892Y623060D01*
X1197698Y625734D01*
X1201659Y635262D01*
X1215652Y1026186D01*
X1215946Y1054505D01*
X1213913Y1065012D01*
Y1069000D01*
G01X1170878Y614517D02*
X1171699Y613696D01*
X1172482Y613372D01*
X1174906D01*
X1176760Y615226D01*
X1177246Y618678D01*
X1176863Y619187D01*
X1177136Y621119D01*
X1177645Y621501D01*
X1177917Y623431D01*
X1177534Y623940D01*
X1177806Y625872D01*
X1178315Y626255D01*
X1180435Y641300D01*
X1207627Y1028683D01*
X1208293Y1054114D01*
X1206433Y1063798D01*
Y1069000D01*
G01X1207543D02*
Y1063904D01*
X1209406Y1054205D01*
X1208737Y1028630D01*
X1181540Y641183D01*
Y641184D01*
X1177808Y614703D01*
X1175366Y612262D01*
X1172023D01*
X1170878Y611117D01*
G01X1244585Y1133724D02*
X1254759D01*
X1259584Y1130680D01*
X1295436Y1096062D01*
X1305860Y1077658D01*
X1306592Y1059547D01*
X1272311Y941806D01*
X1266298Y912895D01*
X1268921Y663481D01*
X1267139Y589875D01*
X1265574Y573164D01*
X1253449Y519203D01*
X1250350Y515130D01*
X1206270Y482260D01*
X1200270Y476280D01*
X1181429Y468482D01*
X1179323D01*
X1178178Y467337D01*
G01X1244585Y1132614D02*
X1254438D01*
X1258895Y1129802D01*
X1294549Y1095375D01*
X1304761Y1077344D01*
X1305475Y1059683D01*
X1271233Y942075D01*
X1265186Y913004D01*
X1267810Y663489D01*
X1266030Y589940D01*
X1264475Y573338D01*
X1252419Y519683D01*
X1249561Y515927D01*
X1224149Y496978D01*
X1223659Y497050D01*
X1222095Y495883D01*
X1222024Y495393D01*
X1220461Y494228D01*
X1219971Y494300D01*
X1218407Y493133D01*
X1218336Y492643D01*
X1216773Y491478D01*
X1216283Y491550D01*
X1214719Y490383D01*
X1214648Y489893D01*
X1213085Y488728D01*
X1212596Y488799D01*
X1211031Y487633D01*
X1210960Y487143D01*
X1205542Y483103D01*
X1199642Y477222D01*
X1194516Y475100D01*
X1193928Y475344D01*
X1192125Y474598D01*
X1191881Y474009D01*
X1191880D01*
X1190080Y473264D01*
X1189492Y473508D01*
X1187689Y472762D01*
X1187445Y472173D01*
X1187444D01*
X1185644Y471428D01*
X1185056Y471672D01*
X1183253Y470926D01*
X1183009Y470337D01*
Y470338D01*
X1181207Y469592D01*
X1179323D01*
X1178178Y470737D01*
G01Y484910D02*
X1179323Y483765D01*
X1181567D01*
X1183367Y484513D01*
X1183610Y485102D01*
X1185412Y485851D01*
X1186000Y485608D01*
X1187800Y486356D01*
X1188043Y486945D01*
X1189845Y487694D01*
X1190433Y487451D01*
X1192233Y488199D01*
X1192476Y488788D01*
X1194278Y489536D01*
X1194866Y489294D01*
X1199719Y491310D01*
X1207026Y498666D01*
X1212647Y507089D01*
X1212522Y507713D01*
X1213606Y509336D01*
X1214230Y509460D01*
X1214229D01*
X1215311Y511081D01*
X1215186Y511706D01*
X1216270Y513329D01*
X1216894Y513453D01*
X1217976Y515074D01*
X1217851Y515699D01*
X1218935Y517322D01*
X1219559Y517446D01*
X1226888Y528428D01*
X1243757Y545275D01*
X1254580Y565520D01*
X1258130Y590490D01*
X1260080Y663218D01*
X1257298Y914047D01*
X1263820Y944691D01*
X1297840Y1061058D01*
X1297198Y1075091D01*
X1288240Y1090881D01*
X1255803Y1122312D01*
X1250353Y1125133D01*
X1244585D01*
G01X1178178Y481510D02*
X1179323Y482655D01*
X1181789D01*
X1200350Y490370D01*
X1207890Y497960D01*
X1227750Y527720D01*
X1244659Y544606D01*
X1255652Y565169D01*
X1259238Y590397D01*
X1261191Y663209D01*
X1258410Y913936D01*
X1264897Y944419D01*
X1298958Y1060924D01*
X1298295Y1075407D01*
X1289128Y1091568D01*
X1256458Y1123223D01*
X1250863Y1126119D01*
X1250739Y1126243D01*
X1244585D01*
G01Y1118763D02*
X1248972D01*
X1253275Y1115743D01*
X1283139Y1086875D01*
X1290848Y1073123D01*
X1291242Y1061930D01*
X1258056Y948387D01*
X1250672Y914300D01*
X1253041Y662723D01*
X1251596Y596418D01*
X1250158Y593107D01*
X1241718Y588892D01*
X1237279Y583891D01*
X1236938Y583809D01*
Y583810D01*
X1232367Y582716D01*
X1231016Y581296D01*
X1226501Y551156D01*
X1223502Y543557D01*
X1220307Y538842D01*
X1205359Y525482D01*
X1181009Y512616D01*
X1179323D01*
X1178178Y511471D01*
G01X1244585Y1117653D02*
X1248620D01*
X1252566Y1114884D01*
X1282250Y1086190D01*
X1289748Y1072815D01*
X1290126Y1062070D01*
X1256979Y948661D01*
X1249560Y914414D01*
X1251930Y662730D01*
X1250490Y596660D01*
X1249300Y593920D01*
X1241030Y589790D01*
X1236680Y584890D01*
X1231790Y583720D01*
X1229970Y581807D01*
X1225422Y551446D01*
X1222514Y544078D01*
X1219464Y539579D01*
X1214403Y535055D01*
X1213909Y535083D01*
X1212454Y533782D01*
X1212426Y533288D01*
X1210973Y531989D01*
X1210479Y532017D01*
X1209024Y530716D01*
X1208996Y530222D01*
X1204720Y526400D01*
X1202894Y525436D01*
X1202286Y525623D01*
X1200560Y524711D01*
X1200373Y524103D01*
X1198649Y523193D01*
X1198041Y523380D01*
X1196315Y522468D01*
X1196128Y521860D01*
X1194404Y520950D01*
X1193795Y521137D01*
X1192070Y520226D01*
X1191883Y519617D01*
X1190159Y518707D01*
X1189550Y518894D01*
X1187825Y517983D01*
X1187638Y517374D01*
X1185914Y516464D01*
X1185306Y516652D01*
X1183581Y515740D01*
X1183394Y515132D01*
X1180733Y513726D01*
X1179323D01*
X1178178Y514871D01*
G01X1244585Y1110173D02*
X1245868D01*
X1248091Y1108686D01*
X1249826Y1106592D01*
X1250647Y1104654D01*
X1250989Y1090888D01*
Y1089454D01*
X1246569Y1066226D01*
X1242961Y1042217D01*
X1228961Y630995D01*
X1215763Y554853D01*
Y550446D01*
X1215225Y547344D01*
X1213900Y545769D01*
X1209040Y543160D01*
X1209039D01*
X1208429Y543343D01*
X1206710Y542420D01*
X1206527Y541811D01*
X1204809Y540889D01*
X1204199Y541072D01*
X1202480Y540149D01*
X1202297Y539540D01*
X1200579Y538618D01*
X1199969Y538802D01*
X1198250Y537879D01*
X1198067Y537270D01*
X1195170Y535715D01*
X1194560Y535898D01*
X1192841Y534975D01*
X1192658Y534366D01*
X1190940Y533444D01*
X1190330Y533627D01*
X1188611Y532704D01*
X1188428Y532095D01*
X1186710Y531173D01*
X1186101Y531357D01*
X1184382Y530433D01*
X1184198Y529824D01*
X1180612Y527899D01*
X1179323D01*
X1178178Y529044D01*
G01X1244585Y1111283D02*
X1246205D01*
X1248843Y1109519D01*
X1250785Y1107175D01*
X1251752Y1104893D01*
X1252099Y1090902D01*
Y1089349D01*
X1247664Y1066040D01*
X1244069Y1042115D01*
X1230068Y630881D01*
X1216873Y554757D01*
Y550350D01*
X1216268Y546859D01*
X1214613Y544891D01*
X1180892Y526789D01*
X1179323D01*
X1178178Y525644D01*
G01X1236354Y1078088D02*
Y1076947D01*
X1238228Y1072422D01*
Y1069103D01*
X1238044Y1066059D01*
X1235447Y1044210D01*
X1221226Y632429D01*
X1220859Y630096D01*
X1214987Y609551D01*
X1209699Y602436D01*
X1203821Y596812D01*
X1201621Y590632D01*
X1200090Y588246D01*
X1199606Y588141D01*
X1198552Y586499D01*
X1198657Y586015D01*
X1197604Y584375D01*
X1197120Y584270D01*
X1196066Y582628D01*
X1196171Y582144D01*
X1195118Y580504D01*
X1194496Y580369D01*
X1193442Y578727D01*
X1193577Y578105D01*
X1192524Y576465D01*
X1191902Y576330D01*
X1190848Y574688D01*
X1190983Y574066D01*
X1187680Y568922D01*
X1185018Y567143D01*
X1184394Y567268D01*
X1182772Y566183D01*
X1182648Y565559D01*
X1179963Y563765D01*
X1179323D01*
X1178178Y564910D01*
G01X1237464Y1078088D02*
Y1077168D01*
X1239338Y1072643D01*
Y1069038D01*
X1239336Y1069036D01*
X1239151Y1065960D01*
X1236555Y1044125D01*
X1222334Y632323D01*
X1221945Y629856D01*
X1215999Y609051D01*
X1210535Y601698D01*
X1204779Y596191D01*
X1202625Y590139D01*
X1188490Y568127D01*
X1180300Y562655D01*
X1179323D01*
X1178178Y561510D01*
G01Y579084D02*
X1179323Y577939D01*
X1181216D01*
X1182594Y579317D01*
Y579812D01*
X1183974Y581192D01*
X1184469D01*
X1187401Y584124D01*
X1188489Y585742D01*
X1188393Y586227D01*
X1189482Y587847D01*
X1189968Y587942D01*
X1193748Y593564D01*
X1197399Y602525D01*
X1204200Y611666D01*
X1207939Y614722D01*
X1209059Y616472D01*
X1211217Y625265D01*
Y625266D01*
X1213375Y634058D01*
X1227205Y1025590D01*
X1227344Y1055732D01*
X1225133Y1066982D01*
Y1069177D01*
G01X1178178Y575684D02*
X1179323Y576829D01*
X1181676D01*
X1188262Y583415D01*
X1194733Y593039D01*
X1198375Y601975D01*
X1205009Y610893D01*
X1208779Y613974D01*
X1210094Y616028D01*
X1214481Y633904D01*
X1228315Y1025568D01*
X1228455Y1055838D01*
X1226243Y1067091D01*
Y1069177D01*
G01X1178178Y604030D02*
X1179318Y605170D01*
X1181022D01*
X1182984Y607132D01*
X1183919Y609188D01*
X1184971Y624536D01*
X1184973Y624538D01*
Y631444D01*
X1185427Y638049D01*
X1187065Y648313D01*
X1212384Y1017019D01*
X1213232Y1054375D01*
X1211283Y1064792D01*
Y1069176D01*
G01X1178178Y593257D02*
X1179323Y592112D01*
X1181192D01*
X1186657Y597481D01*
X1187459Y599389D01*
X1187272Y599848D01*
X1188029Y601646D01*
X1188487Y601833D01*
X1189242Y603630D01*
X1189055Y604088D01*
X1189812Y605887D01*
X1190271Y606074D01*
X1192197Y610655D01*
X1201112Y623900D01*
X1205599Y634691D01*
X1219491Y1026670D01*
X1219737Y1055257D01*
X1217653Y1065980D01*
Y1069177D01*
G01X1178178Y589857D02*
X1179323Y591002D01*
X1181647D01*
X1187594Y596845D01*
X1191115Y605218D01*
X1191117Y605219D01*
X1193179Y610125D01*
X1202095Y623372D01*
X1202138Y623474D01*
X1202137D01*
X1206702Y634450D01*
X1220601Y1026646D01*
X1220848Y1055359D01*
X1218763Y1066087D01*
Y1069177D01*
G01X1178178Y607430D02*
X1178850Y606758D01*
X1180004Y606280D01*
X1180562D01*
X1182057Y607775D01*
X1182825Y609464D01*
X1182958Y611408D01*
X1182540Y611888D01*
X1182673Y613834D01*
X1183153Y614252D01*
X1183286Y616197D01*
X1182868Y616677D01*
X1183001Y618623D01*
X1183482Y619041D01*
X1183860Y624574D01*
X1183863Y624576D01*
Y631483D01*
X1184323Y638175D01*
X1185961Y648439D01*
X1211274Y1017070D01*
X1212119Y1054284D01*
X1210173Y1064689D01*
Y1069176D01*
G01X1339725Y1458622D02*
Y1460127D01*
X1340225Y1460627D01*
X1341919D01*
X1343642Y1458903D01*
X1344537Y1448708D01*
X1344219Y1448328D01*
X1344389Y1446385D01*
X1344770Y1446067D01*
X1344769D01*
X1344939Y1444125D01*
X1344621Y1443746D01*
X1344792Y1441802D01*
X1345172Y1441484D01*
X1345342Y1439542D01*
X1345024Y1439163D01*
X1345195Y1437219D01*
X1345575Y1436901D01*
X1345574D01*
X1346325Y1428342D01*
X1346007Y1427962D01*
X1346178Y1426019D01*
X1346558Y1425701D01*
X1346557D01*
X1346727Y1423759D01*
X1346409Y1423380D01*
X1346580Y1421436D01*
X1346960Y1421118D01*
X1347751Y1412110D01*
Y1346241D01*
X1345392Y1343882D01*
X1202317Y1276560D01*
X1196057Y1273615D01*
X1189329Y1266887D01*
X1187732Y1263032D01*
Y1259724D01*
G01X1177621D02*
Y1266368D01*
X1180663Y1273712D01*
X1191554Y1284603D01*
X1196155Y1286815D01*
X1196689Y1286628D01*
X1198447Y1287474D01*
X1198634Y1288008D01*
X1306747Y1340017D01*
X1312141Y1345411D01*
Y1410945D01*
X1318173Y1451920D01*
Y1464288D01*
X1316394Y1466067D01*
X1314240D01*
X1313740Y1466567D01*
Y1468071D01*
G01X1305079Y1458622D02*
Y1460127D01*
X1305579Y1460627D01*
X1307273D01*
X1308402Y1459498D01*
Y1453837D01*
X1307076Y1448159D01*
X1306535Y1447823D01*
X1306091Y1445924D01*
X1306427Y1445383D01*
X1305984Y1443485D01*
X1305443Y1443149D01*
X1304999Y1441249D01*
X1305335Y1440708D01*
X1301894Y1425972D01*
X1301353Y1425636D01*
X1300909Y1423736D01*
X1301245Y1423196D01*
X1298791Y1412685D01*
Y1345937D01*
X1294092Y1341238D01*
X1189151Y1289272D01*
X1176519Y1276640D01*
X1172771Y1267591D01*
Y1259812D01*
G01X1322402Y1463741D02*
Y1462237D01*
X1322902Y1461737D01*
X1325056D01*
X1326835Y1459958D01*
Y1452862D01*
X1324381Y1411531D01*
Y1345141D01*
X1320794Y1341551D01*
X1201057Y1284261D01*
X1200869Y1283727D01*
X1199109Y1282884D01*
X1198575Y1283073D01*
X1192972Y1280392D01*
X1183875Y1271295D01*
X1181361Y1265226D01*
Y1259724D01*
G01X1313740Y1462953D02*
Y1464457D01*
X1314240Y1464957D01*
X1315934D01*
X1317063Y1463828D01*
Y1452002D01*
X1316535Y1448420D01*
X1316536D01*
X1316138Y1448125D01*
X1315854Y1446194D01*
X1316149Y1445797D01*
X1315866Y1443868D01*
X1315467Y1443573D01*
X1315183Y1441643D01*
X1315479Y1441246D01*
X1315196Y1439317D01*
X1314797Y1439022D01*
X1314513Y1437092D01*
X1314809Y1436695D01*
X1313326Y1426621D01*
X1313327D01*
X1312928Y1426326D01*
X1312645Y1424396D01*
X1312940Y1423998D01*
X1311031Y1411027D01*
Y1345871D01*
X1306095Y1340936D01*
X1195672Y1287816D01*
Y1287815D01*
X1190903Y1285522D01*
X1179722Y1274341D01*
X1176511Y1266589D01*
Y1259724D01*
G01X1331063Y1462953D02*
Y1464457D01*
X1331563Y1464957D01*
X1333257D01*
X1334386Y1463828D01*
Y1451789D01*
X1334496Y1447834D01*
X1334156Y1447475D01*
X1334210Y1445524D01*
X1334570Y1445184D01*
X1334569D01*
X1334623Y1443235D01*
X1334283Y1442876D01*
X1334337Y1440925D01*
X1334698Y1440585D01*
X1334752Y1438636D01*
X1334412Y1438277D01*
X1334466Y1436326D01*
X1334827Y1435986D01*
X1334825Y1435985D01*
X1335117Y1425524D01*
X1335118D01*
X1334777Y1425164D01*
X1334832Y1423214D01*
X1335192Y1422874D01*
X1335191D01*
X1335511Y1411400D01*
Y1346310D01*
X1333668Y1344467D01*
X1199778Y1280111D01*
Y1280110D01*
X1194836Y1277735D01*
X1185741Y1268640D01*
X1183992Y1264418D01*
Y1259724D01*
G01X1322402Y1458622D02*
Y1460127D01*
X1322902Y1460627D01*
X1324596D01*
X1325725Y1459498D01*
Y1452895D01*
X1325459Y1448424D01*
X1325460D01*
X1325089Y1448096D01*
X1324973Y1446148D01*
X1325302Y1445778D01*
X1325187Y1443832D01*
X1324816Y1443503D01*
X1324700Y1441556D01*
X1325029Y1441186D01*
X1324914Y1439240D01*
X1324543Y1438911D01*
X1324427Y1436964D01*
X1324756Y1436594D01*
X1324128Y1425999D01*
X1323757Y1425671D01*
X1323641Y1423723D01*
X1323970Y1423353D01*
X1323855Y1421407D01*
X1323484Y1421078D01*
X1323369Y1419131D01*
X1323697Y1418760D01*
X1323271Y1411564D01*
Y1345601D01*
X1320140Y1342470D01*
X1198095Y1284075D01*
Y1284074D01*
X1192321Y1281312D01*
X1182934Y1271924D01*
X1180251Y1265447D01*
Y1259724D01*
G01X1188842D02*
Y1262811D01*
X1190270Y1266258D01*
X1196705Y1272693D01*
X1202789Y1275555D01*
X1203321Y1275364D01*
X1205086Y1276195D01*
X1205278Y1276727D01*
Y1276726D01*
X1346040Y1342960D01*
X1348861Y1345781D01*
Y1412159D01*
X1344713Y1459403D01*
X1342379Y1461737D01*
X1340225D01*
X1339725Y1462237D01*
Y1463741D01*
G01X1331063Y1468071D02*
Y1466567D01*
X1331563Y1466067D01*
X1333717D01*
X1335496Y1464288D01*
Y1451805D01*
X1336621Y1411416D01*
Y1345850D01*
X1334319Y1343548D01*
X1202737Y1280301D01*
X1202550Y1279767D01*
X1200792Y1278922D01*
X1200258Y1279109D01*
X1195487Y1276816D01*
X1186682Y1268011D01*
X1185102Y1264197D01*
Y1259724D01*
G01X1305079Y1463741D02*
Y1462237D01*
X1305579Y1461737D01*
X1307733D01*
X1309512Y1459958D01*
Y1453709D01*
X1299901Y1412557D01*
Y1345477D01*
X1294748Y1340324D01*
X1189807Y1288358D01*
X1177460Y1276011D01*
X1173881Y1267370D01*
Y1259812D01*
G01X1365709Y1462953D02*
Y1464457D01*
X1366209Y1464957D01*
X1367903D01*
X1369032Y1463828D01*
Y1447538D01*
X1368968Y1445590D01*
X1368605Y1445251D01*
X1368540Y1443302D01*
X1368878Y1442940D01*
X1368814Y1440992D01*
X1368451Y1440653D01*
X1368386Y1438704D01*
X1368724Y1438342D01*
X1368660Y1436394D01*
X1368297Y1436055D01*
X1368233Y1434105D01*
X1368571Y1433744D01*
X1368275Y1424829D01*
X1369119Y1344321D01*
X1367835Y1341219D01*
X1361626Y1335608D01*
X1359483Y1334622D01*
X1358886Y1334842D01*
X1357114Y1334027D01*
X1356893Y1333429D01*
X1199985Y1261185D01*
X1198952Y1260152D01*
Y1259512D01*
G01X1357047Y1463741D02*
Y1462237D01*
X1357547Y1461737D01*
X1359701D01*
X1361480Y1459958D01*
X1365255Y1408248D01*
X1365931Y1346216D01*
X1364680Y1343622D01*
X1359190Y1338130D01*
X1212665Y1270659D01*
X1212469Y1270129D01*
X1210697Y1269312D01*
X1210166Y1269508D01*
X1199699Y1264689D01*
X1198654Y1263645D01*
X1196322Y1261313D01*
Y1259724D01*
G01X1348386Y1462953D02*
Y1464457D01*
X1348886Y1464957D01*
X1350580D01*
X1351709Y1463828D01*
Y1456033D01*
X1353027Y1448566D01*
X1352703Y1448103D01*
X1353042Y1446182D01*
X1353506Y1445857D01*
X1353845Y1443937D01*
X1353520Y1443474D01*
X1353859Y1441552D01*
X1354324Y1441228D01*
X1354323D01*
X1357098Y1425513D01*
X1356855Y1425165D01*
X1357194Y1423244D01*
X1357542Y1423000D01*
X1360230Y1407778D01*
X1360915Y1349650D01*
X1359105Y1345292D01*
X1356545Y1342756D01*
X1197521Y1269582D01*
X1192506Y1264565D01*
X1191472Y1262070D01*
Y1259724D01*
G01X1365709Y1468071D02*
Y1466567D01*
X1366209Y1466067D01*
X1368363D01*
X1370142Y1464288D01*
Y1447519D01*
X1369386Y1424816D01*
X1370232Y1344106D01*
X1368765Y1340563D01*
X1362245Y1334670D01*
X1205957Y1262712D01*
X1205737Y1262114D01*
X1203965Y1261299D01*
X1203368Y1261519D01*
X1200630Y1260259D01*
X1200062Y1259692D01*
Y1259512D01*
G01X1195212Y1259724D02*
Y1261773D01*
X1199054Y1265615D01*
X1358545Y1339056D01*
X1363762Y1344274D01*
X1364818Y1346464D01*
X1364145Y1408201D01*
X1363218Y1420904D01*
X1362866Y1421208D01*
X1362720Y1423196D01*
X1363024Y1423548D01*
X1362883Y1425492D01*
X1362507Y1425815D01*
X1362365Y1427761D01*
X1362689Y1428136D01*
X1361872Y1439332D01*
X1361497Y1439655D01*
X1361355Y1441601D01*
X1361679Y1441976D01*
X1361537Y1443920D01*
X1361538D01*
X1361163Y1444243D01*
X1361021Y1446189D01*
X1361344Y1446564D01*
X1361203Y1448508D01*
X1360828Y1448831D01*
X1360686Y1450777D01*
X1361009Y1451152D01*
X1360403Y1459465D01*
X1359241Y1460627D01*
X1357547D01*
X1357047Y1460127D01*
Y1458622D01*
G01X1192582Y1259724D02*
Y1261849D01*
X1193447Y1263936D01*
X1198166Y1268656D01*
X1357188Y1341829D01*
X1360045Y1344660D01*
X1362028Y1349435D01*
X1361339Y1407882D01*
X1352819Y1456131D01*
Y1464288D01*
X1351040Y1466067D01*
X1348886D01*
X1348386Y1466567D01*
Y1468071D01*
G01X1570016Y1259895D02*
Y1260325D01*
X1569824Y1260613D01*
X1565612Y1262357D01*
X1453832Y1336629D01*
X1450636Y1340655D01*
X1448191Y1347442D01*
X1448619Y1387269D01*
X1460472Y1421935D01*
X1467432Y1431785D01*
X1467348Y1432278D01*
X1468586Y1434029D01*
X1469078Y1434114D01*
X1470203Y1435706D01*
X1470108Y1436263D01*
X1471292Y1437938D01*
X1471849Y1438034D01*
X1472974Y1439626D01*
X1472887Y1440133D01*
X1474113Y1441867D01*
X1474620Y1441954D01*
X1475744Y1443546D01*
X1475647Y1444117D01*
X1476821Y1445777D01*
X1477390Y1445875D01*
X1481756Y1452052D01*
Y1474687D01*
X1480447Y1475996D01*
X1478989D01*
X1478307Y1475314D01*
Y1473977D01*
G01X1571126Y1259895D02*
Y1260662D01*
X1570560Y1261510D01*
X1566137Y1263342D01*
X1454593Y1337457D01*
X1451619Y1341203D01*
X1449304Y1347630D01*
X1449728Y1387079D01*
X1461471Y1421425D01*
X1482866Y1451699D01*
Y1475147D01*
X1480907Y1477106D01*
X1478989D01*
X1478307Y1477788D01*
Y1479095D01*
G01X1486968Y1478308D02*
Y1479645D01*
X1487650Y1480327D01*
X1489108D01*
X1490417Y1479018D01*
Y1451938D01*
X1486981Y1447757D01*
X1486348Y1447695D01*
X1485109Y1446187D01*
X1485171Y1445554D01*
X1463698Y1419426D01*
X1452370Y1386303D01*
X1451962Y1348097D01*
X1453700Y1343272D01*
X1456984Y1339133D01*
X1571233Y1263586D01*
X1573756Y1261063D01*
Y1259824D01*
G01X1578606D02*
Y1262164D01*
X1571499Y1269271D01*
X1460463Y1342696D01*
X1458000Y1345800D01*
X1457441Y1347353D01*
X1457440Y1347355D01*
X1456880Y1348910D01*
X1457270Y1385440D01*
X1467937Y1416625D01*
X1500189Y1450886D01*
Y1475147D01*
X1498230Y1477106D01*
X1496312D01*
X1495630Y1477788D01*
Y1479095D01*
G01X1574866Y1259824D02*
Y1261523D01*
X1571939Y1264450D01*
X1457744Y1339962D01*
X1454683Y1343819D01*
X1453075Y1348285D01*
X1453479Y1386113D01*
X1464684Y1418876D01*
X1491527Y1451540D01*
Y1479478D01*
X1489568Y1481437D01*
X1487650D01*
X1486968Y1482119D01*
Y1483426D01*
G01X1495630Y1473977D02*
Y1475314D01*
X1496312Y1475996D01*
X1497770D01*
X1499079Y1474687D01*
Y1451327D01*
X1494696Y1446671D01*
X1494201Y1446656D01*
X1492864Y1445235D01*
X1492879Y1444741D01*
X1491543Y1443322D01*
X1491048Y1443307D01*
X1489711Y1441886D01*
X1489726Y1441391D01*
X1488390Y1439972D01*
X1487824Y1439955D01*
X1486487Y1438534D01*
X1486504Y1437968D01*
X1485168Y1436549D01*
X1484532Y1436529D01*
X1483194Y1435109D01*
X1483213Y1434472D01*
X1466964Y1417211D01*
X1456161Y1385631D01*
X1455767Y1348722D01*
X1456395Y1346979D01*
X1456396Y1346976D01*
X1457017Y1345253D01*
X1459703Y1341867D01*
X1570793Y1268407D01*
X1577496Y1261704D01*
Y1259824D01*
G01X1582346Y1259695D02*
Y1262593D01*
X1575090Y1271618D01*
X1471706Y1343800D01*
X1469745Y1346202D01*
Y1409794D01*
X1471510Y1414050D01*
X1508850Y1451335D01*
Y1479478D01*
X1506891Y1481437D01*
X1504973D01*
X1504291Y1482119D01*
Y1483426D01*
G01X1512953Y1473977D02*
Y1475314D01*
X1513635Y1475996D01*
X1515093D01*
X1516402Y1474687D01*
Y1451015D01*
X1508638Y1442647D01*
X1508002Y1442623D01*
X1506675Y1441193D01*
X1506699Y1440557D01*
X1505373Y1439128D01*
X1504737Y1439104D01*
X1503410Y1437674D01*
X1503434Y1437038D01*
X1502108Y1435609D01*
X1501472Y1435585D01*
X1500145Y1434155D01*
X1500169Y1433519D01*
X1480875Y1412724D01*
Y1345802D01*
X1483051Y1343161D01*
X1576793Y1273853D01*
X1583969Y1264936D01*
X1584976Y1262686D01*
Y1259695D01*
G01X1581236D02*
Y1262202D01*
X1574324Y1270799D01*
X1470944Y1342978D01*
X1468635Y1345806D01*
Y1410016D01*
X1470568Y1414680D01*
X1495555Y1439629D01*
Y1440265D01*
X1496936Y1441644D01*
X1497572D01*
X1507740Y1451796D01*
Y1479018D01*
X1506431Y1480327D01*
X1504973D01*
X1504291Y1479645D01*
Y1478308D01*
G01X1478307Y1560985D02*
Y1562504D01*
X1478807Y1563004D01*
X1480447D01*
X1481756Y1561695D01*
Y1558063D01*
X1491142Y1549138D01*
X1506801Y1539752D01*
X1540222Y1523411D01*
X1549503Y1518135D01*
X1550870Y1515754D01*
X1550901Y1453065D01*
X1543950Y1439700D01*
X1543478Y1439551D01*
X1542578Y1437820D01*
X1542727Y1437348D01*
X1542726D01*
X1541826Y1435620D01*
X1541828Y1435618D01*
X1541356Y1435469D01*
X1540455Y1433738D01*
X1540604Y1433266D01*
X1529835Y1412560D01*
Y1345905D01*
X1531903Y1342279D01*
X1594555Y1283238D01*
X1598291Y1274885D01*
X1599937Y1267182D01*
Y1259695D01*
G01X1478307Y1566103D02*
Y1564614D01*
X1478807Y1564114D01*
X1480907D01*
X1482866Y1562155D01*
Y1558540D01*
X1491818Y1550027D01*
X1507334Y1540728D01*
Y1540729D01*
X1540741Y1524393D01*
X1540744Y1524392D01*
X1550315Y1518951D01*
X1551981Y1516051D01*
X1552012Y1452794D01*
X1530945Y1412288D01*
Y1346200D01*
X1532786Y1342974D01*
X1595478Y1283894D01*
X1599353Y1275232D01*
X1601047Y1267300D01*
Y1259695D01*
G01X1576940Y398082D02*
X1575795Y399227D01*
X1573859D01*
X1573713Y399373D01*
X1547331Y414426D01*
X1502497Y461192D01*
X1497102Y471867D01*
X1491185Y498317D01*
X1485572Y591264D01*
X1487816Y625484D01*
X1492520Y651241D01*
X1607417Y1062754D01*
Y1069176D01*
G01X1584240Y390995D02*
X1583095Y392140D01*
X1575559D01*
X1548059Y405889D01*
X1524931Y424258D01*
X1515312Y430639D01*
X1512731Y432970D01*
X1506280Y435594D01*
X1504416Y437502D01*
X1493390Y471034D01*
X1487000Y497475D01*
X1481552Y590306D01*
X1481556Y590377D01*
X1481557D01*
X1484208Y628237D01*
X1489151Y653821D01*
X1603677Y1063406D01*
Y1068999D01*
G01X1584240Y394395D02*
X1583095Y393250D01*
X1575822D01*
X1571249Y395536D01*
X1571048Y396140D01*
X1569303Y397013D01*
X1568699Y396812D01*
X1566955Y397683D01*
X1566754Y398287D01*
X1565009Y399160D01*
X1564405Y398959D01*
X1562661Y399830D01*
X1562460Y400434D01*
X1560715Y401307D01*
X1560111Y401106D01*
X1558367Y401977D01*
X1558166Y402581D01*
X1556421Y403454D01*
X1555817Y403253D01*
X1554073Y404124D01*
X1553872Y404728D01*
X1552127Y405601D01*
X1551523Y405400D01*
X1548659Y406831D01*
X1545822Y409084D01*
X1545749Y409717D01*
X1544221Y410930D01*
X1543589Y410858D01*
X1542063Y412070D01*
X1541990Y412703D01*
X1540462Y413916D01*
X1539830Y413844D01*
X1538303Y415056D01*
X1538231Y415688D01*
X1536703Y416902D01*
X1536071Y416830D01*
X1525584Y425157D01*
X1515995Y431518D01*
X1513330Y433925D01*
X1506913Y436535D01*
X1505391Y438094D01*
X1494459Y471339D01*
X1488103Y497639D01*
X1482665Y590300D01*
X1485311Y628092D01*
X1490233Y653566D01*
X1604787Y1063253D01*
Y1068999D01*
G01X1576940Y401482D02*
X1575795Y400337D01*
X1574264D01*
X1572571Y401303D01*
X1572403Y401917D01*
X1570708Y402884D01*
X1570094Y402716D01*
X1568401Y403682D01*
X1568233Y404296D01*
X1566538Y405263D01*
X1565925Y405095D01*
X1564232Y406061D01*
X1564064Y406675D01*
X1562369Y407642D01*
X1561756Y407474D01*
X1560063Y408440D01*
X1559895Y409054D01*
X1558200Y410021D01*
X1557586Y409853D01*
X1553515Y412176D01*
X1553347Y412790D01*
X1551653Y413757D01*
X1551039Y413589D01*
X1548022Y415311D01*
X1544099Y419403D01*
X1544112Y420039D01*
X1542762Y421448D01*
X1542125Y421461D01*
X1540776Y422868D01*
X1540789Y423504D01*
X1539439Y424913D01*
X1538803Y424926D01*
X1537454Y426333D01*
X1537467Y426969D01*
X1536117Y428378D01*
X1535481Y428391D01*
X1503413Y461841D01*
X1498156Y472245D01*
X1492288Y498473D01*
X1486685Y591261D01*
X1488920Y625347D01*
X1493603Y650992D01*
X1608527Y1062601D01*
Y1069176D01*
G01X1584240Y408568D02*
X1583095Y407423D01*
X1575981D01*
X1571770Y409584D01*
Y409583D01*
X1571576Y410189D01*
X1569840Y411081D01*
X1569234Y410886D01*
X1567500Y411776D01*
X1567305Y412382D01*
X1565569Y413273D01*
X1564963Y413078D01*
X1563229Y413968D01*
X1563034Y414574D01*
X1561298Y415465D01*
X1560692Y415270D01*
X1558958Y416160D01*
X1558763Y416765D01*
X1557027Y417657D01*
X1556421Y417462D01*
X1554686Y418352D01*
X1554492Y418957D01*
X1552755Y419848D01*
X1552150Y419653D01*
X1548041Y421761D01*
X1546199Y423690D01*
X1546214Y424327D01*
X1544866Y425738D01*
X1544230Y425753D01*
X1542884Y427163D01*
X1542899Y427799D01*
X1541551Y429210D01*
X1540915Y429225D01*
X1539569Y430635D01*
X1539584Y431271D01*
X1538236Y432682D01*
X1537600Y432697D01*
X1505405Y466417D01*
X1501631Y474280D01*
X1497190Y498574D01*
X1490884Y591896D01*
X1493079Y625030D01*
X1497495Y650559D01*
X1612267Y1061946D01*
Y1069000D01*
G01X1584240Y405168D02*
X1583095Y406313D01*
X1575712D01*
X1547367Y420858D01*
X1504480Y465777D01*
X1500565Y473934D01*
X1496086Y498436D01*
X1489771Y591895D01*
X1490873Y608536D01*
X1491975Y625162D01*
X1496410Y650804D01*
X1611157Y1062098D01*
Y1069000D01*
G01X1576940Y412255D02*
X1575795Y413400D01*
X1573635D01*
X1548561Y426947D01*
X1531331Y443630D01*
X1518884Y469148D01*
X1513721Y475434D01*
X1505706Y479749D01*
X1502770Y483320D01*
X1500094Y497447D01*
X1493782Y592455D01*
X1494821Y608768D01*
X1494822D01*
X1495339Y616889D01*
X1495338D01*
X1495339Y616890D01*
X1495861Y625071D01*
X1500197Y650325D01*
X1614897Y1061136D01*
Y1069177D01*
G01X1576940Y415655D02*
X1575795Y414510D01*
X1573916D01*
X1572201Y415436D01*
X1572019Y416046D01*
X1570302Y416974D01*
X1569693Y416792D01*
X1567978Y417718D01*
X1567796Y418328D01*
X1566079Y419256D01*
X1565470Y419074D01*
X1563755Y420000D01*
X1563573Y420610D01*
X1561856Y421538D01*
X1561247Y421356D01*
X1559532Y422282D01*
X1559350Y422892D01*
X1557633Y423820D01*
X1557023Y423638D01*
X1555308Y424564D01*
X1555126Y425174D01*
X1553409Y426102D01*
X1552800Y425920D01*
X1549224Y427852D01*
X1545630Y431331D01*
X1545620Y431967D01*
X1544218Y433325D01*
X1543582Y433315D01*
X1542181Y434671D01*
X1542171Y435307D01*
X1540769Y436665D01*
X1540133Y436654D01*
X1538732Y438010D01*
X1538722Y438646D01*
X1537320Y440004D01*
X1536684Y439993D01*
X1532244Y444292D01*
X1519825Y469752D01*
X1514440Y476308D01*
X1506425Y480623D01*
X1503808Y483806D01*
X1501198Y497588D01*
X1498048Y545023D01*
X1498046Y545024D01*
X1494895Y592456D01*
X1496965Y624941D01*
X1501282Y650081D01*
X1616007Y1060983D01*
Y1069177D01*
G01X1512953Y1479095D02*
Y1477788D01*
X1513635Y1477106D01*
X1515553D01*
X1517512Y1475147D01*
Y1450578D01*
X1481985Y1412288D01*
Y1346201D01*
X1483821Y1343973D01*
X1577569Y1274661D01*
X1584924Y1265520D01*
X1586086Y1262924D01*
Y1259695D01*
G01X1521614Y1483426D02*
Y1482119D01*
X1522296Y1481437D01*
X1524214D01*
X1526173Y1479478D01*
Y1450173D01*
X1494225Y1412288D01*
Y1347285D01*
X1494926Y1345375D01*
X1495691Y1344472D01*
X1580611Y1277546D01*
X1587971Y1268104D01*
X1589826Y1263958D01*
Y1259695D01*
G01X1521614Y1478308D02*
Y1479645D01*
X1522296Y1480327D01*
X1523754D01*
X1525063Y1479018D01*
Y1450579D01*
X1520337Y1444975D01*
X1519703Y1444921D01*
X1518445Y1443429D01*
X1518499Y1442795D01*
X1493115Y1412694D01*
Y1347087D01*
X1493951Y1344807D01*
X1494916Y1343669D01*
X1579818Y1276757D01*
X1587012Y1267527D01*
X1588716Y1263721D01*
Y1259695D01*
G01X1486968Y1565315D02*
Y1566835D01*
X1487468Y1567335D01*
X1489108D01*
X1490417Y1566026D01*
Y1556284D01*
X1493138Y1552602D01*
X1509366Y1542845D01*
X1555506Y1523282D01*
X1558159Y1521407D01*
X1559062Y1520549D01*
X1559940Y1518130D01*
Y1518129D01*
X1560232Y1517324D01*
X1560529Y1458285D01*
X1559374Y1451942D01*
X1559375D01*
X1554297Y1439501D01*
X1553906Y1439336D01*
X1553168Y1437530D01*
X1553332Y1437139D01*
X1552596Y1435334D01*
X1552597D01*
X1552206Y1435170D01*
X1551468Y1433363D01*
X1551632Y1432972D01*
X1542075Y1409554D01*
Y1346381D01*
X1544267Y1342640D01*
X1597822Y1285411D01*
X1601974Y1276126D01*
X1603677Y1268158D01*
Y1259512D01*
G01X1486968Y1570434D02*
Y1568945D01*
X1487468Y1568445D01*
X1489568D01*
X1491527Y1566486D01*
Y1556650D01*
X1493900Y1553440D01*
X1509872Y1543837D01*
X1556050Y1524258D01*
X1558866Y1522268D01*
X1560017Y1521174D01*
X1561342Y1517522D01*
X1561640Y1458188D01*
X1560447Y1451629D01*
Y1451567D01*
X1560403Y1451523D01*
X1543185Y1409336D01*
Y1346683D01*
X1545163Y1343309D01*
X1598760Y1286034D01*
X1603036Y1276473D01*
X1604787Y1268276D01*
Y1259512D01*
G01X1495630Y1560985D02*
Y1562504D01*
X1496130Y1563004D01*
X1497770D01*
X1499079Y1561695D01*
Y1560652D01*
X1504774Y1551505D01*
X1513709Y1545122D01*
X1557447Y1527005D01*
X1561833Y1523471D01*
X1563035Y1521689D01*
X1564039Y1518455D01*
X1564551Y1460213D01*
X1563588Y1451535D01*
X1563589D01*
X1560066Y1436675D01*
X1559644Y1436416D01*
X1559194Y1434517D01*
X1559454Y1434096D01*
X1559005Y1432199D01*
X1558582Y1431939D01*
X1558133Y1430041D01*
X1558392Y1429620D01*
X1554315Y1412418D01*
Y1346416D01*
X1555618Y1342379D01*
X1601030Y1287501D01*
X1605252Y1278992D01*
X1607417Y1269762D01*
Y1259512D01*
G01X1495630Y1566103D02*
Y1564614D01*
X1496130Y1564114D01*
X1498230D01*
X1500189Y1562155D01*
Y1560970D01*
X1505600Y1552280D01*
X1514251Y1546099D01*
X1558020Y1527970D01*
X1562660Y1524231D01*
X1564047Y1522174D01*
X1565148Y1518628D01*
X1565662Y1460156D01*
X1564685Y1451345D01*
X1555425Y1412288D01*
Y1346591D01*
X1556609Y1342923D01*
X1601967Y1288110D01*
X1606304Y1279371D01*
X1608527Y1269891D01*
Y1259512D01*
G01X1584240Y419341D02*
X1583095Y420486D01*
X1574368D01*
X1545720Y435738D01*
X1535366Y445743D01*
X1532068Y451562D01*
X1525187Y481096D01*
X1522572Y484085D01*
X1515613Y486769D01*
X1515420Y487152D01*
X1515421D01*
X1504083Y509734D01*
X1497625Y592559D01*
X1498651Y608789D01*
X1499676Y625001D01*
X1503713Y648527D01*
X1618638Y1060437D01*
Y1069000D01*
G01X1584240Y422741D02*
X1583095Y421596D01*
X1574646D01*
X1572925Y422512D01*
X1572739Y423121D01*
X1571017Y424038D01*
X1570409Y423852D01*
X1568688Y424768D01*
X1568502Y425377D01*
X1566780Y426294D01*
X1566172Y426108D01*
X1564451Y427024D01*
X1564265Y427633D01*
X1562543Y428550D01*
X1561934Y428364D01*
X1560213Y429280D01*
X1560027Y429889D01*
X1558305Y430806D01*
X1557697Y430620D01*
X1555976Y431536D01*
X1555790Y432144D01*
X1554068Y433062D01*
X1553459Y432876D01*
X1551738Y433792D01*
X1551552Y434401D01*
X1549830Y435318D01*
X1549221Y435132D01*
X1546379Y436645D01*
X1544977Y438000D01*
X1544966Y438636D01*
X1543563Y439992D01*
X1542927Y439981D01*
X1541525Y441336D01*
X1541514Y441972D01*
X1540111Y443328D01*
X1539475Y443317D01*
X1536253Y446430D01*
X1533113Y451970D01*
X1526206Y481619D01*
X1523228Y485023D01*
X1516413Y487651D01*
X1505173Y510037D01*
X1498738Y592567D01*
X1500781Y624872D01*
X1504798Y648283D01*
X1619748Y1060285D01*
Y1069000D01*
G01X1576940Y426428D02*
X1575795Y427573D01*
X1574092D01*
X1573942Y427723D01*
X1538791Y447664D01*
X1538370Y448073D01*
X1535611Y452977D01*
X1527295Y489303D01*
X1514059Y520124D01*
Y536942D01*
X1509396Y549858D01*
X1501541Y593180D01*
X1501549Y593314D01*
X1501550D01*
X1503461Y624190D01*
X1507622Y648314D01*
X1622378Y1059776D01*
Y1069176D01*
G01X1576940Y429828D02*
X1575795Y428683D01*
X1574485D01*
X1574489Y428687D01*
Y428689D01*
X1572413Y429867D01*
X1572244Y430480D01*
X1570546Y431443D01*
X1569933Y431274D01*
X1568237Y432236D01*
X1568068Y432849D01*
X1566371Y433812D01*
X1565758Y433643D01*
X1563221Y435082D01*
X1563052Y435695D01*
X1561355Y436658D01*
X1560742Y436489D01*
X1559046Y437451D01*
X1558877Y438064D01*
X1557180Y439027D01*
X1556566Y438858D01*
X1539463Y448560D01*
X1539259Y448758D01*
X1536658Y453382D01*
X1528355Y489649D01*
X1524417Y498819D01*
X1524653Y499410D01*
X1523884Y501203D01*
X1523292Y501439D01*
X1522523Y503230D01*
X1522759Y503821D01*
X1521990Y505614D01*
X1521398Y505850D01*
X1520629Y507641D01*
X1520865Y508232D01*
X1520095Y510025D01*
X1519503Y510261D01*
X1518734Y512052D01*
X1518970Y512643D01*
X1518201Y514436D01*
X1517609Y514672D01*
X1515169Y520353D01*
Y537137D01*
X1510472Y550147D01*
X1502658Y593246D01*
X1504566Y624061D01*
X1508707Y648070D01*
X1623488Y1059624D01*
Y1069176D01*
G01X1584240Y433515D02*
X1583095Y434660D01*
X1575147D01*
X1558601Y441396D01*
X1546412Y449519D01*
X1545761Y449790D01*
X1543983D01*
X1541525Y450923D01*
X1540223Y452451D01*
X1538981Y455114D01*
X1524838Y539070D01*
X1517210Y553504D01*
X1509780Y570047D01*
X1505442Y594454D01*
X1505441D01*
X1505418Y594584D01*
X1507224Y623640D01*
X1511515Y647567D01*
X1626118Y1058368D01*
Y1069000D01*
G01X1576940Y440602D02*
X1575795Y441747D01*
X1573096D01*
X1556370Y448587D01*
X1553219Y451593D01*
X1550814Y456762D01*
X1548225Y460481D01*
X1540920Y476186D01*
X1534432Y505391D01*
X1528672Y540921D01*
X1520838Y555079D01*
X1513802Y571121D01*
X1511585Y583211D01*
Y583212D01*
X1509366Y595311D01*
X1510283Y609377D01*
X1511195Y623365D01*
X1515080Y646036D01*
X1629858Y1057515D01*
Y1069177D01*
G01X1584240Y436915D02*
X1583095Y435770D01*
X1580165D01*
X1579715Y436220D01*
X1577765D01*
X1577315Y435770D01*
X1575365D01*
X1573560Y436505D01*
X1573312Y437092D01*
X1571505Y437828D01*
X1570919Y437581D01*
X1569113Y438316D01*
X1568866Y438903D01*
X1567059Y439639D01*
X1566473Y439392D01*
X1564667Y440127D01*
X1564420Y440714D01*
X1562613Y441449D01*
X1562027Y441202D01*
X1559124Y442383D01*
X1554928Y445179D01*
X1554803Y445803D01*
X1553179Y446885D01*
X1552555Y446760D01*
X1550933Y447841D01*
X1550808Y448465D01*
X1549184Y449547D01*
X1548560Y449422D01*
X1546938Y450503D01*
X1545983Y450900D01*
X1544228D01*
X1542212Y451830D01*
X1541166Y453057D01*
X1540051Y455447D01*
X1537153Y472653D01*
X1537522Y473172D01*
X1537198Y475096D01*
X1536678Y475465D01*
X1536355Y477387D01*
X1536724Y477906D01*
X1536400Y479830D01*
X1535881Y480199D01*
X1525903Y539431D01*
X1518209Y553992D01*
X1510850Y570377D01*
X1506535Y594648D01*
X1508328Y623507D01*
X1512599Y647319D01*
X1627228Y1058216D01*
Y1069000D01*
G01X1576940Y444002D02*
X1575795Y442857D01*
X1573315D01*
X1571511Y443595D01*
X1571264Y444183D01*
X1569459Y444921D01*
X1568872Y444675D01*
X1567068Y445413D01*
X1566821Y446000D01*
X1565015Y446738D01*
X1564429Y446492D01*
X1556985Y449536D01*
X1554138Y452252D01*
X1551781Y457318D01*
X1549192Y461037D01*
X1546030Y467834D01*
X1546248Y468432D01*
X1545425Y470201D01*
X1544827Y470419D01*
X1544005Y472187D01*
X1544223Y472784D01*
X1543400Y474554D01*
X1542802Y474772D01*
X1541978Y476545D01*
X1541460Y478878D01*
X1541802Y479415D01*
X1541379Y481320D01*
X1540841Y481661D01*
X1540419Y483564D01*
X1540760Y484101D01*
X1540337Y486006D01*
X1539800Y486347D01*
X1539378Y488250D01*
X1539719Y488787D01*
X1539296Y490692D01*
X1538759Y491033D01*
X1538337Y492936D01*
X1538678Y493473D01*
X1538255Y495378D01*
X1537718Y495719D01*
X1535523Y505600D01*
X1529737Y541289D01*
X1521834Y555572D01*
X1514871Y571449D01*
X1510483Y595376D01*
X1512299Y623235D01*
X1516165Y645792D01*
X1630968Y1057363D01*
Y1069177D01*
G01X1584240Y469381D02*
X1583095Y470526D01*
X1576209D01*
X1568158Y473033D01*
X1546049Y494002D01*
X1539662Y503906D01*
X1538274Y507516D01*
X1532689Y541787D01*
X1525979Y553631D01*
X1517902Y571525D01*
X1513256Y596701D01*
X1514972Y622860D01*
X1518924Y645427D01*
X1633598Y1056771D01*
Y1069000D01*
G01X1530275Y1473977D02*
Y1475314D01*
X1530957Y1475996D01*
X1532415D01*
X1533724Y1474687D01*
Y1451703D01*
X1524221Y1438621D01*
X1523592Y1438521D01*
X1522445Y1436942D01*
X1522545Y1436314D01*
X1521399Y1434737D01*
X1520771Y1434637D01*
X1519624Y1433058D01*
X1519724Y1432430D01*
X1518578Y1430853D01*
X1517950Y1430753D01*
X1516803Y1429175D01*
X1516902Y1428546D01*
X1505355Y1412649D01*
Y1346381D01*
X1508900Y1341090D01*
X1582159Y1280259D01*
X1590191Y1269677D01*
X1592457Y1264614D01*
Y1259695D01*
G01X1530275Y1479095D02*
Y1477788D01*
X1530957Y1477106D01*
X1532875D01*
X1534834Y1475147D01*
Y1451342D01*
X1506465Y1412288D01*
Y1346719D01*
X1509733Y1341842D01*
X1582966Y1281032D01*
X1591153Y1270247D01*
X1593567Y1264851D01*
Y1259695D01*
G01X1504291Y1565315D02*
Y1566835D01*
X1504791Y1567335D01*
X1506431D01*
X1507740Y1566026D01*
Y1556048D01*
X1510140Y1552751D01*
X1516364Y1548093D01*
X1559950Y1530039D01*
X1564557Y1526286D01*
X1566746Y1523059D01*
X1567808Y1519688D01*
X1568665Y1458780D01*
X1567722Y1447146D01*
X1567386Y1437090D01*
X1567075Y1436800D01*
X1567009Y1434850D01*
X1567299Y1434541D01*
X1567234Y1432593D01*
X1566923Y1432303D01*
X1566858Y1430353D01*
X1567148Y1430043D01*
X1566555Y1412307D01*
Y1346481D01*
X1567919Y1341588D01*
X1605441Y1288710D01*
X1609046Y1280536D01*
X1611157Y1270521D01*
Y1259495D01*
G01X1512953Y1560985D02*
Y1562504D01*
X1513453Y1563004D01*
X1515093D01*
X1516402Y1561695D01*
Y1559583D01*
X1522292Y1552052D01*
X1527024Y1547759D01*
X1561888Y1533331D01*
X1567358Y1528874D01*
X1570165Y1524738D01*
X1571710Y1519829D01*
X1572330Y1473963D01*
X1574814Y1456671D01*
X1576145Y1441826D01*
X1575828Y1441446D01*
X1576002Y1439503D01*
X1576383Y1439186D01*
X1576382D01*
X1576556Y1437244D01*
X1576238Y1436864D01*
X1576413Y1434921D01*
X1576794Y1434604D01*
X1576793D01*
X1578795Y1412288D01*
Y1346231D01*
X1579891Y1343115D01*
X1608978Y1290482D01*
X1613027Y1281177D01*
X1614897Y1272198D01*
Y1259512D01*
G01X1504291Y1570434D02*
Y1568945D01*
X1504791Y1568445D01*
X1506891D01*
X1508850Y1566486D01*
Y1556410D01*
X1510940Y1553540D01*
X1516918Y1549065D01*
X1560526Y1531003D01*
X1565385Y1527044D01*
X1567756Y1523548D01*
X1568916Y1519866D01*
X1569776Y1458743D01*
X1568831Y1447082D01*
X1567665Y1412288D01*
Y1346633D01*
X1568937Y1342073D01*
X1606412Y1289261D01*
X1610109Y1280878D01*
X1612267Y1270637D01*
Y1259495D01*
G01X1512953Y1566103D02*
Y1564614D01*
X1513453Y1564114D01*
X1515553D01*
X1517512Y1562155D01*
Y1559966D01*
X1523109Y1552811D01*
X1527627Y1548711D01*
X1562463Y1534295D01*
X1568186Y1529633D01*
X1571176Y1525227D01*
X1572818Y1520007D01*
X1573439Y1474050D01*
X1575917Y1456800D01*
X1579905Y1412338D01*
Y1346421D01*
X1580908Y1343571D01*
X1609975Y1290973D01*
X1614091Y1281515D01*
X1616007Y1272313D01*
Y1259512D01*
G01X1584240Y472781D02*
X1583095Y471636D01*
X1576378D01*
X1568735Y474016D01*
X1563401Y479075D01*
X1563384Y479711D01*
X1561968Y481054D01*
X1561332Y481038D01*
X1559918Y482379D01*
X1559901Y483016D01*
X1558485Y484358D01*
X1557849Y484342D01*
X1556435Y485683D01*
X1556418Y486320D01*
X1555002Y487662D01*
X1554366Y487645D01*
X1552952Y488986D01*
X1552935Y489623D01*
X1551519Y490965D01*
X1550883Y490949D01*
X1546910Y494716D01*
X1545854Y496354D01*
X1545988Y496976D01*
X1544930Y498616D01*
X1544308Y498751D01*
X1540658Y504412D01*
X1539352Y507808D01*
X1533753Y542161D01*
X1532515Y544347D01*
X1532684Y544960D01*
X1531722Y546658D01*
X1531109Y546828D01*
X1530148Y548524D01*
X1530318Y549137D01*
X1529356Y550835D01*
X1528743Y551005D01*
X1526970Y554134D01*
X1525856Y556602D01*
X1526081Y557198D01*
X1525279Y558976D01*
X1524683Y559201D01*
X1518970Y571859D01*
X1514373Y596766D01*
X1516076Y622728D01*
X1520009Y645181D01*
X1634708Y1056619D01*
Y1069000D01*
G01X1584240Y483554D02*
X1583095Y484699D01*
X1575273D01*
X1557873Y495431D01*
X1555093Y497905D01*
X1546533Y508737D01*
X1545863Y510215D01*
X1539287Y548303D01*
X1535270Y562168D01*
X1525414Y575398D01*
X1524119Y580339D01*
X1526676Y619759D01*
X1529888Y637579D01*
X1641079Y1054845D01*
Y1069000D01*
G01X1576940Y476468D02*
X1575795Y477613D01*
X1574931D01*
X1568061Y480353D01*
X1551482Y495401D01*
X1543233Y505743D01*
X1542491Y507433D01*
X1536306Y543036D01*
X1531005Y561559D01*
X1521998Y573178D01*
X1520279Y579791D01*
X1520289Y579966D01*
X1520290D01*
X1522692Y619118D01*
X1526399Y639472D01*
X1637338Y1055410D01*
Y1069176D01*
G01X1584240Y486954D02*
X1583095Y485809D01*
X1580388D01*
X1579938Y486259D01*
X1577988D01*
X1577538Y485809D01*
X1575588D01*
X1572349Y487807D01*
X1572203Y488426D01*
X1570542Y489451D01*
X1569923Y489304D01*
X1568264Y490327D01*
X1568117Y490946D01*
X1566456Y491971D01*
X1565837Y491824D01*
X1564178Y492847D01*
X1564031Y493467D01*
X1562370Y494491D01*
X1561751Y494345D01*
X1558539Y496326D01*
X1555904Y498670D01*
X1553442Y501786D01*
Y501787D01*
X1553516Y502419D01*
X1552306Y503950D01*
X1551674Y504024D01*
X1550465Y505553D01*
X1550539Y506185D01*
X1549329Y507716D01*
X1548697Y507790D01*
X1547488Y509319D01*
X1546933Y510544D01*
X1546427Y513477D01*
X1546794Y513997D01*
X1546462Y515920D01*
X1545941Y516287D01*
X1545942D01*
X1545611Y518208D01*
X1545978Y518728D01*
X1545646Y520651D01*
X1545125Y521018D01*
X1540371Y548553D01*
X1536281Y562670D01*
X1526434Y575889D01*
X1525239Y580447D01*
X1527780Y619624D01*
X1530973Y637337D01*
X1642189Y1054699D01*
Y1069000D01*
G01X1576940Y479868D02*
X1575795Y478723D01*
X1575145D01*
X1573118Y479531D01*
X1572867Y480117D01*
X1571054Y480839D01*
X1570470Y480588D01*
X1568659Y481310D01*
X1567216Y482620D01*
X1567185Y483256D01*
X1565740Y484567D01*
X1565104Y484537D01*
X1563661Y485847D01*
X1563630Y486483D01*
X1562185Y487794D01*
X1561549Y487764D01*
X1560106Y489074D01*
X1560075Y489710D01*
X1558630Y491021D01*
X1557994Y490991D01*
X1556551Y492301D01*
X1556520Y492937D01*
X1555075Y494248D01*
X1554439Y494218D01*
X1552295Y496164D01*
X1551079Y497688D01*
X1551151Y498320D01*
X1549934Y499846D01*
X1549301Y499917D01*
X1548086Y501441D01*
X1548157Y502073D01*
X1546940Y503599D01*
X1546307Y503670D01*
X1544192Y506322D01*
X1543562Y507756D01*
X1537390Y543285D01*
X1533547Y556714D01*
X1533856Y557270D01*
X1533320Y559146D01*
X1532762Y559455D01*
X1532014Y562071D01*
X1523015Y573678D01*
X1521398Y579899D01*
X1523796Y618984D01*
X1527484Y639229D01*
X1638448Y1055264D01*
Y1069176D01*
G01X1576940Y494041D02*
X1575795Y492896D01*
X1574511D01*
X1572868Y494539D01*
X1571155Y498675D01*
Y505078D01*
X1570404Y506877D01*
X1570646Y507465D01*
X1569894Y509266D01*
X1569304Y509508D01*
X1567149Y514667D01*
X1566058Y516282D01*
X1566179Y516907D01*
X1565086Y518524D01*
X1564461Y518645D01*
X1562076Y522174D01*
X1561246Y523938D01*
X1561461Y524536D01*
X1560629Y526302D01*
X1560030Y526517D01*
X1559200Y528281D01*
X1559415Y528880D01*
X1558584Y530645D01*
X1557985Y530860D01*
X1557056Y532834D01*
X1555726Y537213D01*
X1556026Y537774D01*
X1555459Y539641D01*
X1554896Y539941D01*
X1554330Y541806D01*
X1554629Y542368D01*
X1554063Y544234D01*
X1553500Y544534D01*
X1553501D01*
X1552934Y546399D01*
X1553234Y546961D01*
X1552667Y548828D01*
X1552104Y549127D01*
X1552106D01*
X1551539Y550992D01*
X1551839Y551554D01*
X1551272Y553420D01*
X1550710Y553720D01*
X1550158Y555538D01*
X1541321Y563571D01*
X1537536Y567307D01*
X1530021Y577393D01*
X1529058Y581059D01*
X1531452Y618140D01*
X1534484Y635250D01*
X1645928Y1054128D01*
Y1069177D01*
G01X1576940Y490641D02*
X1575795Y491786D01*
X1574051D01*
X1571927Y493910D01*
X1570045Y498454D01*
Y504855D01*
X1568280Y509079D01*
X1568279Y509081D01*
X1566167Y514137D01*
X1561107Y521623D01*
X1559026Y526043D01*
X1559025Y526045D01*
X1556017Y532434D01*
X1549780Y552957D01*
X1549781D01*
X1549183Y554923D01*
X1540557Y562765D01*
X1536696Y566576D01*
X1529001Y576902D01*
X1527938Y580951D01*
X1527949Y581130D01*
X1527950D01*
X1530348Y618273D01*
X1533399Y635490D01*
X1644818Y1054274D01*
Y1069177D01*
G01X1538937Y1478308D02*
Y1479645D01*
X1539619Y1480327D01*
X1541077D01*
X1542386Y1479018D01*
Y1452338D01*
X1535726Y1441665D01*
X1535727D01*
X1535107Y1441521D01*
X1534073Y1439866D01*
X1534217Y1439246D01*
X1517595Y1412606D01*
Y1345806D01*
X1519692Y1343234D01*
X1585090Y1283812D01*
X1593089Y1272771D01*
X1596197Y1265826D01*
Y1259695D01*
G01X1538937Y1483426D02*
Y1482119D01*
X1539619Y1481437D01*
X1541537D01*
X1543496Y1479478D01*
Y1452020D01*
X1518705Y1412288D01*
Y1346202D01*
X1520500Y1344000D01*
X1585922Y1284557D01*
X1594056Y1273330D01*
X1597307Y1266064D01*
Y1259695D01*
G01X1521614Y1570434D02*
Y1568945D01*
X1522114Y1568445D01*
X1524214D01*
X1526173Y1566486D01*
Y1556136D01*
X1527684Y1553877D01*
X1530362Y1551678D01*
X1564576Y1537509D01*
X1571001Y1532254D01*
X1574718Y1526730D01*
X1576585Y1520762D01*
X1577175Y1477816D01*
X1578040Y1469170D01*
X1583392Y1440673D01*
X1592578Y1407652D01*
X1592880Y1347720D01*
X1595080Y1338620D01*
X1617727Y1284017D01*
X1619748Y1273870D01*
Y1259512D01*
G01X1521614Y1565315D02*
Y1566835D01*
X1522114Y1567335D01*
X1523754D01*
X1525063Y1566026D01*
Y1555799D01*
X1526852Y1553123D01*
X1529784Y1550715D01*
X1564000Y1536546D01*
X1570171Y1531498D01*
X1573706Y1526244D01*
X1575477Y1520585D01*
X1576065Y1477753D01*
X1576940Y1469012D01*
X1582309Y1440421D01*
X1584635Y1432058D01*
X1584392Y1431627D01*
X1584914Y1429747D01*
X1585346Y1429504D01*
X1585868Y1427626D01*
X1585625Y1427195D01*
X1586147Y1425315D01*
X1586579Y1425072D01*
X1591468Y1407498D01*
X1591770Y1347585D01*
X1594021Y1338275D01*
X1616659Y1283693D01*
X1618638Y1273760D01*
Y1259512D01*
G01X1584240Y516915D02*
X1583095Y515770D01*
X1581012D01*
X1580562Y516220D01*
X1578612D01*
X1578162Y515770D01*
X1572899D01*
X1571662Y517277D01*
X1571724Y517910D01*
X1570486Y519418D01*
X1569853Y519480D01*
X1568616Y520987D01*
X1568679Y521620D01*
X1567440Y523128D01*
X1566807Y523191D01*
X1565407Y524896D01*
X1564661Y526697D01*
X1564905Y527285D01*
X1564159Y529088D01*
X1563570Y529331D01*
X1562824Y531132D01*
X1563068Y531720D01*
X1562322Y533523D01*
X1561733Y533766D01*
X1560223Y537412D01*
Y552553D01*
X1559353Y554658D01*
X1555691Y558319D01*
X1552360Y560545D01*
X1552236Y561169D01*
X1550614Y562253D01*
X1549990Y562129D01*
X1548369Y563212D01*
X1548245Y563836D01*
X1546623Y564920D01*
X1545999Y564796D01*
X1544378Y565879D01*
X1540100Y570160D01*
X1538940Y571727D01*
X1539034Y572356D01*
X1537872Y573924D01*
X1537243Y574018D01*
X1533513Y579054D01*
X1532851Y581436D01*
X1535191Y617686D01*
X1538157Y634420D01*
X1649669Y1053564D01*
Y1069000D01*
G01X1584240Y513515D02*
X1583095Y514660D01*
X1572374D01*
X1564444Y524319D01*
X1560884Y532914D01*
X1560883Y532915D01*
X1559113Y537191D01*
Y552332D01*
X1558411Y554029D01*
X1554983Y557457D01*
X1543670Y565017D01*
X1539257Y569433D01*
X1532498Y578558D01*
X1531731Y581320D01*
X1534087Y617819D01*
X1537072Y634660D01*
X1648559Y1053710D01*
Y1069000D01*
G01X1576940Y520602D02*
X1575795Y521747D01*
X1574720D01*
X1573492Y522256D01*
X1573074Y522674D01*
X1567496Y527956D01*
X1562873Y539122D01*
Y553989D01*
X1559549Y562015D01*
X1552058Y568805D01*
X1550457Y571200D01*
X1548768Y572889D01*
X1540021Y575693D01*
X1538338Y577105D01*
X1537467Y578169D01*
X1535526Y581735D01*
X1537836Y617248D01*
X1540711Y633482D01*
X1652299Y1053143D01*
Y1069176D01*
G01X1576940Y524002D02*
X1575795Y522857D01*
X1574941D01*
X1574121Y523197D01*
X1573848Y523470D01*
X1572286Y524949D01*
X1572269Y525586D01*
X1570852Y526928D01*
X1570216Y526910D01*
X1568432Y528600D01*
X1567657Y530473D01*
X1567900Y531061D01*
X1567154Y532863D01*
X1566566Y533107D01*
X1565820Y534908D01*
X1566064Y535496D01*
X1565318Y537298D01*
X1564729Y537542D01*
X1563983Y539343D01*
Y544610D01*
X1564433Y545060D01*
Y547010D01*
X1563983Y547460D01*
Y549410D01*
X1564433Y549860D01*
Y551810D01*
X1563983Y552260D01*
Y554210D01*
X1562421Y557982D01*
X1562665Y558570D01*
X1561919Y560373D01*
X1561331Y560616D01*
X1560480Y562671D01*
X1559036Y563980D01*
X1559004Y564616D01*
X1557558Y565926D01*
X1556923Y565895D01*
X1552905Y569536D01*
X1551319Y571908D01*
X1549363Y573864D01*
X1547507Y574459D01*
X1547216Y575026D01*
X1545358Y575621D01*
X1544792Y575330D01*
X1540568Y576684D01*
X1539131Y577889D01*
X1538393Y578792D01*
X1536655Y581984D01*
X1538940Y617115D01*
X1541796Y633242D01*
X1653409Y1052997D01*
Y1069176D01*
G01X1584240Y531088D02*
X1583086Y529934D01*
X1583062Y529943D01*
X1580539D01*
X1580089Y530393D01*
X1578139D01*
X1577689Y529943D01*
X1575739D01*
X1572582Y531251D01*
X1572139Y531672D01*
X1571306Y533434D01*
X1571520Y534033D01*
X1570685Y535797D01*
X1570086Y536012D01*
Y536013D01*
X1568194Y540013D01*
Y546344D01*
X1568644Y546794D01*
Y548744D01*
X1568194Y549194D01*
Y551144D01*
X1568644Y551594D01*
Y553544D01*
X1568194Y553994D01*
Y555944D01*
X1566940Y558973D01*
X1567183Y559561D01*
X1566437Y561363D01*
X1565848Y561607D01*
Y561608D01*
X1564735Y564295D01*
X1560973Y568057D01*
X1555367Y572656D01*
X1554137Y574492D01*
X1551170Y577459D01*
X1546459Y579410D01*
X1544513D01*
X1543336Y579753D01*
X1542775Y580034D01*
X1541489Y581000D01*
X1540494Y583069D01*
X1541141Y592819D01*
X1541140D01*
X1541620Y593238D01*
X1541749Y595185D01*
X1541330Y595664D01*
X1541459Y597609D01*
X1541893Y597989D01*
X1542028Y600020D01*
X1541648Y600454D01*
X1541777Y602399D01*
X1542150Y602725D01*
X1542279Y604672D01*
X1541953Y605044D01*
X1542081Y606989D01*
X1542398Y607266D01*
X1542534Y609319D01*
X1542258Y609634D01*
X1542744Y616984D01*
X1545544Y632704D01*
X1657149Y1052101D01*
Y1069000D01*
G01X1584240Y527688D02*
X1583095Y528833D01*
X1575518D01*
X1571966Y530304D01*
X1571224Y531010D01*
X1567190Y539539D01*
X1567084Y539645D01*
Y555723D01*
X1563794Y563666D01*
X1560227Y567233D01*
X1554535Y571901D01*
X1553275Y573784D01*
X1550541Y576518D01*
X1546238Y578300D01*
X1544354D01*
X1542929Y578715D01*
X1542188Y579086D01*
X1540605Y580274D01*
X1539367Y582851D01*
X1541640Y617118D01*
X1544459Y632944D01*
X1656039Y1052247D01*
Y1068491D01*
X1656037Y1068493D01*
Y1068495D01*
X1656039Y1068497D01*
Y1069000D01*
G01X1530275Y1566103D02*
Y1564614D01*
X1530775Y1564114D01*
X1532875D01*
X1534834Y1562155D01*
Y1558783D01*
X1538613Y1553128D01*
X1540527Y1551556D01*
X1567439Y1540411D01*
X1573421Y1535501D01*
X1578082Y1528525D01*
X1580713Y1520697D01*
X1581370Y1478990D01*
X1585959Y1448849D01*
X1596407Y1409312D01*
X1596711Y1349168D01*
X1598911Y1340068D01*
X1621069Y1286644D01*
X1623488Y1274500D01*
Y1259612D01*
G01X1530275Y1560985D02*
Y1562504D01*
X1530775Y1563004D01*
X1532415D01*
X1533724Y1561695D01*
Y1558446D01*
X1537781Y1552375D01*
X1539949Y1550593D01*
X1566862Y1539448D01*
X1572589Y1534747D01*
X1577077Y1528031D01*
X1579605Y1520507D01*
X1580261Y1478897D01*
X1584870Y1448623D01*
X1588164Y1436156D01*
X1587915Y1435728D01*
X1588413Y1433842D01*
X1588842Y1433593D01*
X1589340Y1431708D01*
X1589091Y1431280D01*
X1589589Y1429394D01*
X1590018Y1429145D01*
X1590017D01*
X1595297Y1409165D01*
X1595601Y1349033D01*
X1597852Y1339723D01*
X1620001Y1286320D01*
X1622378Y1274390D01*
Y1259612D01*
G01X1538937Y1565315D02*
Y1566835D01*
X1539437Y1567335D01*
X1541077D01*
X1542386Y1566026D01*
Y1555577D01*
X1543639Y1553362D01*
X1569440Y1542449D01*
X1574823Y1538297D01*
X1580308Y1530539D01*
X1583695Y1520894D01*
X1584891Y1481821D01*
X1587197Y1461375D01*
X1587196D01*
X1587206Y1461294D01*
X1592579Y1441090D01*
X1592260Y1440539D01*
X1592761Y1438654D01*
X1593313Y1438335D01*
X1593312D01*
X1599053Y1416750D01*
X1599390Y1349965D01*
X1601641Y1340655D01*
X1623616Y1287672D01*
X1626118Y1275112D01*
Y1259712D01*
G01X1538937Y1570434D02*
Y1568945D01*
X1539437Y1568445D01*
X1541537D01*
X1543496Y1566486D01*
Y1555870D01*
X1544420Y1554238D01*
X1570005Y1543416D01*
X1575634Y1539075D01*
X1581305Y1531054D01*
X1581306Y1531053D01*
X1581304D01*
X1584800Y1521100D01*
X1586000Y1481900D01*
X1588300Y1461500D01*
X1600163Y1416898D01*
X1600500Y1350100D01*
X1602700Y1341000D01*
X1624684Y1287996D01*
X1627228Y1275222D01*
Y1259712D01*
G01X1576940Y534775D02*
X1575795Y535920D01*
X1574311D01*
X1572096Y538135D01*
X1571605Y539321D01*
Y556025D01*
X1566795Y567778D01*
X1557338Y577086D01*
X1554754Y578144D01*
X1553523Y579356D01*
X1551696Y583461D01*
X1551695Y583468D01*
X1550150Y602410D01*
X1550148D01*
X1548075Y627849D01*
X1548077Y627918D01*
X1548078D01*
X1548237Y631549D01*
X1659530Y1049597D01*
X1659779Y1051495D01*
Y1069177D01*
G01X1576940Y538175D02*
X1575795Y537030D01*
X1574771D01*
X1573037Y538764D01*
X1572715Y539542D01*
Y541975D01*
X1573165Y542425D01*
Y544375D01*
X1572715Y544825D01*
Y549075D01*
X1573165Y549525D01*
Y551475D01*
X1572715Y551925D01*
Y556244D01*
X1571959Y558092D01*
X1572205Y558679D01*
X1571467Y560485D01*
X1570879Y560731D01*
X1570141Y562535D01*
X1570387Y563122D01*
X1569649Y564928D01*
X1569061Y565174D01*
X1567737Y568410D01*
X1566348Y569777D01*
X1566342Y570414D01*
X1564952Y571782D01*
X1564315Y571777D01*
X1562926Y573144D01*
X1562920Y573781D01*
X1561530Y575149D01*
X1560894Y575145D01*
X1557961Y578031D01*
X1555377Y579089D01*
X1554452Y580000D01*
X1552787Y583746D01*
X1551880Y594869D01*
X1552292Y595354D01*
X1552133Y597299D01*
X1551647Y597711D01*
X1551489Y599654D01*
X1551901Y600139D01*
X1551742Y602084D01*
X1551256Y602496D01*
X1549187Y627870D01*
X1549341Y631380D01*
X1660622Y1049381D01*
X1660889Y1051422D01*
Y1069177D01*
G01X1651535Y1596811D02*
Y1595504D01*
X1652217Y1594822D01*
X1654135D01*
X1656094Y1592863D01*
Y1557310D01*
X1655791Y1554613D01*
X1653790Y1552762D01*
X1634340Y1540690D01*
X1626010Y1532270D01*
X1619250Y1516930D01*
X1608211Y1412240D01*
X1608210D01*
X1606710Y1353150D01*
X1607620Y1345761D01*
X1660889Y1265247D01*
Y1259600D01*
G01X1651535Y1591693D02*
Y1593030D01*
X1652217Y1593712D01*
X1653675D01*
X1654984Y1592403D01*
Y1557373D01*
X1654733Y1555148D01*
X1653114Y1553649D01*
X1633643Y1541564D01*
X1625076Y1532906D01*
X1618164Y1517219D01*
X1610148Y1441203D01*
X1609762Y1440892D01*
X1609558Y1438952D01*
X1609869Y1438567D01*
X1609665Y1436628D01*
X1609335Y1436361D01*
X1609130Y1434421D01*
X1609397Y1434091D01*
X1609193Y1432152D01*
X1608862Y1431885D01*
X1608658Y1429945D01*
X1608925Y1429615D01*
X1607105Y1412356D01*
X1607101Y1412312D01*
X1605598Y1353096D01*
X1606550Y1345366D01*
X1659779Y1264913D01*
Y1259600D01*
G01X1660196Y1601142D02*
Y1599835D01*
X1660878Y1599153D01*
X1662796D01*
X1664755Y1597194D01*
Y1558250D01*
X1663615Y1556226D01*
X1658870Y1551551D01*
X1637151Y1537621D01*
X1629188Y1530123D01*
X1622953Y1514614D01*
X1619773Y1412710D01*
Y1346201D01*
X1664631Y1267413D01*
X1664630Y1267412D01*
Y1259600D01*
G01X1663520D02*
Y1267120D01*
X1618663Y1345907D01*
Y1412728D01*
X1619266Y1432075D01*
X1618927Y1432436D01*
X1618988Y1434386D01*
X1619349Y1434725D01*
X1621849Y1514846D01*
X1628249Y1530764D01*
X1636465Y1538500D01*
X1658173Y1552423D01*
X1662724Y1556908D01*
X1663645Y1558542D01*
Y1596734D01*
X1662336Y1598043D01*
X1660878D01*
X1660196Y1597361D01*
Y1596024D01*
G01X1668858Y1596811D02*
Y1595504D01*
X1669540Y1594822D01*
X1671458D01*
X1673417Y1592863D01*
Y1555770D01*
X1672320Y1553400D01*
X1670381Y1552090D01*
X1639603Y1534677D01*
X1632410Y1527905D01*
X1627120Y1514747D01*
X1627303Y1447868D01*
X1632013Y1412785D01*
Y1346628D01*
X1668370Y1268953D01*
Y1259600D01*
G01X1668858Y1591693D02*
Y1593030D01*
X1669540Y1593712D01*
X1670998D01*
X1672307Y1592403D01*
Y1556015D01*
X1671442Y1554147D01*
X1669796Y1553035D01*
X1652705Y1543366D01*
X1652091Y1543536D01*
X1650393Y1542575D01*
X1650223Y1541962D01*
X1638939Y1535578D01*
X1631471Y1528546D01*
X1626009Y1514960D01*
X1626193Y1447792D01*
X1627872Y1435281D01*
X1627486Y1434775D01*
X1627746Y1432841D01*
X1628252Y1432455D01*
X1630903Y1412710D01*
Y1346381D01*
X1667260Y1268706D01*
Y1259600D01*
G01X1635265Y470737D02*
X1636410Y469592D01*
X1638294D01*
X1640096Y470338D01*
Y470337D01*
X1640340Y470926D01*
X1642143Y471672D01*
X1642731Y471428D01*
X1644531Y472173D01*
X1644532D01*
X1644776Y472762D01*
X1646579Y473508D01*
X1647167Y473264D01*
X1648967Y474009D01*
X1648968D01*
X1649212Y474598D01*
X1651015Y475344D01*
X1651603Y475100D01*
X1656729Y477222D01*
X1662629Y483103D01*
X1670307Y488828D01*
X1670398Y489458D01*
X1671962Y490624D01*
X1672592Y490532D01*
X1674155Y491697D01*
X1674246Y492327D01*
X1675811Y493494D01*
X1676440Y493402D01*
X1678003Y494567D01*
X1678094Y495197D01*
X1679659Y496364D01*
X1680288Y496272D01*
X1706648Y515927D01*
X1709506Y519683D01*
X1721562Y573338D01*
X1723117Y589940D01*
X1724897Y663489D01*
X1722273Y913004D01*
X1728320Y942075D01*
X1762562Y1059683D01*
X1761848Y1077344D01*
X1751636Y1095375D01*
X1715982Y1129802D01*
X1711525Y1132614D01*
X1701672D01*
G01Y1133724D02*
X1711846D01*
X1716671Y1130680D01*
X1752523Y1096062D01*
X1762947Y1077658D01*
X1763679Y1059547D01*
X1729398Y941806D01*
X1723385Y912895D01*
X1726008Y663481D01*
X1724226Y589875D01*
X1722661Y573164D01*
X1710536Y519203D01*
X1707437Y515130D01*
X1663357Y482260D01*
X1657357Y476280D01*
X1638516Y468482D01*
X1636410D01*
X1635265Y467337D01*
G01X1701772Y1122503D02*
X1706994D01*
X1711701Y1119774D01*
X1743223Y1089219D01*
X1751671Y1074239D01*
X1752118Y1061194D01*
X1718479Y946021D01*
X1711700Y914163D01*
X1714278Y663001D01*
X1712456Y590658D01*
X1710882Y579529D01*
X1710883D01*
X1709276Y568174D01*
X1696547Y551590D01*
X1695217Y547870D01*
X1686407Y542030D01*
X1661397Y500170D01*
X1657938Y496797D01*
X1645149Y491482D01*
X1636149Y489742D01*
X1629110D01*
X1627965Y488597D01*
G01X1701772Y1129984D02*
X1709843D01*
X1710110Y1129821D01*
Y1129820D01*
X1715648Y1126420D01*
X1749521Y1093732D01*
X1759239Y1076270D01*
X1759837Y1060150D01*
X1725252Y941705D01*
X1719558Y913768D01*
X1722168Y663520D01*
X1720166Y590143D01*
X1719149Y576190D01*
X1709592Y532374D01*
X1707527Y529160D01*
X1698597Y524190D01*
X1696907Y522500D01*
X1688437Y517830D01*
X1666927Y492890D01*
X1658097Y484160D01*
X1637464Y475569D01*
X1629110D01*
X1627965Y474424D01*
G01X1635265Y484910D02*
X1636410Y483765D01*
X1638654D01*
X1640454Y484513D01*
X1640697Y485102D01*
X1642499Y485851D01*
X1643087Y485608D01*
X1644887Y486356D01*
X1645130Y486945D01*
X1646932Y487694D01*
X1647520Y487451D01*
X1649320Y488199D01*
X1649563Y488788D01*
X1651365Y489536D01*
X1651953Y489294D01*
X1656806Y491310D01*
X1664113Y498666D01*
X1669734Y507089D01*
X1669609Y507713D01*
X1670693Y509336D01*
X1671317Y509460D01*
X1671316D01*
X1672398Y511081D01*
X1672273Y511706D01*
X1673357Y513329D01*
X1673981Y513453D01*
X1675063Y515074D01*
X1674938Y515699D01*
X1676022Y517322D01*
X1676646Y517446D01*
X1683975Y528428D01*
X1700844Y545275D01*
X1711667Y565520D01*
X1715217Y590490D01*
X1717167Y663218D01*
X1714385Y914047D01*
X1720907Y944691D01*
X1754927Y1061058D01*
X1754285Y1075091D01*
X1745327Y1090881D01*
X1712890Y1122312D01*
X1707440Y1125133D01*
X1701672D01*
G01X1701772Y1128874D02*
X1709529D01*
X1714964Y1125537D01*
X1748631Y1093048D01*
X1758139Y1075963D01*
X1758721Y1060289D01*
X1724173Y941972D01*
X1718446Y913874D01*
X1721057Y663529D01*
X1719057Y590199D01*
X1718047Y576350D01*
X1708550Y532806D01*
X1706743Y529995D01*
X1697922Y525085D01*
X1696233Y523396D01*
X1687726Y518707D01*
X1675682Y504741D01*
X1675188Y504705D01*
X1673914Y503227D01*
X1673950Y502733D01*
X1672677Y501257D01*
X1672183Y501221D01*
X1670909Y499743D01*
X1670945Y499249D01*
X1669672Y497773D01*
X1669179Y497737D01*
X1667904Y496259D01*
X1667940Y495766D01*
X1666115Y493649D01*
X1657470Y485102D01*
X1654970Y484061D01*
X1654381Y484304D01*
X1652580Y483554D01*
X1652338Y482965D01*
X1650538Y482216D01*
X1649949Y482459D01*
X1648148Y481709D01*
X1647906Y481120D01*
X1646106Y480371D01*
X1645517Y480613D01*
X1643716Y479863D01*
X1643474Y479274D01*
X1641674Y478525D01*
X1641085Y478767D01*
X1639284Y478018D01*
X1639042Y477428D01*
Y477429D01*
X1637242Y476679D01*
X1629110D01*
X1627965Y477824D01*
G01X1635265Y481510D02*
X1636410Y482655D01*
X1638876D01*
X1657437Y490370D01*
X1664977Y497960D01*
X1684837Y527720D01*
X1701746Y544606D01*
X1712739Y565169D01*
X1716325Y590397D01*
X1718278Y663209D01*
X1715497Y913936D01*
X1721984Y944419D01*
X1756045Y1060924D01*
X1755382Y1075407D01*
X1746215Y1091568D01*
X1713545Y1123223D01*
X1707950Y1126119D01*
X1707826Y1126243D01*
X1701672D01*
G01X1701772Y1121393D02*
X1706695D01*
X1711026Y1118882D01*
X1742334Y1088533D01*
X1750570Y1073930D01*
X1751002Y1061334D01*
X1717401Y946293D01*
X1710588Y914274D01*
X1713167Y663009D01*
X1711347Y590750D01*
X1708217Y568619D01*
X1695560Y552128D01*
X1694295Y548592D01*
X1685583Y542816D01*
X1672769Y521370D01*
X1672152Y521215D01*
X1671151Y519540D01*
X1671307Y518922D01*
X1670307Y517249D01*
X1669690Y517094D01*
X1668689Y515419D01*
X1668845Y514801D01*
X1667845Y513128D01*
X1667846D01*
X1667229Y512973D01*
X1666227Y511298D01*
X1666383Y510681D01*
X1663625Y506064D01*
X1663008Y505908D01*
X1662006Y504233D01*
X1662162Y503616D01*
X1660518Y500864D01*
X1657318Y497743D01*
X1649889Y494656D01*
X1649301Y494899D01*
X1647500Y494151D01*
X1647257Y493562D01*
Y493561D01*
X1644827Y492551D01*
X1641825Y491971D01*
X1641298Y492327D01*
X1639383Y491957D01*
X1639026Y491429D01*
X1636042Y490852D01*
X1629110D01*
X1627965Y491997D01*
G01X1701644Y1113913D02*
X1704200D01*
X1707467Y1111764D01*
X1736402Y1083637D01*
X1743106Y1071771D01*
X1743310Y1064056D01*
X1713289Y961436D01*
X1702953Y918738D01*
X1698872Y876454D01*
X1690163Y632789D01*
X1684727Y596063D01*
X1684726Y596062D01*
Y596060D01*
X1679290Y559337D01*
X1676895Y548180D01*
X1675850Y545744D01*
X1673224Y541749D01*
X1668414Y538275D01*
X1667786Y538376D01*
X1666204Y537233D01*
X1666103Y536605D01*
X1662859Y534262D01*
X1659231Y532441D01*
X1658627Y532642D01*
X1656883Y531766D01*
X1656682Y531162D01*
X1654940Y530288D01*
X1654335Y530488D01*
X1652592Y529612D01*
X1652391Y529008D01*
X1650649Y528134D01*
X1650045Y528335D01*
X1648301Y527459D01*
X1648100Y526855D01*
X1646358Y525981D01*
X1645754Y526181D01*
X1644011Y525305D01*
X1643810Y524701D01*
X1642068Y523827D01*
X1641464Y524027D01*
X1639720Y523151D01*
X1639520Y522547D01*
X1639519Y522548D01*
X1636063Y520813D01*
X1629110D01*
X1627965Y521958D01*
G01X1701672Y1117653D02*
X1705707D01*
X1709653Y1114884D01*
X1739337Y1086190D01*
X1746835Y1072815D01*
X1747213Y1062070D01*
X1714066Y948661D01*
X1706647Y914414D01*
X1709017Y662730D01*
X1707577Y596660D01*
X1706387Y593920D01*
X1698117Y589790D01*
X1693767Y584890D01*
X1688877Y583720D01*
X1687057Y581807D01*
X1682509Y551446D01*
X1679601Y544078D01*
X1676551Y539579D01*
X1668772Y532626D01*
X1668136Y532661D01*
X1666682Y531361D01*
X1666646Y530725D01*
X1661807Y526400D01*
X1659981Y525436D01*
X1659373Y525623D01*
X1657647Y524711D01*
X1657460Y524103D01*
X1655736Y523193D01*
X1655128Y523380D01*
X1653402Y522468D01*
X1653215Y521860D01*
X1651491Y520950D01*
X1650882Y521137D01*
X1649157Y520226D01*
X1648970Y519617D01*
X1647246Y518707D01*
X1646637Y518894D01*
X1644912Y517983D01*
X1644725Y517374D01*
X1643001Y516464D01*
X1642393Y516652D01*
X1640668Y515740D01*
X1640481Y515132D01*
X1637820Y513726D01*
X1636410D01*
X1635265Y514871D01*
G01X1701672Y1118763D02*
X1706059D01*
X1710362Y1115743D01*
X1740226Y1086875D01*
X1747935Y1073123D01*
X1748329Y1061930D01*
X1715143Y948387D01*
X1707759Y914300D01*
X1710128Y662723D01*
X1708683Y596418D01*
X1707245Y593107D01*
X1698805Y588892D01*
X1694366Y583891D01*
X1694025Y583809D01*
Y583810D01*
X1689454Y582716D01*
X1688103Y581296D01*
X1683588Y551156D01*
X1680589Y543557D01*
X1677394Y538842D01*
X1669512Y531798D01*
Y531797D01*
X1662446Y525482D01*
X1638096Y512616D01*
X1636410D01*
X1635265Y511471D01*
G01X1701644Y1115023D02*
X1704533D01*
X1708166Y1112634D01*
X1737290Y1084322D01*
X1744209Y1072077D01*
X1744425Y1063911D01*
X1714362Y961149D01*
X1704051Y918553D01*
X1699981Y876381D01*
X1691271Y632688D01*
X1685825Y595900D01*
X1685826D01*
X1680383Y559139D01*
X1677958Y547842D01*
X1676832Y545216D01*
X1674152Y541139D01*
Y541138D01*
X1674040Y540968D01*
X1663437Y533310D01*
X1636327Y519703D01*
X1629110D01*
X1627965Y518558D01*
G01Y536131D02*
X1629110Y534986D01*
X1636685D01*
X1639271Y536038D01*
Y536037D01*
X1639518Y536625D01*
X1641326Y537359D01*
X1641912Y537112D01*
X1643718Y537846D01*
X1643965Y538433D01*
X1645772Y539168D01*
X1646359Y538921D01*
X1648165Y539655D01*
X1648357Y540111D01*
X1650165Y540847D01*
X1650621Y540654D01*
X1653963Y542013D01*
X1655332Y543401D01*
X1655328Y543896D01*
X1656699Y545285D01*
X1657194Y545289D01*
X1658835Y546953D01*
X1660258Y549374D01*
Y550892D01*
X1661515Y553926D01*
X1664946Y557357D01*
X1665513Y558323D01*
X1666983Y564778D01*
X1666644Y565317D01*
X1667077Y567219D01*
X1667617Y567558D01*
X1668048Y569455D01*
X1668049Y569459D01*
X1667711Y569998D01*
X1668144Y571900D01*
X1668683Y572239D01*
X1669114Y574136D01*
X1669115Y574140D01*
X1668777Y574679D01*
X1669210Y576581D01*
X1669749Y576920D01*
X1682278Y631936D01*
X1682279Y631940D01*
X1696271Y1042746D01*
X1698844Y1060901D01*
X1703850Y1087918D01*
X1703509Y1103966D01*
X1702601Y1106085D01*
X1702252Y1106433D01*
X1701772D01*
G01X1701672Y1110173D02*
X1702955D01*
X1705178Y1108686D01*
X1706913Y1106592D01*
X1707734Y1104654D01*
X1708076Y1090888D01*
Y1089454D01*
X1703656Y1066226D01*
X1700048Y1042217D01*
X1686048Y630995D01*
X1672850Y554853D01*
Y550446D01*
X1672312Y547344D01*
X1670987Y545769D01*
X1666127Y543160D01*
X1666126D01*
X1665516Y543343D01*
X1663797Y542420D01*
X1663614Y541811D01*
X1661896Y540889D01*
X1661286Y541072D01*
X1659567Y540149D01*
X1659384Y539540D01*
X1657666Y538618D01*
X1657056Y538802D01*
X1655337Y537879D01*
X1655154Y537270D01*
X1652257Y535715D01*
X1651647Y535898D01*
X1649928Y534975D01*
X1649745Y534366D01*
X1648027Y533444D01*
X1647417Y533627D01*
X1645698Y532704D01*
X1645515Y532095D01*
X1643797Y531173D01*
X1643188Y531357D01*
X1641469Y530433D01*
X1641285Y529824D01*
X1637699Y527899D01*
X1636410D01*
X1635265Y529044D01*
G01X1627965Y532731D02*
X1629110Y533876D01*
X1636903D01*
X1654593Y541070D01*
X1659723Y546271D01*
X1661368Y549072D01*
Y550671D01*
X1662456Y553297D01*
X1665831Y556672D01*
X1666557Y557908D01*
Y557907D01*
X1666558Y557909D01*
X1668699Y567309D01*
X1668700Y567313D01*
X1669132Y569210D01*
X1669133Y569214D01*
X1669765Y571990D01*
X1669766Y571994D01*
X1670198Y573891D01*
X1670199Y573895D01*
X1670831Y576671D01*
X1670832Y576675D01*
X1683361Y631689D01*
X1683385Y631713D01*
Y631796D01*
X1697379Y1042649D01*
X1699940Y1060722D01*
X1704963Y1087828D01*
X1704615Y1104205D01*
X1703537Y1106721D01*
X1702710Y1107543D01*
X1701772D01*
G01X1701672Y1111283D02*
X1703292D01*
X1705930Y1109519D01*
X1707872Y1107175D01*
X1708839Y1104893D01*
X1709186Y1090902D01*
Y1089349D01*
X1704751Y1066040D01*
X1701156Y1042115D01*
X1687155Y630881D01*
X1673960Y554757D01*
Y550350D01*
X1673355Y546859D01*
X1671700Y544891D01*
X1637979Y526789D01*
X1636410D01*
X1635265Y525644D01*
G01Y564910D02*
X1636410Y563765D01*
X1637050D01*
X1639735Y565559D01*
X1639859Y566183D01*
X1641481Y567268D01*
X1642105Y567143D01*
X1644767Y568922D01*
X1648070Y574066D01*
X1647935Y574688D01*
X1648989Y576330D01*
X1649611Y576465D01*
X1650664Y578105D01*
X1650529Y578727D01*
X1651583Y580369D01*
X1652205Y580504D01*
X1653258Y582144D01*
X1653123Y582766D01*
X1654177Y584408D01*
X1654799Y584543D01*
X1655852Y586183D01*
X1655747Y586667D01*
X1656801Y588309D01*
X1657285Y588414D01*
X1658708Y590632D01*
X1660908Y596812D01*
X1666786Y602436D01*
X1672074Y609551D01*
X1677946Y630096D01*
X1678313Y632429D01*
X1692534Y1044210D01*
X1695131Y1066059D01*
X1695315Y1069103D01*
Y1071163D01*
G01X1627965Y571997D02*
X1629110Y570852D01*
X1635699D01*
X1638652Y572088D01*
X1640574Y574037D01*
X1640571Y574532D01*
X1641941Y575921D01*
X1642436Y575924D01*
X1643805Y577312D01*
X1643802Y577807D01*
X1645172Y579196D01*
X1645667Y579199D01*
X1647530Y581088D01*
X1655046Y592667D01*
X1658020Y600930D01*
X1668839Y611958D01*
X1674160Y631909D01*
X1688260Y1031411D01*
Y1056142D01*
X1685960Y1067707D01*
Y1069000D01*
G01X1627965Y568597D02*
X1629110Y569742D01*
X1635922D01*
X1639286Y571149D01*
X1648400Y580389D01*
X1656047Y592170D01*
X1658983Y600325D01*
X1669837Y611389D01*
X1674901Y630378D01*
Y630377D01*
X1675265Y631744D01*
X1689370Y1031391D01*
Y1056252D01*
X1687070Y1067817D01*
Y1069000D01*
G01X1635265Y561510D02*
X1636410Y562655D01*
X1637387D01*
X1645577Y568127D01*
X1659712Y590139D01*
X1661866Y596191D01*
X1667622Y601698D01*
X1673086Y609051D01*
X1679032Y629856D01*
X1679421Y632323D01*
X1693642Y1044125D01*
X1696238Y1065960D01*
X1696423Y1069036D01*
X1696425Y1069038D01*
Y1071163D01*
G01X1635265Y575684D02*
X1636410Y576829D01*
X1638763D01*
X1645349Y583415D01*
X1651820Y593039D01*
X1655462Y601975D01*
X1662096Y610893D01*
X1665866Y613974D01*
X1667181Y616028D01*
X1671568Y633904D01*
X1685402Y1025568D01*
X1685542Y1055838D01*
X1683330Y1067091D01*
Y1069177D01*
G01X1635265Y579084D02*
X1636410Y577939D01*
X1638303D01*
X1639681Y579317D01*
Y579812D01*
X1641061Y581192D01*
X1641556D01*
X1644488Y584124D01*
X1645576Y585742D01*
X1645480Y586227D01*
X1646569Y587847D01*
X1647055Y587942D01*
X1650835Y593564D01*
X1654486Y602525D01*
X1661287Y611666D01*
X1665026Y614722D01*
X1666146Y616472D01*
X1668304Y625265D01*
Y625266D01*
X1670462Y634058D01*
X1684292Y1025590D01*
X1684431Y1055732D01*
X1682220Y1066982D01*
Y1069177D01*
G01X1627965Y582771D02*
X1629110Y583916D01*
X1637804D01*
X1647968Y594080D01*
X1654227Y609097D01*
X1662602Y621695D01*
X1667400Y633171D01*
X1667592Y634046D01*
X1667594Y634056D01*
X1667677Y634434D01*
X1667678Y634439D01*
X1667783Y634918D01*
X1681587Y1025644D01*
X1681725Y1055733D01*
X1679590Y1066595D01*
Y1069000D01*
G01X1627965Y586171D02*
X1629110Y585026D01*
X1637344D01*
X1640065Y587747D01*
Y588242D01*
X1641445Y589622D01*
X1641940D01*
X1643318Y591000D01*
Y591495D01*
X1644698Y592875D01*
X1645193D01*
X1647028Y594710D01*
X1653243Y609623D01*
X1661618Y622222D01*
X1666337Y633507D01*
X1666507Y634283D01*
Y634284D01*
X1666506D01*
X1666508Y634294D01*
X1666592Y634673D01*
X1666593Y634674D01*
X1666677Y635057D01*
X1680477Y1025666D01*
X1680614Y1055627D01*
X1678480Y1066486D01*
Y1069000D01*
G01X1627965Y596944D02*
X1629110Y598089D01*
X1638248D01*
X1642360Y602201D01*
X1645793Y610437D01*
X1655768Y625205D01*
X1655811Y625308D01*
X1655810D01*
X1659849Y635021D01*
X1673849Y1026160D01*
X1674145Y1054606D01*
X1672110Y1065119D01*
Y1069000D01*
G01X1627965Y600344D02*
X1629110Y599199D01*
X1637788D01*
X1641420Y602831D01*
X1644810Y610967D01*
X1648920Y617051D01*
X1648826Y617537D01*
X1649918Y619154D01*
X1650404Y619248D01*
X1651495Y620863D01*
X1651401Y621349D01*
X1652494Y622966D01*
X1652979Y623060D01*
X1654785Y625734D01*
X1658746Y635262D01*
X1672739Y1026186D01*
X1673033Y1054505D01*
X1671000Y1065012D01*
Y1069000D01*
G01X1635265Y593257D02*
X1636410Y592112D01*
X1638279D01*
X1643744Y597481D01*
X1644546Y599389D01*
X1644359Y599848D01*
X1645116Y601646D01*
X1645574Y601833D01*
X1646329Y603630D01*
X1646142Y604088D01*
X1646899Y605887D01*
X1647358Y606074D01*
X1649284Y610655D01*
X1658199Y623900D01*
X1662686Y634691D01*
X1676578Y1026670D01*
X1676824Y1055257D01*
X1674740Y1065980D01*
Y1069177D01*
G01X1635265Y604030D02*
X1636405Y605170D01*
X1638109D01*
X1640071Y607132D01*
X1641006Y609188D01*
X1642058Y624536D01*
X1642060Y624538D01*
Y631444D01*
X1642514Y638049D01*
X1644152Y648313D01*
X1669471Y1017019D01*
X1670319Y1054375D01*
X1668370Y1064792D01*
Y1069176D01*
G01X1635265Y589857D02*
X1636410Y591002D01*
X1638734D01*
X1644681Y596845D01*
X1648202Y605218D01*
X1648204Y605219D01*
X1650266Y610125D01*
X1659182Y623372D01*
X1659225Y623474D01*
X1659224D01*
X1663789Y634450D01*
X1677688Y1026646D01*
X1677935Y1055359D01*
X1675850Y1066087D01*
Y1069177D01*
G01X1635265Y607430D02*
X1636415Y606280D01*
X1637649D01*
X1639144Y607775D01*
X1639912Y609464D01*
X1640045Y611408D01*
X1639627Y611888D01*
X1639760Y613834D01*
X1640240Y614252D01*
X1640373Y616197D01*
X1639955Y616677D01*
X1640088Y618623D01*
X1640569Y619041D01*
X1640947Y624574D01*
X1640950Y624576D01*
Y631483D01*
X1641410Y638175D01*
X1643048Y648439D01*
X1668361Y1017070D01*
X1669206Y1054284D01*
X1667260Y1064689D01*
Y1069176D01*
G01X1663520Y1069000D02*
Y1063798D01*
X1665380Y1054114D01*
X1664714Y1028683D01*
X1637522Y641300D01*
X1635236Y625080D01*
X1634840Y624783D01*
X1634568Y622851D01*
X1634866Y622455D01*
X1634594Y620525D01*
X1634198Y620228D01*
X1633926Y618296D01*
X1634224Y617900D01*
X1633847Y615226D01*
X1631993Y613372D01*
X1629569D01*
X1628786Y613696D01*
X1627965Y614517D01*
G01X1664630Y1069000D02*
Y1063904D01*
X1666493Y1054205D01*
X1665824Y1028630D01*
X1638627Y641183D01*
Y641184D01*
X1634895Y614703D01*
X1632453Y612262D01*
X1629110D01*
X1627965Y611117D01*
G01X1671000Y1259600D02*
Y1269771D01*
X1643143Y1346004D01*
Y1412710D01*
X1635851Y1434553D01*
X1635407Y1434774D01*
X1634790Y1436625D01*
X1635011Y1437068D01*
X1630082Y1451833D01*
X1630081Y1452012D01*
X1630082D01*
X1629911Y1514434D01*
X1634652Y1526227D01*
X1641463Y1532667D01*
X1676118Y1552207D01*
X1680307Y1556783D01*
X1680968Y1559351D01*
Y1596734D01*
X1679659Y1598043D01*
X1678201D01*
X1677519Y1597361D01*
Y1596024D01*
G01Y1601142D02*
Y1599835D01*
X1678201Y1599153D01*
X1680119D01*
X1682078Y1597194D01*
Y1559210D01*
X1681313Y1556238D01*
X1676818Y1551326D01*
X1642127Y1531767D01*
X1635592Y1525587D01*
X1631022Y1514221D01*
X1631192Y1452015D01*
X1644253Y1412891D01*
Y1346201D01*
X1672110Y1269968D01*
Y1259600D01*
G01X1686181Y1591693D02*
Y1593030D01*
X1686863Y1593712D01*
X1688321D01*
X1689630Y1592403D01*
Y1557213D01*
X1689054Y1554637D01*
X1686308Y1552207D01*
X1675383Y1546375D01*
X1674910Y1546519D01*
X1673189Y1545599D01*
X1673045Y1545126D01*
X1671325Y1544208D01*
X1670852Y1544352D01*
X1669131Y1543432D01*
X1668987Y1542959D01*
X1667267Y1542041D01*
X1666794Y1542185D01*
X1665072Y1541266D01*
X1664929Y1540792D01*
X1643625Y1529418D01*
X1637839Y1523712D01*
X1633887Y1513900D01*
X1633886D01*
X1633806Y1513699D01*
X1633971Y1453836D01*
X1634756Y1449881D01*
X1655383Y1412710D01*
Y1345922D01*
X1674729Y1272649D01*
X1674730Y1272645D01*
X1674740Y1272608D01*
Y1259600D01*
G01X1686181Y1596811D02*
Y1595504D01*
X1686863Y1594822D01*
X1688781D01*
X1690740Y1592863D01*
Y1557090D01*
X1690059Y1554044D01*
X1686946Y1551289D01*
X1644290Y1528514D01*
X1638783Y1523083D01*
X1634917Y1513485D01*
X1635081Y1453947D01*
X1635811Y1450268D01*
X1656493Y1412998D01*
Y1346067D01*
X1675839Y1272794D01*
X1675850Y1272783D01*
Y1259600D01*
G01X1694842Y1601142D02*
Y1599835D01*
X1695524Y1599153D01*
X1697442D01*
X1699401Y1597194D01*
Y1559740D01*
X1698042Y1556061D01*
X1690629Y1548946D01*
X1646370Y1525230D01*
X1641886Y1520698D01*
X1638731Y1512854D01*
X1638885Y1456629D01*
X1639971Y1451162D01*
X1640920Y1448999D01*
X1668733Y1410923D01*
Y1346201D01*
X1679590Y1278767D01*
Y1259600D01*
G01X1694842Y1596024D02*
Y1597361D01*
X1695524Y1598043D01*
X1696982D01*
X1698291Y1596734D01*
Y1559939D01*
X1697089Y1556685D01*
X1689970Y1549853D01*
X1645698Y1526130D01*
X1640939Y1521320D01*
X1637620Y1513068D01*
X1637775Y1456518D01*
X1638905Y1450827D01*
X1639952Y1448442D01*
X1646709Y1439191D01*
X1646633Y1438702D01*
X1647784Y1437126D01*
X1648273Y1437050D01*
X1667623Y1410560D01*
Y1346112D01*
X1678480Y1278678D01*
Y1259600D01*
G01X1703503Y1591693D02*
Y1593030D01*
X1704185Y1593712D01*
X1705643D01*
X1706952Y1592403D01*
Y1556196D01*
X1706176Y1554274D01*
X1704767Y1553005D01*
X1683093Y1541458D01*
X1682620Y1541602D01*
X1680898Y1540684D01*
X1680753Y1540210D01*
X1679033Y1539294D01*
X1678560Y1539439D01*
X1676838Y1538521D01*
X1676693Y1538047D01*
X1674973Y1537131D01*
X1674499Y1537275D01*
X1672777Y1536357D01*
X1672633Y1535884D01*
X1647586Y1522539D01*
X1644417Y1519432D01*
X1641409Y1512198D01*
X1641559Y1457295D01*
X1642563Y1452231D01*
X1643786Y1449840D01*
X1679863Y1411040D01*
Y1347281D01*
X1682220Y1305837D01*
Y1259600D01*
G01X1703503Y1596811D02*
Y1595504D01*
X1704185Y1594822D01*
X1706103D01*
X1708062Y1592863D01*
Y1555980D01*
X1707110Y1553620D01*
X1705409Y1552089D01*
X1648250Y1521634D01*
X1645356Y1518797D01*
X1642520Y1511978D01*
X1642669Y1457405D01*
X1643622Y1452599D01*
X1644704Y1450483D01*
X1680973Y1411477D01*
Y1347313D01*
X1683330Y1305869D01*
Y1259600D01*
G01X1651535Y1489331D02*
Y1490668D01*
X1652217Y1491350D01*
X1653675D01*
X1654984Y1490041D01*
Y1454363D01*
X1656752Y1450661D01*
X1662917Y1445676D01*
X1662984Y1445043D01*
X1664502Y1443816D01*
X1665135Y1443883D01*
X1666651Y1442657D01*
X1666718Y1442025D01*
X1668235Y1440797D01*
X1668868Y1440864D01*
X1670384Y1439638D01*
X1670451Y1439006D01*
X1671968Y1437779D01*
X1672600Y1437846D01*
X1682107Y1430159D01*
X1682166Y1429597D01*
X1683684Y1428370D01*
X1684246Y1428429D01*
X1685762Y1427203D01*
X1685821Y1426641D01*
X1687339Y1425414D01*
X1687901Y1425473D01*
X1689417Y1424248D01*
X1689476Y1423685D01*
X1690994Y1422458D01*
X1691556Y1422518D01*
X1704343Y1412180D01*
Y1346881D01*
X1693441Y1274666D01*
Y1256012D01*
G01X1687070Y1259612D02*
Y1260828D01*
X1693213Y1347687D01*
Y1413216D01*
X1647948Y1452644D01*
X1647211Y1453914D01*
X1646467Y1457662D01*
X1646321Y1510786D01*
X1648731Y1516770D01*
X1649258Y1517262D01*
X1709834Y1549497D01*
X1716724Y1558379D01*
Y1597194D01*
X1714765Y1599153D01*
X1712847D01*
X1712165Y1599835D01*
Y1601142D01*
G01X1685960Y1259612D02*
Y1260868D01*
X1692103Y1347727D01*
Y1412710D01*
X1647080Y1451927D01*
X1646158Y1453517D01*
X1645357Y1457551D01*
X1645210Y1511000D01*
X1647793Y1517413D01*
X1648607Y1518173D01*
X1677094Y1533333D01*
Y1533332D01*
X1677238Y1533806D01*
X1678961Y1534723D01*
X1679434Y1534578D01*
X1709102Y1550366D01*
X1715614Y1558760D01*
Y1596734D01*
X1714305Y1598043D01*
X1712847D01*
X1712165Y1597361D01*
Y1596024D01*
G01X1651535Y1494449D02*
Y1493142D01*
X1652217Y1492460D01*
X1654135D01*
X1656094Y1490501D01*
Y1454615D01*
X1657646Y1451367D01*
X1705453Y1412710D01*
Y1346797D01*
X1694551Y1274582D01*
Y1256012D01*
G01X1700712Y1222377D02*
X1702092D01*
X1703097Y1223382D01*
X1703715Y1224874D01*
Y1248032D01*
X1700645Y1255445D01*
Y1270755D01*
X1717693Y1348163D01*
Y1411293D01*
X1716593Y1413457D01*
X1667238Y1449451D01*
X1664755Y1454259D01*
Y1494832D01*
X1662796Y1496791D01*
X1660878D01*
X1660196Y1497473D01*
Y1498780D01*
G01X1700712Y1223487D02*
X1701632D01*
X1702156Y1224011D01*
X1702605Y1225095D01*
Y1247811D01*
X1699535Y1255224D01*
Y1270876D01*
X1716583Y1348284D01*
Y1411027D01*
X1715723Y1412716D01*
X1702842Y1422109D01*
X1702213Y1422011D01*
X1700637Y1423161D01*
X1700538Y1423790D01*
X1698963Y1424938D01*
X1698334Y1424840D01*
X1696757Y1425990D01*
X1696659Y1426619D01*
X1695084Y1427767D01*
X1694455Y1427669D01*
X1692879Y1428819D01*
X1692781Y1429447D01*
X1683400Y1436288D01*
X1682990Y1436224D01*
X1681160Y1437559D01*
X1681096Y1437969D01*
X1679521Y1439117D01*
X1679112Y1439053D01*
X1677281Y1440389D01*
X1677217Y1440797D01*
X1675642Y1441946D01*
X1675013Y1441848D01*
X1673437Y1442998D01*
X1673338Y1443627D01*
X1666371Y1448708D01*
X1663645Y1453989D01*
Y1494372D01*
X1662336Y1495681D01*
X1660878D01*
X1660196Y1494999D01*
Y1493662D01*
G01X1668858Y1489331D02*
Y1490668D01*
X1669540Y1491350D01*
X1670998D01*
X1672307Y1490041D01*
Y1455223D01*
X1673964Y1451223D01*
X1677481Y1447705D01*
X1680951Y1445272D01*
X1681061Y1444646D01*
X1682659Y1443525D01*
X1683286Y1443635D01*
X1684882Y1442516D01*
X1684992Y1441889D01*
X1686590Y1440769D01*
X1687217Y1440879D01*
X1688813Y1439760D01*
X1688923Y1439133D01*
X1690521Y1438013D01*
X1691148Y1438123D01*
X1705475Y1428079D01*
X1705585Y1427452D01*
X1707183Y1426331D01*
X1707809Y1426442D01*
X1709405Y1425323D01*
X1709515Y1424696D01*
X1711113Y1423576D01*
X1711740Y1423686D01*
X1713336Y1422567D01*
X1713446Y1421940D01*
X1715044Y1420820D01*
X1715671Y1420930D01*
X1717267Y1419811D01*
X1717377Y1419184D01*
X1718975Y1418064D01*
X1719602Y1418174D01*
X1727501Y1412636D01*
X1728823Y1410096D01*
Y1346381D01*
X1703430Y1270109D01*
Y1256290D01*
X1706500Y1248878D01*
Y1223881D01*
X1705647Y1221823D01*
X1704175Y1220351D01*
X1702717Y1219747D01*
X1700612D01*
G01X1668858Y1494449D02*
Y1493142D01*
X1669540Y1492460D01*
X1671458D01*
X1673417Y1490501D01*
Y1455444D01*
X1674905Y1451852D01*
X1678198Y1448559D01*
X1728361Y1413390D01*
X1729933Y1410368D01*
Y1346201D01*
X1704540Y1269929D01*
Y1256511D01*
X1707610Y1249099D01*
Y1223660D01*
X1706588Y1221194D01*
X1704804Y1219410D01*
X1702938Y1218637D01*
X1700612D01*
G01X1700824Y1204787D02*
X1707602D01*
X1714713Y1207733D01*
X1749982Y1243002D01*
Y1243638D01*
X1751362Y1245018D01*
X1751998D01*
X1756573Y1249593D01*
Y1268589D01*
X1752636Y1411965D01*
X1747245Y1422553D01*
X1745189Y1424137D01*
X1744558Y1424055D01*
X1743012Y1425246D01*
X1742930Y1425877D01*
X1741386Y1427066D01*
X1740754Y1426984D01*
X1739209Y1428175D01*
X1739127Y1428806D01*
X1737583Y1429995D01*
X1736951Y1429913D01*
X1735406Y1431104D01*
X1735324Y1431735D01*
X1730766Y1435245D01*
X1725624Y1438710D01*
X1724999Y1438588D01*
X1723381Y1439679D01*
X1723260Y1440304D01*
X1721643Y1441393D01*
X1721018Y1441271D01*
X1719400Y1442362D01*
X1719278Y1442987D01*
X1717661Y1444076D01*
X1717037Y1443955D01*
X1715419Y1445045D01*
X1715297Y1445670D01*
X1710711Y1448760D01*
X1709031Y1450440D01*
X1706952Y1455460D01*
Y1490041D01*
X1705643Y1491350D01*
X1704185D01*
X1703503Y1490668D01*
Y1489331D01*
G01X1712165Y1493662D02*
Y1494999D01*
X1712847Y1495681D01*
X1714305D01*
X1715614Y1494372D01*
Y1452496D01*
X1718700Y1449000D01*
X1720335Y1447939D01*
X1720467Y1447316D01*
X1722104Y1446253D01*
X1722726Y1446385D01*
X1724361Y1445324D01*
X1724493Y1444701D01*
X1726130Y1443638D01*
X1726752Y1443771D01*
X1728387Y1442710D01*
X1728519Y1442087D01*
X1730156Y1441024D01*
X1730778Y1441157D01*
X1734100Y1439000D01*
X1739826Y1434467D01*
X1739900Y1433834D01*
X1741429Y1432623D01*
X1742061Y1432697D01*
X1743589Y1431487D01*
X1743663Y1430855D01*
X1745193Y1429643D01*
X1745825Y1429717D01*
X1751227Y1425440D01*
X1756410Y1412930D01*
Y1412315D01*
X1760335Y1269384D01*
Y1247965D01*
X1716762Y1204392D01*
X1708685Y1201046D01*
X1700854D01*
G01X1700824Y1203677D02*
X1707823D01*
X1715342Y1206792D01*
X1757683Y1249133D01*
Y1268605D01*
X1753739Y1412246D01*
X1748121Y1423280D01*
X1731416Y1436147D01*
X1711420Y1449621D01*
X1709972Y1451069D01*
X1708062Y1455681D01*
Y1490501D01*
X1706103Y1492460D01*
X1704185D01*
X1703503Y1493142D01*
Y1494449D01*
G01X1700744Y1216007D02*
X1705288D01*
X1708825Y1219544D01*
X1710509Y1223609D01*
X1727281Y1240381D01*
X1730576Y1241746D01*
X1745190Y1256360D01*
Y1266598D01*
X1741298Y1408296D01*
X1740597Y1409943D01*
X1740596D01*
X1739897Y1411586D01*
X1739280Y1412214D01*
X1736774Y1413759D01*
X1728490Y1419310D01*
X1727866Y1419186D01*
X1726245Y1420273D01*
X1726121Y1420897D01*
X1724502Y1421982D01*
X1723878Y1421859D01*
X1722257Y1422945D01*
X1722133Y1423569D01*
X1706721Y1433896D01*
X1706358Y1433824D01*
X1704424Y1435121D01*
X1704352Y1435484D01*
X1702733Y1436569D01*
X1702109Y1436446D01*
X1700488Y1437533D01*
X1700364Y1438157D01*
X1698745Y1439242D01*
X1698121Y1439118D01*
X1696500Y1440205D01*
X1696376Y1440829D01*
X1694757Y1441914D01*
X1694132Y1441791D01*
X1692511Y1442877D01*
X1692388Y1443502D01*
X1684630Y1448700D01*
X1682153Y1451177D01*
X1680968Y1454038D01*
Y1494372D01*
X1679659Y1495681D01*
X1678201D01*
X1677519Y1494999D01*
Y1493662D01*
G01X1700988Y1212267D02*
X1705108D01*
X1708299Y1213589D01*
X1712390Y1217680D01*
X1714130Y1221880D01*
X1728371Y1236121D01*
X1733168Y1238108D01*
X1742772Y1247712D01*
Y1248348D01*
X1744152Y1249728D01*
X1744788D01*
X1748967Y1253907D01*
Y1267292D01*
X1745049Y1409924D01*
X1742587Y1414688D01*
X1731317Y1423151D01*
X1730687Y1423062D01*
X1729126Y1424234D01*
X1729037Y1424864D01*
X1729036D01*
X1727478Y1426034D01*
X1726848Y1425945D01*
X1725287Y1427116D01*
X1725198Y1427747D01*
X1725197D01*
X1723639Y1428917D01*
X1723009Y1428828D01*
X1721448Y1429999D01*
X1721359Y1430630D01*
X1721358D01*
X1719800Y1431800D01*
X1707678Y1439686D01*
X1707055Y1439554D01*
X1705420Y1440619D01*
X1705288Y1441241D01*
X1705287D01*
X1703653Y1442304D01*
X1703031Y1442172D01*
X1701396Y1443237D01*
X1701264Y1443859D01*
X1701263D01*
X1699629Y1444922D01*
X1699007Y1444790D01*
X1697371Y1445854D01*
X1697240Y1446477D01*
X1697239D01*
X1692803Y1449363D01*
X1691459Y1450707D01*
X1689630Y1455123D01*
Y1490041D01*
X1688321Y1491350D01*
X1686863D01*
X1686181Y1490668D01*
Y1489331D01*
G01X1700524Y1208527D02*
X1706223D01*
X1710532Y1210312D01*
X1715738Y1215518D01*
X1717308Y1219308D01*
X1731026Y1233026D01*
X1735363Y1234823D01*
X1752760Y1252220D01*
Y1267889D01*
X1748835Y1410835D01*
X1745718Y1417099D01*
X1734558Y1426031D01*
X1734136Y1425984D01*
X1732613Y1427203D01*
X1732566Y1427625D01*
X1731044Y1428843D01*
X1730622Y1428796D01*
X1729099Y1430015D01*
X1729052Y1430437D01*
X1727530Y1431655D01*
X1726897Y1431585D01*
X1725374Y1432804D01*
X1725304Y1433437D01*
X1723600Y1434800D01*
X1715359Y1440355D01*
X1714734Y1440234D01*
X1713116Y1441325D01*
X1712994Y1441950D01*
X1711378Y1443039D01*
X1710753Y1442917D01*
X1709135Y1444008D01*
X1709013Y1444633D01*
X1707397Y1445722D01*
X1706773Y1445601D01*
X1705155Y1446692D01*
X1705033Y1447316D01*
X1701111Y1449960D01*
X1699947Y1451124D01*
X1698291Y1455122D01*
Y1494372D01*
X1696982Y1495681D01*
X1695524D01*
X1694842Y1494999D01*
Y1493662D01*
G01X1700988Y1211157D02*
X1705329D01*
X1708928Y1212648D01*
X1713331Y1217051D01*
X1715071Y1221251D01*
X1729000Y1235180D01*
X1733797Y1237167D01*
X1750077Y1253447D01*
Y1267308D01*
X1746152Y1410208D01*
X1743457Y1415423D01*
X1720437Y1432710D01*
X1693506Y1450230D01*
X1692400Y1451336D01*
X1690740Y1455344D01*
Y1490501D01*
X1688781Y1492460D01*
X1686863D01*
X1686181Y1493142D01*
Y1494449D01*
G01X1700744Y1214897D02*
X1705748D01*
X1709766Y1218915D01*
X1711450Y1222980D01*
X1727910Y1239440D01*
X1731205Y1240805D01*
X1746300Y1255900D01*
Y1266614D01*
X1742402Y1408537D01*
X1740837Y1412215D01*
X1739978Y1413089D01*
X1737375Y1414694D01*
X1685338Y1449562D01*
X1683094Y1451806D01*
X1682078Y1454259D01*
Y1494832D01*
X1680119Y1496791D01*
X1678201D01*
X1677519Y1497473D01*
Y1498780D01*
G01X1712165D02*
Y1497473D01*
X1712847Y1496791D01*
X1714765D01*
X1716724Y1494832D01*
Y1452916D01*
X1719432Y1449849D01*
X1734748Y1439903D01*
X1752143Y1426132D01*
X1757520Y1413151D01*
Y1412331D01*
X1761445Y1269400D01*
Y1247505D01*
X1717391Y1203451D01*
X1708906Y1199936D01*
X1700854D01*
G01X1700524Y1207417D02*
X1706444D01*
X1711161Y1209371D01*
X1716679Y1214889D01*
X1718249Y1218679D01*
X1731655Y1232085D01*
X1735992Y1233882D01*
X1753870Y1251760D01*
Y1267905D01*
X1749938Y1411110D01*
X1746603Y1417813D01*
X1724259Y1435696D01*
X1701820Y1450821D01*
X1700888Y1451753D01*
X1699401Y1455343D01*
Y1494832D01*
X1697442Y1496791D01*
X1695524D01*
X1694842Y1497473D01*
Y1498780D01*
G54D27*
X1803917Y823898D03*
G54D18*
X187835Y1457835D03*
Y1473189D03*
Y1488544D03*
Y1503898D03*
Y1519252D03*
Y1560197D03*
Y1575552D03*
Y1590906D03*
Y1606260D03*
Y1621615D03*
X283110Y1586575D03*
X291771Y1590906D03*
X283110Y1601930D03*
X291771Y1606260D03*
X283110Y1617284D03*
X291771Y1621615D03*
X300433Y1586575D03*
X309094Y1590906D03*
X300433Y1601930D03*
X309094Y1606260D03*
X300433Y1617284D03*
X309094Y1621615D03*
X317756Y1586575D03*
X326417Y1590906D03*
X317756Y1601930D03*
X326417Y1606260D03*
X317756Y1617284D03*
X326417Y1621615D03*
X335078Y1586575D03*
X343740Y1590906D03*
X335078Y1601930D03*
X343740Y1606260D03*
X335078Y1617284D03*
X343740Y1621615D03*
X361063Y1560197D03*
X352401Y1571221D03*
X361063Y1575552D03*
X352401Y1586575D03*
X361063Y1590906D03*
X352401Y1601930D03*
X361063Y1606260D03*
X352401Y1617284D03*
X361063Y1621615D03*
X456339Y1453504D03*
Y1571221D03*
Y1586575D03*
Y1601930D03*
Y1617284D03*
X465000Y1575552D03*
X473662Y1586575D03*
X465000Y1590906D03*
X473662Y1601930D03*
X465000Y1606260D03*
X473662Y1617284D03*
X465000Y1621615D03*
X482323Y1575552D03*
X490985Y1586575D03*
X482323Y1590906D03*
X490985Y1601930D03*
X482323Y1606260D03*
X490985Y1617284D03*
X482323Y1621615D03*
X499646Y1575552D03*
X508307Y1586575D03*
X499646Y1590906D03*
X508307Y1601930D03*
X499646Y1606260D03*
X508307Y1617284D03*
X499646Y1621615D03*
X516969Y1575552D03*
Y1590906D03*
Y1606260D03*
Y1621615D03*
X534292Y1575552D03*
X525630Y1586575D03*
X534292Y1590906D03*
X525630Y1601930D03*
X534292Y1606260D03*
X525630Y1617284D03*
X534292Y1621615D03*
X638228Y1606260D03*
X629567Y1617284D03*
X638228Y1621615D03*
X646890Y1617284D03*
X655551Y1606260D03*
X664213Y1617284D03*
X655551Y1621615D03*
X672874Y1606260D03*
X681535Y1617284D03*
X672874Y1621615D03*
X698858Y1601930D03*
X690197Y1606260D03*
X698858Y1617284D03*
X690197Y1621615D03*
X707520Y1457835D03*
Y1473189D03*
Y1488544D03*
Y1503898D03*
Y1519252D03*
Y1560197D03*
Y1575552D03*
Y1590906D03*
Y1606260D03*
Y1621615D03*
X1201141Y1453504D03*
Y1468859D03*
Y1484213D03*
Y1499567D03*
Y1514922D03*
Y1555867D03*
Y1571221D03*
Y1586575D03*
Y1601930D03*
Y1617284D03*
X1209803Y1457835D03*
Y1473189D03*
Y1488544D03*
Y1503898D03*
Y1519252D03*
Y1560197D03*
Y1575552D03*
Y1590906D03*
Y1606260D03*
Y1621615D03*
X1305079Y1586575D03*
X1313740Y1590906D03*
X1305079Y1601930D03*
X1313740Y1606260D03*
X1305079Y1617284D03*
X1313740Y1621615D03*
X1322402Y1586575D03*
X1331063Y1590906D03*
X1322402Y1601930D03*
X1331063Y1606260D03*
X1322402Y1617284D03*
X1331063Y1621615D03*
X1339725Y1586575D03*
X1348386Y1590906D03*
X1339725Y1601930D03*
X1348386Y1606260D03*
X1339725Y1617284D03*
X1348386Y1621615D03*
X1357047Y1586575D03*
X1365709Y1590906D03*
X1357047Y1601930D03*
X1365709Y1606260D03*
X1357047Y1617284D03*
X1365709Y1621615D03*
X1383032Y1457835D03*
Y1473189D03*
Y1488544D03*
Y1503898D03*
Y1519252D03*
Y1560197D03*
Y1575552D03*
X1374370Y1586575D03*
X1383032Y1590906D03*
X1374370Y1601930D03*
X1383032Y1606260D03*
X1374370Y1617284D03*
X1383032Y1621615D03*
X1478307Y1586575D03*
Y1601930D03*
Y1617284D03*
X1486968Y1575552D03*
X1495630Y1586575D03*
X1486968Y1590906D03*
X1495630Y1601930D03*
X1486968Y1606260D03*
X1495630Y1617284D03*
X1486968Y1621615D03*
X1504291Y1575552D03*
X1512953Y1586575D03*
X1504291Y1590906D03*
X1512953Y1601930D03*
X1504291Y1606260D03*
X1512953Y1617284D03*
X1504291Y1621615D03*
X1521614Y1575552D03*
X1530275Y1586575D03*
X1521614Y1590906D03*
X1530275Y1601930D03*
X1521614Y1606260D03*
X1530275Y1617284D03*
X1521614Y1621615D03*
X1538937Y1575552D03*
X1547598Y1586575D03*
X1538937Y1590906D03*
X1547598Y1601930D03*
X1538937Y1606260D03*
X1547598Y1617284D03*
X1538937Y1621615D03*
X1556260Y1575552D03*
Y1590906D03*
Y1606260D03*
Y1621615D03*
X1660196Y1606260D03*
X1651535Y1617284D03*
X1660196Y1621615D03*
X1677519Y1606260D03*
X1668858Y1617284D03*
X1677519Y1621615D03*
X1686181Y1617284D03*
X1694842Y1606260D03*
X1703503Y1617284D03*
X1694842Y1621615D03*
X1712165Y1606260D03*
X1720826Y1617284D03*
X1712165Y1621615D03*
X1729488Y1457835D03*
Y1473189D03*
Y1488544D03*
Y1503898D03*
Y1519252D03*
Y1560197D03*
Y1575552D03*
Y1590906D03*
Y1606260D03*
Y1621615D03*
G54D28*
G01X404324Y1271889D02*
X405546Y1273111D01*
X454650D01*
X459459Y1268302D01*
Y1208916D01*
X456120Y1205577D01*
Y1196599D01*
X457998Y1194721D01*
X460035D01*
X461285Y1193471D01*
G01X404324Y1275889D02*
X405602Y1274611D01*
X455272D01*
X460959Y1268924D01*
Y1208294D01*
X457620Y1204955D01*
Y1197221D01*
X458620Y1196221D01*
X460035D01*
X461285Y1197471D01*
G01X429677Y1106955D02*
X430785Y1108063D01*
Y1111867D01*
X428708Y1113944D01*
Y1121423D01*
X435230Y1127945D01*
Y1129429D01*
X432367Y1132292D01*
Y1147191D01*
X427231Y1152327D01*
Y1162384D01*
G01X463604Y1118396D02*
X462420D01*
X460348Y1116324D01*
X447875D01*
X443235Y1120964D01*
X434044D01*
X431476Y1118396D01*
G01X457559Y1162384D02*
X459359Y1160584D01*
Y1127276D01*
X466226Y1120409D01*
Y1115247D01*
X462913Y1111934D01*
Y1106365D01*
G01X465785Y1197471D02*
X466735Y1196521D01*
X468326D01*
X469150Y1197345D01*
Y1204263D01*
X465346Y1208067D01*
Y1287733D01*
X460476Y1292603D01*
Y1295849D01*
X459290Y1297035D01*
G01X465785Y1193471D02*
X467035Y1194721D01*
X469072D01*
X470650Y1196299D01*
Y1204885D01*
X466846Y1208689D01*
Y1288355D01*
X461976Y1293225D01*
Y1295721D01*
X463290Y1297035D01*
G01X492818Y1162384D02*
Y1115421D01*
X496372Y1111867D01*
Y1106298D01*
G01X497063Y1118396D02*
X501781D01*
X504307Y1120922D01*
X509072D01*
X513002Y1116992D01*
X522784D01*
X524188Y1118396D01*
X529191D01*
G01X523146Y1162384D02*
X524946Y1160584D01*
Y1126691D01*
X531311Y1120326D01*
Y1112364D01*
X528500Y1109553D01*
Y1106365D01*
G01X952395Y1395276D02*
X953651Y1394094D01*
X955065Y1394137D01*
X956756D01*
X958433Y1392460D01*
Y1365495D01*
X955790Y1362852D01*
X933302D01*
X923724Y1372430D01*
Y1383807D01*
X922990Y1384541D01*
X921532D01*
X920255Y1383264D01*
G01X931159Y1379427D02*
X927354Y1383232D01*
Y1398422D01*
X931159Y1402227D01*
G01X920360Y1387039D02*
X921358Y1386041D01*
X923612D01*
X925224Y1384429D01*
Y1373052D01*
X933924Y1364352D01*
X955168D01*
X956933Y1366117D01*
Y1391838D01*
X956134Y1392637D01*
X955111D01*
X953696Y1392594D01*
X952514Y1391339D01*
G01X931159Y1387027D02*
X928854Y1389332D01*
Y1392322D01*
X931159Y1394627D01*
G01X937671Y1492139D02*
X936421Y1490889D01*
X930399D01*
X920371Y1480861D01*
Y1458929D01*
X923978Y1455322D01*
Y1423048D01*
X935147Y1411879D01*
X953900D01*
X957106Y1408673D01*
Y1402670D01*
X956342Y1401906D01*
X948463D01*
X946985Y1403384D01*
Y1405012D01*
X948235Y1406262D01*
G01X944235D02*
X945485Y1405012D01*
Y1402762D01*
X947841Y1400406D01*
X956964D01*
X958606Y1402048D01*
Y1409295D01*
X954522Y1413379D01*
X935769D01*
X925478Y1423670D01*
Y1455944D01*
X921871Y1459551D01*
Y1480239D01*
X931021Y1489389D01*
X936421D01*
X937671Y1488139D01*
G01X931137Y1375878D02*
X932544Y1374471D01*
X940120D01*
X943253Y1377604D01*
Y1398448D01*
X942124Y1399577D01*
X940709D01*
X939559Y1398427D01*
G01X931199Y1371951D02*
X932219Y1372971D01*
X940742D01*
X944753Y1376982D01*
Y1399070D01*
X942746Y1401077D01*
X940709D01*
X939559Y1402227D01*
G01X931159Y1406027D02*
X934979Y1402207D01*
Y1387047D01*
X931159Y1383227D01*
G01Y1390827D02*
X933479Y1393147D01*
Y1396107D01*
X931159Y1398427D01*
G01X1318287Y1295381D02*
X1319592Y1294076D01*
X1364261D01*
X1375133Y1283204D01*
Y1208294D01*
X1371794Y1204955D01*
Y1197221D01*
X1372794Y1196221D01*
X1374209D01*
X1375459Y1197471D01*
G01X1318287Y1291381D02*
X1319482Y1292576D01*
X1363639D01*
X1373633Y1282582D01*
Y1208916D01*
X1370294Y1205577D01*
Y1196599D01*
X1372172Y1194721D01*
X1374209D01*
X1375459Y1193471D01*
G01X1344241Y1106298D02*
X1344959Y1107016D01*
Y1111867D01*
X1343390Y1113436D01*
Y1119230D01*
X1349673Y1125513D01*
Y1128981D01*
X1346901Y1131753D01*
Y1147405D01*
X1341405Y1152901D01*
Y1162384D01*
G01X1345650Y1118396D02*
X1348197Y1120943D01*
X1358021D01*
X1361938Y1117026D01*
X1371140D01*
X1372510Y1118396D01*
X1377778D01*
G01X1371733Y1162384D02*
X1373533Y1160584D01*
Y1126703D01*
X1380273Y1119963D01*
Y1115120D01*
X1377087Y1111934D01*
Y1106365D01*
G01X1385052Y1303139D02*
X1386238Y1301953D01*
Y1298531D01*
X1379520Y1291813D01*
Y1208067D01*
X1383324Y1204263D01*
Y1197345D01*
X1382500Y1196521D01*
X1380909D01*
X1379959Y1197471D01*
G01X1389052Y1303139D02*
X1387738Y1301825D01*
Y1297909D01*
X1381020Y1291191D01*
Y1208689D01*
X1384824Y1204885D01*
Y1196299D01*
X1383246Y1194721D01*
X1381209D01*
X1379959Y1193471D01*
G01X1406992Y1162384D02*
Y1115421D01*
X1410546Y1111867D01*
Y1106298D01*
G01X1443365Y1118396D02*
X1437467D01*
X1435604Y1116533D01*
X1427550D01*
X1423161Y1120922D01*
X1413763D01*
X1411237Y1118396D01*
G01X1442674Y1106365D02*
Y1111934D01*
X1445650Y1114910D01*
Y1121373D01*
X1439120Y1127903D01*
Y1160584D01*
X1437320Y1162384D01*
G54D19*
G01X47621Y1343672D02*
Y1361645D01*
X51950Y1405603D01*
Y1428872D01*
X42270Y1438552D01*
X29860D01*
G01X23603Y1449735D02*
Y1441643D01*
X26694Y1438552D01*
X29860D01*
G01X65938Y1578410D02*
X74794D01*
X77712Y1575492D01*
X85815D01*
X89714Y1571593D01*
Y1546115D01*
X78993Y1535394D01*
X75102Y1524522D01*
X67981Y1498791D01*
X60675Y1462064D01*
X48346Y1449735D01*
X23603D01*
G01X71020Y1224323D02*
Y1217279D01*
X96979Y1191320D01*
Y1178225D01*
X82411Y1163657D01*
Y1102597D01*
X88775Y1096233D01*
X102761D01*
G01X338768Y246874D02*
Y298914D01*
X356600Y316746D01*
Y332285D01*
X391737Y367422D01*
Y377581D01*
G01X429348Y1129092D02*
Y1125804D01*
X425741Y1122197D01*
Y1118206D01*
X424297Y1116762D01*
X411757D01*
X411235Y1116240D01*
X404651D01*
X403961Y1116930D01*
X373112D01*
X365748Y1124294D01*
Y1134325D01*
G01X425062Y883981D02*
Y881487D01*
X410557Y866982D01*
X398879D01*
X396306Y864409D01*
G01X443091Y1034266D02*
X439521D01*
X437721Y1032466D01*
Y1018365D01*
X439521Y1016565D01*
X442328D01*
X453270Y1005623D01*
Y1003763D01*
G01X832423Y964669D02*
X832140Y964386D01*
Y959070D01*
X824168Y951098D01*
Y949538D01*
G01X940909Y633560D02*
X938479Y631130D01*
Y618639D01*
X939752Y617366D01*
Y563000D01*
X944351Y558401D01*
Y534211D01*
G01X969448Y712181D02*
X977047Y719780D01*
Y725879D01*
X974048Y728878D01*
Y740947D01*
X969687Y745308D01*
Y779014D01*
X961536Y787165D01*
Y817812D01*
X954850Y824498D01*
Y826644D01*
X954760Y826734D01*
G01X954700Y837700D02*
Y838600D01*
X957500Y841400D01*
X962500D01*
X979961Y823939D01*
X983860D01*
X985403Y822396D01*
Y813933D01*
X981477Y810007D01*
Y766874D01*
X981286Y766683D01*
Y763169D01*
X997652Y746803D01*
Y667099D01*
X1018709Y646042D01*
Y449942D01*
X1012188Y443421D01*
G01X1014719Y938322D02*
Y926021D01*
X1007259Y918561D01*
Y912448D01*
X1012817Y906890D01*
Y863815D01*
X1010435Y861433D01*
Y854789D01*
X1013918Y851306D01*
G01X1275788Y1124088D02*
X1295089Y1104787D01*
X1324119D01*
X1329470Y1110138D01*
X1337454D01*
X1340004Y1112688D01*
Y1119667D01*
X1347300Y1126963D01*
Y1128332D01*
G01X1335000Y641000D02*
X1330283Y636283D01*
Y608180D01*
X1335000Y603463D01*
Y594500D01*
G01Y685500D02*
X1332116Y682616D01*
Y673230D01*
X1335000Y670346D01*
Y641000D01*
G01X1367444Y1003763D02*
X1372270Y998937D01*
Y992954D01*
X1381813Y983411D01*
X1405024D01*
X1413920Y992307D01*
X1416618D01*
G01X1357265Y1034266D02*
X1358916D01*
X1361289Y1031893D01*
Y1025947D01*
X1362200Y1025036D01*
X1367235D01*
X1370832Y1021439D01*
Y1015493D01*
X1367444Y1012105D01*
Y1003763D01*
G01X1527267Y932647D02*
Y932788D01*
X1522209Y937846D01*
G01X1529128Y952978D02*
X1531883Y950223D01*
Y936654D01*
X1527876Y932647D01*
X1527267D01*
X211473Y1446675D03*
Y1451631D03*
Y1462631D03*
Y1457675D03*
X216465Y1446675D03*
X229745D03*
X224753D03*
X216465Y1451631D03*
Y1462631D03*
Y1457675D03*
X224753Y1462631D03*
X229745Y1457675D03*
X224753D03*
X229745Y1451631D03*
Y1462631D03*
X224753Y1451631D03*
X393094Y1423600D03*
X395894D03*
X439624Y1345691D03*
Y1350683D03*
Y1357603D03*
Y1362595D03*
Y1381801D03*
Y1369889D03*
Y1374881D03*
Y1386793D03*
X435881Y1394934D03*
Y1398800D03*
X456820Y1345691D03*
X451864D03*
Y1350683D03*
X456820D03*
X444580Y1345691D03*
Y1350683D03*
X456820Y1362595D03*
Y1357603D03*
X451864Y1362595D03*
Y1357603D03*
X444580D03*
Y1362595D03*
X456820Y1374881D03*
X451864D03*
X444580Y1369889D03*
X456820Y1369795D03*
X451864D03*
X444580Y1374881D03*
Y1381801D03*
X456820D03*
X451864D03*
X456820Y1399079D03*
X451864Y1393993D03*
Y1399079D03*
X456820Y1393993D03*
Y1386793D03*
X451864D03*
X444580D03*
X456820Y1405999D03*
X451864D03*
Y1410991D03*
X456820D03*
X454125Y1461182D03*
Y1578898D03*
Y1583629D03*
Y1594253D03*
Y1609607D03*
Y1598984D03*
Y1614338D03*
X471448Y1578898D03*
Y1594253D03*
Y1583629D03*
X462786Y1583229D03*
Y1587960D03*
X471448Y1598984D03*
X462786Y1598584D03*
Y1603315D03*
X471448Y1609607D03*
Y1614338D03*
X462786Y1613938D03*
Y1618669D03*
X488771Y1578898D03*
Y1583629D03*
X480109Y1583229D03*
Y1587960D03*
X488771Y1594253D03*
Y1609607D03*
Y1598984D03*
X480109Y1598584D03*
Y1603315D03*
X488771Y1614338D03*
X480109Y1613938D03*
Y1618669D03*
X506093Y1578898D03*
X497432Y1587960D03*
X506093Y1583629D03*
Y1594253D03*
X497432Y1583229D03*
X506093Y1598984D03*
Y1609607D03*
X497432Y1598584D03*
Y1603315D03*
Y1613938D03*
Y1618669D03*
X506093Y1614338D03*
X514755Y1583229D03*
Y1587960D03*
Y1603315D03*
Y1598584D03*
Y1613938D03*
Y1618669D03*
X529501Y702622D03*
X878220Y835844D03*
Y851592D03*
X881370Y835844D03*
X893968Y845293D03*
X884519Y854742D03*
Y851592D03*
X884585Y886354D03*
X900267Y838992D03*
X919163Y848442D03*
X925462Y845293D03*
X919163Y851592D03*
X916014D03*
X928612Y864189D03*
Y879937D03*
X916014D03*
X922313D03*
X919163D03*
X925462D03*
X919163Y876787D03*
X925462Y867338D03*
X922313Y883086D03*
X919163D03*
X928612Y886236D03*
X1316906Y839320D03*
X1323205Y829871D03*
X1332654Y842470D03*
X1329504Y845619D03*
X1332654D03*
X1326355Y836170D03*
X1335803Y848769D03*
X1323205Y833021D03*
X1326355Y842470D03*
X1332654Y848769D03*
X1320055Y839320D03*
X1329504Y848769D03*
X1323204Y839319D03*
X1329504Y858218D03*
X1323205D03*
X1320055D03*
X1329504Y851918D03*
X1323205D03*
X1332654Y858218D03*
X1326355Y873964D03*
Y877114D03*
X1329504Y870814D03*
X1332654D03*
Y867665D03*
X1320055Y880263D03*
X1335803Y883413D03*
X1329504Y889712D03*
X1320055Y886562D03*
X1332654D03*
X1338953Y845619D03*
Y848769D03*
X1345252Y842470D03*
X1342103Y848769D03*
X1338953Y880263D03*
X1345252Y886562D03*
X1342103Y883413D03*
X1338952Y889713D03*
X1338953Y892862D03*
X1342103Y886562D03*
X1351550Y883413D03*
Y886562D03*
X1367298Y829871D03*
X1359425Y829000D03*
X1354699Y842470D03*
Y845619D03*
X1360999Y836170D03*
X1357849Y842470D03*
X1364148Y833021D03*
X1367298Y836170D03*
Y839320D03*
X1364148Y848769D03*
X1367298Y870814D03*
Y880263D03*
X1357849Y883413D03*
X1360999Y886562D03*
X1364148Y883413D03*
X1367298Y886562D03*
X1370447Y829871D03*
Y839320D03*
X1383046Y845619D03*
X1379896D03*
Y848769D03*
Y839320D03*
Y833021D03*
Y855068D03*
Y861367D03*
X1376747Y858218D03*
X1373597Y861367D03*
X1376747D03*
X1383046Y851918D03*
X1379896D03*
X1383046Y858218D03*
Y861367D03*
X1373598Y873965D03*
X1376747Y867665D03*
Y877114D03*
X1373597Y867665D03*
X1379896D03*
X1383046Y870814D03*
X1373597Y883413D03*
G54D29*
G01X151338Y1069289D02*
X167786D01*
X171083Y1065992D01*
Y1063124D01*
X176924Y1057283D01*
Y1043912D01*
X161409Y1028397D01*
X126086D01*
X124543Y1026854D01*
X108522D01*
X107413Y1025745D01*
X105971D01*
M02*
